G04 ================== begin FILE IDENTIFICATION RECORD ==================*
G04 Layout Name:  E:/<user>/9332_F0TG_MB_C/brd/0417/9332_F0TG_MB_C_V02_0417_0820.brd*
G04 Film Name:    gnd1*
G04 File Format:  Gerber RS274X*
G04 File Origin:  Cadence Allegro 17.2-S081*
G04 Origin Date:  Wed Apr 19 14:50:07 2023*
G04 *
G04 Layer:  DRAWING FORMAT/TITLE_BLOCK_A*
G04 Layer:  PIN/SPECIAL_DRILL*
G04 Layer:  VIA CLASS/GND1*
G04 Layer:  PIN/GND1*
G04 Layer:  MANUFACTURING/PHOTOPLOT_OUTLINE*
G04 Layer:  ETCH/GND1*
G04 Layer:  DRAWING FORMAT/TITLE_BLOCK*
G04 Layer:  DRAWING FORMAT/TITLE_DATA_GND1*
G04 *
G04 Offset:    (0.00 0.00)*
G04 Mirror:    No*
G04 Mode:      Negative*
G04 Rotation:  0*
G04 FullContactRelief:  No*
G04 UndefLineWidth:     6.00*
G04 ================== end FILE IDENTIFICATION RECORD ====================*
%FSLAX25Y25*MOIN*%
%IR0*IPPOS*OFA0.00000B0.00000*MIA0B0*SFA1.00000B1.00000*%
%ADD14C,.03*%
%ADD39C,.06*%
%ADD30C,.024*%
%ADD67C,.052*%
%ADD25C,.061*%
%AMMACRO53*
4,1,36,0.0,.01,
-.001736,.009848,
-.00342,.009397,
-.005,.00866,
-.006428,.00766,
-.00766,.006428,
-.00866,.005,
-.009397,.00342,
-.009848,.001736,
-.01,0.0,
-.009848,-.001736,
-.009397,-.00342,
-.00866,-.005,
-.00766,-.006428,
-.006428,-.00766,
-.005,-.00866,
-.00342,-.009397,
-.001736,-.009848,
0.0,-.01,
.001736,-.009848,
.00342,-.009397,
.005,-.00866,
.006428,-.00766,
.00766,-.006428,
.00866,-.005,
.009397,-.00342,
.009848,-.001736,
.01,0.0,
.009848,.001736,
.009397,.00342,
.00866,.005,
.00766,.006428,
.006428,.00766,
.005,.00866,
.00342,.009397,
.001736,.009848,
0.0,.01,
0.0*
%
%ADD53MACRO53*%
%ADD41C,.071*%
%ADD23C,.026*%
%ADD63C,.064*%
%AMMACRO28*
4,1,36,.0025,0.0,
.002462,.000434,
.002349,.000855,
.002165,.00125,
.001915,.001607,
.001607,.001915,
.00125,.002165,
.000855,.002349,
.000434,.002462,
0.0,.0025,
-.000434,.002462,
-.000855,.002349,
-.00125,.002165,
-.001607,.001915,
-.001915,.001607,
-.002165,.00125,
-.002349,.000855,
-.002462,.000434,
-.0025,0.0,
-.002462,-.000434,
-.002349,-.000855,
-.002165,-.00125,
-.001915,-.001607,
-.001607,-.001915,
-.00125,-.002165,
-.000855,-.002349,
-.000434,-.002462,
0.0,-.0025,
.000434,-.002462,
.000855,-.002349,
.00125,-.002165,
.001607,-.001915,
.001915,-.001607,
.002165,-.00125,
.002349,-.000855,
.002462,-.000434,
.0025,0.0,
135.*
%
%ADD28MACRO28*%
%ADD24C,.028*%
%AMMACRO19*
4,1,36,.0025,0.0,
.002462,.000434,
.002349,.000855,
.002165,.00125,
.001915,.001607,
.001607,.001915,
.00125,.002165,
.000855,.002349,
.000434,.002462,
0.0,.0025,
-.000434,.002462,
-.000855,.002349,
-.00125,.002165,
-.001607,.001915,
-.001915,.001607,
-.002165,.00125,
-.002349,.000855,
-.002462,.000434,
-.0025,0.0,
-.002462,-.000434,
-.002349,-.000855,
-.002165,-.00125,
-.001915,-.001607,
-.001607,-.001915,
-.00125,-.002165,
-.000855,-.002349,
-.000434,-.002462,
0.0,-.0025,
.000434,-.002462,
.000855,-.002349,
.00125,-.002165,
.001607,-.001915,
.001915,-.001607,
.002165,-.00125,
.002349,-.000855,
.002462,-.000434,
.0025,0.0,
180.*
%
%ADD19MACRO19*%
%AMMACRO17*
4,1,36,.0025,0.0,
.002462,.000434,
.002349,.000855,
.002165,.00125,
.001915,.001607,
.001607,.001915,
.00125,.002165,
.000855,.002349,
.000434,.002462,
0.0,.0025,
-.000434,.002462,
-.000855,.002349,
-.00125,.002165,
-.001607,.001915,
-.001915,.001607,
-.002165,.00125,
-.002349,.000855,
-.002462,.000434,
-.0025,0.0,
-.002462,-.000434,
-.002349,-.000855,
-.002165,-.00125,
-.001915,-.001607,
-.001607,-.001915,
-.00125,-.002165,
-.000855,-.002349,
-.000434,-.002462,
0.0,-.0025,
.000434,-.002462,
.000855,-.002349,
.00125,-.002165,
.001607,-.001915,
.001915,-.001607,
.002165,-.00125,
.002349,-.000855,
.002462,-.000434,
.0025,0.0,
225.*
%
%ADD17MACRO17*%
%AMMACRO10*
4,1,36,.0025,0.0,
.002462,.000434,
.002349,.000855,
.002165,.00125,
.001915,.001607,
.001607,.001915,
.00125,.002165,
.000855,.002349,
.000434,.002462,
0.0,.0025,
-.000434,.002462,
-.000855,.002349,
-.00125,.002165,
-.001607,.001915,
-.001915,.001607,
-.002165,.00125,
-.002349,.000855,
-.002462,.000434,
-.0025,0.0,
-.002462,-.000434,
-.002349,-.000855,
-.002165,-.00125,
-.001915,-.001607,
-.001607,-.001915,
-.00125,-.002165,
-.000855,-.002349,
-.000434,-.002462,
0.0,-.0025,
.000434,-.002462,
.000855,-.002349,
.00125,-.002165,
.001607,-.001915,
.001915,-.001607,
.002165,-.00125,
.002349,-.000855,
.002462,-.000434,
.0025,0.0,
270.*
%
%ADD10MACRO10*%
%AMMACRO81*
4,1,36,.003,0.0,
.002954,.000521,
.002819,.001026,
.002598,.0015,
.002298,.001928,
.001928,.002298,
.0015,.002598,
.001026,.002819,
.000521,.002954,
0.0,.003,
-.000521,.002954,
-.001026,.002819,
-.0015,.002598,
-.001928,.002298,
-.002298,.001928,
-.002598,.0015,
-.002819,.001026,
-.002954,.000521,
-.003,0.0,
-.002954,-.000521,
-.002819,-.001026,
-.002598,-.0015,
-.002298,-.001928,
-.001928,-.002298,
-.0015,-.002598,
-.001026,-.002819,
-.000521,-.002954,
0.0,-.003,
.000521,-.002954,
.001026,-.002819,
.0015,-.002598,
.001928,-.002298,
.002298,-.001928,
.002598,-.0015,
.002819,-.001026,
.002954,-.000521,
.003,0.0,
270.*
%
%ADD81MACRO81*%
%AMMACRO43*
4,1,36,-.0025,0.0,
-.002462,.000434,
-.002349,.000855,
-.002165,.00125,
-.001915,.001607,
-.001607,.001915,
-.00125,.002165,
-.000855,.002349,
-.000434,.002462,
0.0,.0025,
.000434,.002462,
.000855,.002349,
.00125,.002165,
.001607,.001915,
.001915,.001607,
.002165,.00125,
.002349,.000855,
.002462,.000434,
.0025,0.0,
.002462,-.000434,
.002349,-.000855,
.002165,-.00125,
.001915,-.001607,
.001607,-.001915,
.00125,-.002165,
.000855,-.002349,
.000434,-.002462,
0.0,-.0025,
-.000434,-.002462,
-.000855,-.002349,
-.00125,-.002165,
-.001607,-.001915,
-.001915,-.001607,
-.002165,-.00125,
-.002349,-.000855,
-.002462,-.000434,
-.0025,0.0,
180.*
%
%ADD43MACRO43*%
%AMMACRO31*
4,1,36,.003,0.0,
.002954,.000521,
.002819,.001026,
.002598,.0015,
.002298,.001928,
.001928,.002298,
.0015,.002598,
.001026,.002819,
.000521,.002954,
0.0,.003,
-.000521,.002954,
-.001026,.002819,
-.0015,.002598,
-.001928,.002298,
-.002298,.001928,
-.002598,.0015,
-.002819,.001026,
-.002954,.000521,
-.003,0.0,
-.002954,-.000521,
-.002819,-.001026,
-.002598,-.0015,
-.002298,-.001928,
-.001928,-.002298,
-.0015,-.002598,
-.001026,-.002819,
-.000521,-.002954,
0.0,-.003,
.000521,-.002954,
.001026,-.002819,
.0015,-.002598,
.001928,-.002298,
.002298,-.001928,
.002598,-.0015,
.002819,-.001026,
.002954,-.000521,
.003,0.0,
180.*
%
%ADD31MACRO31*%
%ADD22C,.074*%
%ADD20C,.0263*%
%AMMACRO80*
4,1,36,-.003,0.0,
-.002954,.000521,
-.002819,.001026,
-.002598,.0015,
-.002298,.001928,
-.001928,.002298,
-.0015,.002598,
-.001026,.002819,
-.000521,.002954,
0.0,.003,
.000521,.002954,
.001026,.002819,
.0015,.002598,
.001928,.002298,
.002298,.001928,
.002598,.0015,
.002819,.001026,
.002954,.000521,
.003,0.0,
.002954,-.000521,
.002819,-.001026,
.002598,-.0015,
.002298,-.001928,
.001928,-.002298,
.0015,-.002598,
.001026,-.002819,
.000521,-.002954,
0.0,-.003,
-.000521,-.002954,
-.001026,-.002819,
-.0015,-.002598,
-.001928,-.002298,
-.002298,-.001928,
-.002598,-.0015,
-.002819,-.001026,
-.002954,-.000521,
-.003,0.0,
270.*
%
%ADD80MACRO80*%
%ADD79C,.0435*%
%ADD66C,.075*%
%ADD61C,.06015*%
%ADD47C,.066*%
%ADD50C,.076*%
%ADD49C,.095*%
%ADD42C,.0248*%
%ADD73C,.087*%
%ADD33C,.03417*%
%AMMACRO13*
4,1,18,.09673,.06845,
.107147,.050613,
.114308,.031238,
.117996,.010914,
.118098,-.009741,
.114613,-.030101,
.107644,-.049546,
.097406,-.067485,
.09673,-.06845,
.10175,-.07347,
.112962,-.054685,
.120742,-.034239,
.124853,-.012752,
.125171,.009122,
.121685,.030719,
.114502,.051383,
.10384,.070486,
.10175,.07347,
.09673,.06845,
0.0*
4,1,18,.06845,-.09673,
.050613,-.107147,
.031238,-.114308,
.010914,-.117996,
-.009741,-.118098,
-.030101,-.114613,
-.049546,-.107644,
-.067485,-.097406,
-.06845,-.09673,
-.07347,-.10175,
-.054685,-.112962,
-.034239,-.120742,
-.012752,-.124853,
.009122,-.125171,
.030719,-.121685,
.051383,-.114502,
.070486,-.10384,
.07347,-.10175,
.06845,-.09673,
0.0*
4,1,18,-.09673,-.06845,
-.107147,-.050613,
-.114308,-.031238,
-.117996,-.010914,
-.118098,.009741,
-.114613,.030101,
-.107644,.049546,
-.097406,.067485,
-.09673,.06845,
-.10175,.07347,
-.112962,.054685,
-.120742,.034239,
-.124853,.012752,
-.125171,-.009122,
-.121685,-.030719,
-.114502,-.051383,
-.10384,-.070486,
-.10175,-.07347,
-.09673,-.06845,
0.0*
4,1,18,-.06845,.09673,
-.050613,.107147,
-.031238,.114308,
-.010914,.117996,
.009741,.118098,
.030101,.114613,
.049546,.107644,
.067485,.097406,
.06845,.09673,
.07347,.10175,
.054685,.112962,
.034239,.120742,
.012752,.124853,
-.009122,.125171,
-.030719,.121685,
-.051383,.114502,
-.070486,.10384,
-.07347,.10175,
-.06845,.09673,
0.0*
%
%ADD13MACRO13*%
%AMMACRO35*
4,1,16,.0711,.04282,
.077455,.029823,
.081457,.01592,
.082984,.001533,
.08199,-.0129,
.078504,-.026942,
.072633,-.040164,
.0711,-.04282,
.07619,-.04791,
.083352,-.033952,
.087981,-.018962,
.089937,-.003396,
.089161,.012273,
.085675,.027569,
.079586,.042027,
.07619,.04791,
.0711,.04282,
0.0*
4,1,16,.04282,-.0711,
.029823,-.077455,
.01592,-.081457,
.001533,-.082984,
-.0129,-.08199,
-.026942,-.078504,
-.040164,-.072633,
-.04282,-.0711,
-.04791,-.07619,
-.033952,-.083352,
-.018962,-.087981,
-.003396,-.089937,
.012273,-.089161,
.027569,-.085675,
.042027,-.079586,
.04791,-.07619,
.04282,-.0711,
0.0*
4,1,16,-.0711,-.04282,
-.077455,-.029823,
-.081457,-.01592,
-.082984,-.001533,
-.08199,.0129,
-.078504,.026942,
-.072633,.040164,
-.0711,.04282,
-.07619,.04791,
-.083352,.033952,
-.087981,.018962,
-.089937,.003396,
-.089161,-.012273,
-.085675,-.027569,
-.079586,-.042027,
-.07619,-.04791,
-.0711,-.04282,
0.0*
4,1,16,-.04282,.0711,
-.029823,.077455,
-.01592,.081457,
-.001533,.082984,
.0129,.08199,
.026942,.078504,
.040164,.072633,
.04282,.0711,
.04791,.07619,
.033952,.083352,
.018962,.087981,
.003396,.089937,
-.012273,.089161,
-.027569,.085675,
-.042027,.079586,
-.04791,.07619,
-.04282,.0711,
0.0*
%
%ADD35MACRO35*%
%AMMACRO64*
4,1,16,.02584,.01524,
.028094,.010521,
.029494,.005483,
.029998,.000278,
.029591,-.004935,
.028284,-.009999,
.026118,-.014758,
.02584,-.01524,
.03092,-.02032,
.033979,-.014642,
.036005,-.008519,
.036938,-.002138,
.036748,.004309,
.035441,.010625,
.033058,.016618,
.03092,.02032,
.02584,.01524,
90.*
4,1,16,.01524,-.02584,
.010521,-.028094,
.005483,-.029494,
.000278,-.029998,
-.004935,-.029591,
-.009999,-.028284,
-.014758,-.026118,
-.01524,-.02584,
-.02032,-.03092,
-.014642,-.033979,
-.008519,-.036005,
-.002138,-.036938,
.004309,-.036748,
.010625,-.035441,
.016618,-.033058,
.02032,-.03092,
.01524,-.02584,
90.*
4,1,16,-.02584,-.01524,
-.028094,-.010521,
-.029494,-.005483,
-.029998,-.000278,
-.029591,.004935,
-.028284,.009999,
-.026118,.014758,
-.02584,.01524,
-.03092,.02032,
-.033979,.014642,
-.036005,.008519,
-.036938,.002138,
-.036748,-.004309,
-.035441,-.010625,
-.033058,-.016618,
-.03092,-.02032,
-.02584,-.01524,
90.*
4,1,16,-.01524,.02584,
-.010521,.028094,
-.005483,.029494,
-.000278,.029998,
.004935,.029591,
.009999,.028284,
.014758,.026118,
.01524,.02584,
.02032,.03092,
.014642,.033979,
.008519,.036005,
.002138,.036938,
-.004309,.036748,
-.010625,.035441,
-.016618,.033058,
-.02032,.03092,
-.01524,.02584,
90.*
%
%ADD64MACRO64*%
%AMMACRO46*
4,1,15,.02438,.01377,
.026401,.009327,
.027619,.004601,
.027999,-.000265,
.027527,-.005123,
.02622,-.009825,
.02438,-.01377,
.02948,-.01887,
.032309,-.013464,
.034156,-.007649,
.034965,-.001602,
.034712,.004494,
.033405,.010454,
.031082,.016095,
.02948,.01887,
.02438,.01377,
90.*
4,1,15,.01377,-.02438,
.009327,-.026401,
.004601,-.027619,
-.000265,-.027999,
-.005123,-.027527,
-.009825,-.02622,
-.01377,-.02438,
-.01887,-.02948,
-.013464,-.032309,
-.007649,-.034156,
-.001602,-.034965,
.004494,-.034712,
.010454,-.033405,
.016095,-.031082,
.01887,-.02948,
.01377,-.02438,
90.*
4,1,15,-.02438,-.01377,
-.026401,-.009327,
-.027619,-.004601,
-.027999,.000265,
-.027527,.005123,
-.02622,.009825,
-.02438,.01377,
-.02948,.01887,
-.032309,.013464,
-.034156,.007649,
-.034965,.001602,
-.034712,-.004494,
-.033405,-.010454,
-.031082,-.016095,
-.02948,-.01887,
-.02438,-.01377,
90.*
4,1,15,-.01377,.02438,
-.009327,.026401,
-.004601,.027619,
.000265,.027999,
.005123,.027527,
.009825,.02622,
.01377,.02438,
.01887,.02948,
.013464,.032309,
.007649,.034156,
.001602,.034965,
-.004494,.034712,
-.010454,.033405,
-.016095,.031082,
-.01887,.02948,
-.01377,.02438,
90.*
%
%ADD46MACRO46*%
%AMMACRO16*
4,1,16,.07001,.04172,
.076191,.028929,
.080057,.015259,
.08149,.001126,
.080448,-.013042,
.076961,-.026814,
.071136,-.03977,
.07001,-.04172,
.0751,-.04682,
.082089,-.033068,
.086584,-.018311,
.088449,-.002997,
.087625,.012407,
.08414,.027435,
.078097,.041629,
.0751,.04682,
.07001,.04172,
0.0*
4,1,16,.04172,-.07001,
.028929,-.076191,
.015259,-.080057,
.001126,-.08149,
-.013042,-.080448,
-.026814,-.076961,
-.03977,-.071136,
-.04172,-.07001,
-.04682,-.0751,
-.033068,-.082089,
-.018311,-.086584,
-.002997,-.088449,
.012407,-.087625,
.027435,-.08414,
.041629,-.078097,
.04682,-.0751,
.04172,-.07001,
0.0*
4,1,16,-.07001,-.04172,
-.076191,-.028929,
-.080057,-.015259,
-.08149,-.001126,
-.080448,.013042,
-.076961,.026814,
-.071136,.03977,
-.07001,.04172,
-.0751,.04682,
-.082089,.033068,
-.086584,.018311,
-.088449,.002997,
-.087625,-.012407,
-.08414,-.027435,
-.078097,-.041629,
-.0751,-.04682,
-.07001,-.04172,
0.0*
4,1,16,-.04172,.07001,
-.028929,.076191,
-.015259,.080057,
-.001126,.08149,
.013042,.080448,
.026814,.076961,
.03977,.071136,
.04172,.07001,
.04682,.0751,
.033068,.082089,
.018311,.086584,
.002997,.088449,
-.012407,.087625,
-.027435,.08414,
-.041629,.078097,
-.04682,.0751,
-.04172,.07001,
0.0*
%
%ADD16MACRO16*%
%AMMACRO65*
4,1,15,.02142,.01082,
.022973,.006936,
.023829,.002841,
.02396,-.00134,
.023364,-.00548,
.022057,-.009454,
.02142,-.01082,
.02657,-.01597,
.02894,-.011114,
.03043,-.005919,
.030995,-.000545,
.030619,.004845,
.029313,.010088,
.027115,.015025,
.02657,.01597,
.02142,.01082,
0.0*
4,1,15,.01082,-.02142,
.006936,-.022973,
.002841,-.023829,
-.00134,-.02396,
-.00548,-.023364,
-.009454,-.022057,
-.01082,-.02142,
-.01597,-.02657,
-.011114,-.02894,
-.005919,-.03043,
-.000545,-.030995,
.004845,-.030619,
.010088,-.029313,
.015025,-.027115,
.01597,-.02657,
.01082,-.02142,
0.0*
4,1,15,-.02142,-.01082,
-.022973,-.006936,
-.023829,-.002841,
-.02396,.00134,
-.023364,.00548,
-.022057,.009454,
-.02142,.01082,
-.02657,.01597,
-.02894,.011114,
-.03043,.005919,
-.030995,.000545,
-.030619,-.004845,
-.029313,-.010088,
-.027115,-.015025,
-.02657,-.01597,
-.02142,-.01082,
0.0*
4,1,15,-.01082,.02142,
-.006936,.022973,
-.002841,.023829,
.00134,.02396,
.00548,.023364,
.009454,.022057,
.01082,.02142,
.01597,.02657,
.011114,.02894,
.005919,.03043,
.000545,.030995,
-.004845,.030619,
-.010088,.029313,
-.015025,.027115,
-.01597,.02657,
-.01082,.02142,
0.0*
%
%ADD65MACRO65*%
%AMMACRO51*
4,1,15,.02475,.01414,
.026829,.009627,
.028094,.004822,
.028504,-.000129,
.028049,-.005077,
.026741,-.009871,
.02475,-.01414,
.02984,-.01923,
.032726,-.013756,
.034617,-.007864,
.035457,-.001734,
.03522,.00445,
.033912,.010498,
.031574,.016227,
.02984,.01923,
.02475,.01414,
0.0*
4,1,15,.01414,-.02475,
.009627,-.026829,
.004822,-.028094,
-.000129,-.028504,
-.005077,-.028049,
-.009871,-.026741,
-.01414,-.02475,
-.01923,-.02984,
-.013756,-.032726,
-.007864,-.034617,
-.001734,-.035457,
.00445,-.03522,
.010498,-.033912,
.016227,-.031574,
.01923,-.02984,
.01414,-.02475,
0.0*
4,1,15,-.02475,-.01414,
-.026829,-.009627,
-.028094,-.004822,
-.028504,.000129,
-.028049,.005077,
-.026741,.009871,
-.02475,.01414,
-.02984,.01923,
-.032726,.013756,
-.034617,.007864,
-.035457,.001734,
-.03522,-.00445,
-.033912,-.010498,
-.031574,-.016227,
-.02984,-.01923,
-.02475,-.01414,
0.0*
4,1,15,-.01414,.02475,
-.009627,.026829,
-.004822,.028094,
.000129,.028504,
.005077,.028049,
.009871,.026741,
.01414,.02475,
.01923,.02984,
.013756,.032726,
.007864,.034617,
.001734,.035457,
-.00445,.03522,
-.010498,.033912,
-.016227,.031574,
-.01923,.02984,
-.01414,.02475,
0.0*
%
%ADD51MACRO51*%
%AMMACRO76*
4,1,15,.03682,.01914,
.039584,.012455,
.041146,.005393,
.041457,-.001834,
.040509,-.009005,
.03833,-.015903,
.03682,-.01914,
.04197,-.0243,
.045552,-.016643,
.04775,-.00848,
.048497,-.000059,
.047771,.008363,
.045593,.016531,
.042029,.024197,
.04197,.0243,
.03682,.01914,
0.0*
4,1,15,.01914,-.03682,
.012455,-.039584,
.005393,-.041146,
-.001834,-.041457,
-.009005,-.040509,
-.015903,-.03833,
-.01914,-.03682,
-.0243,-.04197,
-.016643,-.045552,
-.00848,-.04775,
-.000059,-.048497,
.008363,-.047771,
.016531,-.045593,
.024197,-.042029,
.0243,-.04197,
.01914,-.03682,
0.0*
4,1,15,-.03682,-.01914,
-.039584,-.012455,
-.041146,-.005393,
-.041457,.001834,
-.040509,.009005,
-.03833,.015903,
-.03682,.01914,
-.04197,.0243,
-.045552,.016643,
-.04775,.00848,
-.048497,.000059,
-.047771,-.008363,
-.045593,-.016531,
-.042029,-.024197,
-.04197,-.0243,
-.03682,-.01914,
0.0*
4,1,15,-.01914,.03682,
-.012455,.039584,
-.005393,.041146,
.001834,.041457,
.009005,.040509,
.015903,.03833,
.01914,.03682,
.0243,.04197,
.016643,.045552,
.00848,.04775,
.000059,.048497,
-.008363,.047771,
-.016531,.045593,
-.024197,.042029,
-.0243,.04197,
-.01914,.03682,
0.0*
%
%ADD76MACRO76*%
%AMMACRO72*
4,1,36,.0025,0.0,
.002462,.000434,
.002349,.000855,
.002165,.00125,
.001915,.001607,
.001607,.001915,
.00125,.002165,
.000855,.002349,
.000434,.002462,
0.0,.0025,
-.000434,.002462,
-.000855,.002349,
-.00125,.002165,
-.001607,.001915,
-.001915,.001607,
-.002165,.00125,
-.002349,.000855,
-.002462,.000434,
-.0025,0.0,
-.002462,-.000434,
-.002349,-.000855,
-.002165,-.00125,
-.001915,-.001607,
-.001607,-.001915,
-.00125,-.002165,
-.000855,-.002349,
-.000434,-.002462,
0.0,-.0025,
.000434,-.002462,
.000855,-.002349,
.00125,-.002165,
.001607,-.001915,
.001915,-.001607,
.002165,-.00125,
.002349,-.000855,
.002462,-.000434,
.0025,0.0,
134.996*
%
%ADD72MACRO72*%
%AMMACRO74*
4,1,15,-.03682,.01914,
-.039584,.012455,
-.041146,.005393,
-.041457,-.001834,
-.040509,-.009005,
-.03833,-.015903,
-.03682,-.01914,
-.04197,-.0243,
-.045552,-.016643,
-.04775,-.00848,
-.048497,-.000059,
-.047771,.008363,
-.045593,.016531,
-.042029,.024197,
-.04197,.0243,
-.03682,.01914,
0.0*
4,1,15,-.01914,-.03682,
-.012455,-.039584,
-.005393,-.041146,
.001834,-.041457,
.009005,-.040509,
.015903,-.03833,
.01914,-.03682,
.0243,-.04197,
.016643,-.045552,
.00848,-.04775,
.000059,-.048497,
-.008363,-.047771,
-.016531,-.045593,
-.024197,-.042029,
-.0243,-.04197,
-.01914,-.03682,
0.0*
4,1,15,.03682,-.01914,
.039584,-.012455,
.041146,-.005393,
.041457,.001834,
.040509,.009005,
.03833,.015903,
.03682,.01914,
.04197,.0243,
.045552,.016643,
.04775,.00848,
.048497,.000059,
.047771,-.008363,
.045593,-.016531,
.042029,-.024197,
.04197,-.0243,
.03682,-.01914,
0.0*
4,1,15,.01914,.03682,
.012455,.039584,
.005393,.041146,
-.001834,.041457,
-.009005,.040509,
-.015903,.03833,
-.01914,.03682,
-.0243,.04197,
-.016643,.045552,
-.00848,.04775,
-.000059,.048497,
.008363,.047771,
.016531,.045593,
.024197,.042029,
.0243,.04197,
.01914,.03682,
0.0*
%
%ADD74MACRO74*%
%AMMACRO37*
4,1,36,.003,0.0,
.002954,.000521,
.002819,.001026,
.002598,.0015,
.002298,.001928,
.001928,.002298,
.0015,.002598,
.001026,.002819,
.000521,.002954,
0.0,.003,
-.000521,.002954,
-.001026,.002819,
-.0015,.002598,
-.001928,.002298,
-.002298,.001928,
-.002598,.0015,
-.002819,.001026,
-.002954,.000521,
-.003,0.0,
-.002954,-.000521,
-.002819,-.001026,
-.002598,-.0015,
-.002298,-.001928,
-.001928,-.002298,
-.0015,-.002598,
-.001026,-.002819,
-.000521,-.002954,
0.0,-.003,
.000521,-.002954,
.001026,-.002819,
.0015,-.002598,
.001928,-.002298,
.002298,-.001928,
.002598,-.0015,
.002819,-.001026,
.002954,-.000521,
.003,0.0,
179.996*
%
%ADD37MACRO37*%
%ADD59O,.285X.23*%
%ADD71C,.142*%
%AMMACRO60*
4,1,36,0.0,.01,
-.001736,.009848,
-.00342,.009397,
-.005,.00866,
-.006428,.00766,
-.00766,.006428,
-.00866,.005,
-.009397,.00342,
-.009848,.001736,
-.01,0.0,
-.009848,-.001736,
-.009397,-.00342,
-.00866,-.005,
-.00766,-.006428,
-.006428,-.00766,
-.005,-.00866,
-.00342,-.009397,
-.001736,-.009848,
0.0,-.01,
.001736,-.009848,
.00342,-.009397,
.005,-.00866,
.006428,-.00766,
.00766,-.006428,
.00866,-.005,
.009397,-.00342,
.009848,-.001736,
.01,0.0,
.009848,.001736,
.009397,.00342,
.00866,.005,
.00766,.006428,
.006428,.00766,
.005,.00866,
.00342,.009397,
.001736,.009848,
0.0,.01,
180.*
%
%ADD60MACRO60*%
%ADD34O,.219X.156*%
%ADD11C,.125*%
%ADD27C,.424*%
%ADD18C,.155*%
%ADD52C,.291*%
%ADD54C,.247*%
%ADD45C,.256*%
%AMMACRO32*
4,1,36,0.0,.0085,
.001476,.008371,
.002907,.007987,
.00425,.007361,
.005464,.006511,
.006511,.005464,
.007361,.00425,
.007987,.002907,
.008371,.001476,
.0085,0.0,
.008371,-.001476,
.007987,-.002907,
.007361,-.00425,
.006511,-.005464,
.005464,-.006511,
.00425,-.007361,
.002907,-.007987,
.001476,-.008371,
0.0,-.0085,
-.001476,-.008371,
-.002907,-.007987,
-.00425,-.007361,
-.005464,-.006511,
-.006511,-.005464,
-.007361,-.00425,
-.007987,-.002907,
-.008371,-.001476,
-.0085,0.0,
-.008371,.001476,
-.007987,.002907,
-.007361,.00425,
-.006511,.005464,
-.005464,.006511,
-.00425,.007361,
-.002907,.007987,
-.001476,.008371,
0.0,.0085,
180.*
%
%ADD32MACRO32*%
%AMMACRO58*
4,1,20,-.0075,-.05555,
-.0075,-.06273,
-.013677,-.060878,
-.019439,-.057981,
-.024611,-.054127,
-.029034,-.049434,
-.032576,-.044045,
-.035127,-.038122,
-.036612,-.031846,
-.037,-.0265,
-.037,-.0075,
-.03,-.0075,
-.03,-.0265,
-.029544,-.03171,
-.028191,-.036762,
-.02598,-.041502,
-.022981,-.045786,
-.019282,-.049484,
-.014998,-.052484,
-.010258,-.054694,
-.0075,-.05555,
90.*
4,1,20,.0075,-.06273,
.0075,-.05555,
.01243,-.053806,
.016983,-.051232,
.02102,-.047906,
.024418,-.043931,
.027073,-.039425,
.028906,-.034527,
.029861,-.029385,
.03,-.0265,
.03,-.0075,
.037,-.0075,
.037,-.0265,
.036438,-.032925,
.034769,-.039154,
.032043,-.044999,
.028344,-.050282,
.023784,-.054842,
.018501,-.058541,
.012656,-.061266,
.0075,-.06273,
90.*
4,1,20,-.0075,.06273,
-.0075,.05555,
-.01243,.053806,
-.016983,.051232,
-.02102,.047906,
-.024418,.043931,
-.027073,.039425,
-.028906,.034527,
-.029861,.029385,
-.03,.0265,
-.03,.0075,
-.037,.0075,
-.037,.0265,
-.036438,.032925,
-.034769,.039154,
-.032043,.044999,
-.028344,.050282,
-.023784,.054842,
-.018501,.058541,
-.012656,.061266,
-.0075,.06273,
90.*
4,1,20,.0075,.05555,
.0075,.06273,
.013677,.060878,
.019439,.057981,
.024611,.054127,
.029034,.049434,
.032576,.044045,
.035127,.038122,
.036612,.031846,
.037,.0265,
.037,.0075,
.03,.0075,
.03,.0265,
.029544,.03171,
.028191,.036762,
.02598,.041502,
.022981,.045786,
.019282,.049484,
.014998,.052484,
.010258,.054694,
.0075,.05555,
90.*
%
%ADD58MACRO58*%
%AMMACRO15*
4,1,36,.0025,0.0,
.002462,.000434,
.002349,.000855,
.002165,.00125,
.001915,.001607,
.001607,.001915,
.00125,.002165,
.000855,.002349,
.000434,.002462,
0.0,.0025,
-.000434,.002462,
-.000855,.002349,
-.00125,.002165,
-.001607,.001915,
-.001915,.001607,
-.002165,.00125,
-.002349,.000855,
-.002462,.000434,
-.0025,0.0,
-.002462,-.000434,
-.002349,-.000855,
-.002165,-.00125,
-.001915,-.001607,
-.001607,-.001915,
-.00125,-.002165,
-.000855,-.002349,
-.000434,-.002462,
0.0,-.0025,
.000434,-.002462,
.000855,-.002349,
.00125,-.002165,
.001607,-.001915,
.001915,-.001607,
.002165,-.00125,
.002349,-.000855,
.002462,-.000434,
.0025,0.0,
90.*
%
%ADD15MACRO15*%
%AMMACRO55*
4,1,36,0.0,.019,
-.003299,.018711,
-.006498,.017854,
-.0095,.016454,
-.012213,.014555,
-.014555,.012213,
-.016454,.0095,
-.017854,.006498,
-.018711,.003299,
-.019,0.0,
-.018711,-.003299,
-.017854,-.006498,
-.016454,-.0095,
-.014555,-.012213,
-.012213,-.014555,
-.0095,-.016454,
-.006498,-.017854,
-.003299,-.018711,
0.0,-.019,
.003299,-.018711,
.006498,-.017854,
.0095,-.016454,
.012213,-.014555,
.014555,-.012213,
.016454,-.0095,
.017854,-.006498,
.018711,-.003299,
.019,0.0,
.018711,.003299,
.017854,.006498,
.016454,.0095,
.014555,.012213,
.012213,.014555,
.0095,.016454,
.006498,.017854,
.003299,.018711,
0.0,.019,
270.*
%
%ADD55MACRO55*%
%AMMACRO38*
4,1,36,.003,0.0,
.002954,.000521,
.002819,.001026,
.002598,.0015,
.002298,.001928,
.001928,.002298,
.0015,.002598,
.001026,.002819,
.000521,.002954,
0.0,.003,
-.000521,.002954,
-.001026,.002819,
-.0015,.002598,
-.001928,.002298,
-.002298,.001928,
-.002598,.0015,
-.002819,.001026,
-.002954,.000521,
-.003,0.0,
-.002954,-.000521,
-.002819,-.001026,
-.002598,-.0015,
-.002298,-.001928,
-.001928,-.002298,
-.0015,-.002598,
-.001026,-.002819,
-.000521,-.002954,
0.0,-.003,
.000521,-.002954,
.001026,-.002819,
.0015,-.002598,
.001928,-.002298,
.002298,-.001928,
.002598,-.0015,
.002819,-.001026,
.002954,-.000521,
.003,0.0,
90.*
%
%ADD38MACRO38*%
%AMMACRO12*
4,1,36,.0025,0.0,
.002462,.000434,
.002349,.000855,
.002165,.00125,
.001915,.001607,
.001607,.001915,
.00125,.002165,
.000855,.002349,
.000434,.002462,
0.0,.0025,
-.000434,.002462,
-.000855,.002349,
-.00125,.002165,
-.001607,.001915,
-.001915,.001607,
-.002165,.00125,
-.002349,.000855,
-.002462,.000434,
-.0025,0.0,
-.002462,-.000434,
-.002349,-.000855,
-.002165,-.00125,
-.001915,-.001607,
-.001607,-.001915,
-.00125,-.002165,
-.000855,-.002349,
-.000434,-.002462,
0.0,-.0025,
.000434,-.002462,
.000855,-.002349,
.00125,-.002165,
.001607,-.001915,
.001915,-.001607,
.002165,-.00125,
.002349,-.000855,
.002462,-.000434,
.0025,0.0,
0.0*
%
%ADD12MACRO12*%
%AMMACRO78*
4,1,36,-.003,0.0,
-.002954,.000521,
-.002819,.001026,
-.002598,.0015,
-.002298,.001928,
-.001928,.002298,
-.0015,.002598,
-.001026,.002819,
-.000521,.002954,
0.0,.003,
.000521,.002954,
.001026,.002819,
.0015,.002598,
.001928,.002298,
.002298,.001928,
.002598,.0015,
.002819,.001026,
.002954,.000521,
.003,0.0,
.002954,-.000521,
.002819,-.001026,
.002598,-.0015,
.002298,-.001928,
.001928,-.002298,
.0015,-.002598,
.001026,-.002819,
.000521,-.002954,
0.0,-.003,
-.000521,-.002954,
-.001026,-.002819,
-.0015,-.002598,
-.001928,-.002298,
-.002298,-.001928,
-.002598,-.0015,
-.002819,-.001026,
-.002954,-.000521,
-.003,0.0,
90.*
%
%ADD78MACRO78*%
%AMMACRO44*
4,1,36,-.0025,0.0,
-.002462,.000434,
-.002349,.000855,
-.002165,.00125,
-.001915,.001607,
-.001607,.001915,
-.00125,.002165,
-.000855,.002349,
-.000434,.002462,
0.0,.0025,
.000434,.002462,
.000855,.002349,
.00125,.002165,
.001607,.001915,
.001915,.001607,
.002165,.00125,
.002349,.000855,
.002462,.000434,
.0025,0.0,
.002462,-.000434,
.002349,-.000855,
.002165,-.00125,
.001915,-.001607,
.001607,-.001915,
.00125,-.002165,
.000855,-.002349,
.000434,-.002462,
0.0,-.0025,
-.000434,-.002462,
-.000855,-.002349,
-.00125,-.002165,
-.001607,-.001915,
-.001915,-.001607,
-.002165,-.00125,
-.002349,-.000855,
-.002462,-.000434,
-.0025,0.0,
0.0*
%
%ADD44MACRO44*%
%ADD36C,.188*%
%AMMACRO29*
4,1,36,.003,0.0,
.002954,.000521,
.002819,.001026,
.002598,.0015,
.002298,.001928,
.001928,.002298,
.0015,.002598,
.001026,.002819,
.000521,.002954,
0.0,.003,
-.000521,.002954,
-.001026,.002819,
-.0015,.002598,
-.001928,.002298,
-.002298,.001928,
-.002598,.0015,
-.002819,.001026,
-.002954,.000521,
-.003,0.0,
-.002954,-.000521,
-.002819,-.001026,
-.002598,-.0015,
-.002298,-.001928,
-.001928,-.002298,
-.0015,-.002598,
-.001026,-.002819,
-.000521,-.002954,
0.0,-.003,
.000521,-.002954,
.001026,-.002819,
.0015,-.002598,
.001928,-.002298,
.002298,-.001928,
.002598,-.0015,
.002819,-.001026,
.002954,-.000521,
.003,0.0,
0.0*
%
%ADD29MACRO29*%
%AMMACRO21*
4,1,16,.02584,.01524,
.028094,.010521,
.029494,.005483,
.029998,.000278,
.029591,-.004935,
.028284,-.009999,
.026118,-.014758,
.02584,-.01524,
.03092,-.02032,
.033979,-.014642,
.036005,-.008519,
.036938,-.002138,
.036748,.004309,
.035441,.010625,
.033058,.016618,
.03092,.02032,
.02584,.01524,
180.*
4,1,16,.01524,-.02584,
.010521,-.028094,
.005483,-.029494,
.000278,-.029998,
-.004935,-.029591,
-.009999,-.028284,
-.014758,-.026118,
-.01524,-.02584,
-.02032,-.03092,
-.014642,-.033979,
-.008519,-.036005,
-.002138,-.036938,
.004309,-.036748,
.010625,-.035441,
.016618,-.033058,
.02032,-.03092,
.01524,-.02584,
180.*
4,1,16,-.02584,-.01524,
-.028094,-.010521,
-.029494,-.005483,
-.029998,-.000278,
-.029591,.004935,
-.028284,.009999,
-.026118,.014758,
-.02584,.01524,
-.03092,.02032,
-.033979,.014642,
-.036005,.008519,
-.036938,.002138,
-.036748,-.004309,
-.035441,-.010625,
-.033058,-.016618,
-.03092,-.02032,
-.02584,-.01524,
180.*
4,1,16,-.01524,.02584,
-.010521,.028094,
-.005483,.029494,
-.000278,.029998,
.004935,.029591,
.009999,.028284,
.014758,.026118,
.01524,.02584,
.02032,.03092,
.014642,.033979,
.008519,.036005,
.002138,.036938,
-.004309,.036748,
-.010625,.035441,
-.016618,.033058,
-.02032,.03092,
-.01524,.02584,
180.*
%
%ADD21MACRO21*%
%AMMACRO62*
4,1,15,.02438,.01377,
.026401,.009327,
.027619,.004601,
.027999,-.000265,
.027527,-.005123,
.02622,-.009825,
.02438,-.01377,
.02948,-.01887,
.032309,-.013464,
.034156,-.007649,
.034965,-.001602,
.034712,.004494,
.033405,.010454,
.031082,.016095,
.02948,.01887,
.02438,.01377,
270.*
4,1,15,.01377,-.02438,
.009327,-.026401,
.004601,-.027619,
-.000265,-.027999,
-.005123,-.027527,
-.009825,-.02622,
-.01377,-.02438,
-.01887,-.02948,
-.013464,-.032309,
-.007649,-.034156,
-.001602,-.034965,
.004494,-.034712,
.010454,-.033405,
.016095,-.031082,
.01887,-.02948,
.01377,-.02438,
270.*
4,1,15,-.02438,-.01377,
-.026401,-.009327,
-.027619,-.004601,
-.027999,.000265,
-.027527,.005123,
-.02622,.009825,
-.02438,.01377,
-.02948,.01887,
-.032309,.013464,
-.034156,.007649,
-.034965,.001602,
-.034712,-.004494,
-.033405,-.010454,
-.031082,-.016095,
-.02948,-.01887,
-.02438,-.01377,
270.*
4,1,15,-.01377,.02438,
-.009327,.026401,
-.004601,.027619,
.000265,.027999,
.005123,.027527,
.009825,.02622,
.01377,.02438,
.01887,.02948,
.013464,.032309,
.007649,.034156,
.001602,.034965,
-.004494,.034712,
-.010454,.033405,
-.016095,.031082,
-.01887,.02948,
-.01377,.02438,
270.*
%
%ADD62MACRO62*%
%AMMACRO40*
4,1,15,.02438,.01377,
.026401,.009327,
.027619,.004601,
.027999,-.000265,
.027527,-.005123,
.02622,-.009825,
.02438,-.01377,
.02948,-.01887,
.032309,-.013464,
.034156,-.007649,
.034965,-.001602,
.034712,.004494,
.033405,.010454,
.031082,.016095,
.02948,.01887,
.02438,.01377,
180.*
4,1,15,.01377,-.02438,
.009327,-.026401,
.004601,-.027619,
-.000265,-.027999,
-.005123,-.027527,
-.009825,-.02622,
-.01377,-.02438,
-.01887,-.02948,
-.013464,-.032309,
-.007649,-.034156,
-.001602,-.034965,
.004494,-.034712,
.010454,-.033405,
.016095,-.031082,
.01887,-.02948,
.01377,-.02438,
180.*
4,1,15,-.02438,-.01377,
-.026401,-.009327,
-.027619,-.004601,
-.027999,.000265,
-.027527,.005123,
-.02622,.009825,
-.02438,.01377,
-.02948,.01887,
-.032309,.013464,
-.034156,.007649,
-.034965,.001602,
-.034712,-.004494,
-.033405,-.010454,
-.031082,-.016095,
-.02948,-.01887,
-.02438,-.01377,
180.*
4,1,15,-.01377,.02438,
-.009327,.026401,
-.004601,.027619,
.000265,.027999,
.005123,.027527,
.009825,.02622,
.01377,.02438,
.01887,.02948,
.013464,.032309,
.007649,.034156,
.001602,.034965,
-.004494,.034712,
-.010454,.033405,
-.016095,.031082,
-.01887,.02948,
-.01377,.02438,
180.*
%
%ADD40MACRO40*%
%AMMACRO26*
4,1,20,-.039,.0245,
-.038408,.031272,
-.036648,.037838,
-.033775,.043999,
-.029876,.049567,
-.02507,.054374,
-.019501,.058273,
-.01334,.061146,
-.0075,.06277,
-.0075,.05561,
-.012788,.053835,
-.017688,.051168,
-.02205,.047691,
-.025742,.04351,
-.028652,.038751,
-.030691,.033558,
-.031798,.028091,
-.032,.0245,
-.032,.0075,
-.039,.0075,
-.039,.0245,
90.*
4,1,20,-.039,-.0075,
-.032,-.0075,
-.032,-.0245,
-.031514,-.030057,
-.03007,-.035445,
-.027713,-.040501,
-.024513,-.04507,
-.020569,-.049015,
-.015999,-.052214,
-.010944,-.054572,
-.0075,-.05561,
-.0075,-.06277,
-.014032,-.060887,
-.020137,-.057898,
-.025631,-.053894,
-.030345,-.048997,
-.034138,-.043356,
-.036894,-.037142,
-.038529,-.030544,
-.039,-.0245,
-.039,-.0075,
90.*
4,1,20,.0075,.06277,
.014032,.060887,
.020137,.057898,
.025631,.053894,
.030345,.048997,
.034138,.043356,
.036894,.037142,
.038529,.030544,
.039,.0245,
.039,.0075,
.032,.0075,
.032,.0245,
.031514,.030057,
.03007,.035445,
.027713,.040501,
.024513,.04507,
.020569,.049015,
.015999,.052214,
.010944,.054572,
.0075,.05561,
.0075,.06277,
90.*
4,1,20,.0075,-.05561,
.012788,-.053835,
.017688,-.051168,
.02205,-.047691,
.025742,-.04351,
.028652,-.038751,
.030691,-.033558,
.031798,-.028091,
.032,-.0245,
.032,-.0075,
.039,-.0075,
.039,-.0245,
.038408,-.031272,
.036648,-.037838,
.033775,-.043999,
.029876,-.049567,
.02507,-.054374,
.019501,-.058273,
.01334,-.061146,
.0075,-.06277,
.0075,-.05561,
90.*
%
%ADD26MACRO26*%
%AMMACRO70*
4,1,15,.02475,.01414,
.026829,.009627,
.028094,.004822,
.028504,-.000129,
.028049,-.005077,
.026741,-.009871,
.02475,-.01414,
.02984,-.01923,
.032726,-.013756,
.034617,-.007864,
.035457,-.001734,
.03522,.00445,
.033912,.010498,
.031574,.016227,
.02984,.01923,
.02475,.01414,
270.*
4,1,15,.01414,-.02475,
.009627,-.026829,
.004822,-.028094,
-.000129,-.028504,
-.005077,-.028049,
-.009871,-.026741,
-.01414,-.02475,
-.01923,-.02984,
-.013756,-.032726,
-.007864,-.034617,
-.001734,-.035457,
.00445,-.03522,
.010498,-.033912,
.016227,-.031574,
.01923,-.02984,
.01414,-.02475,
270.*
4,1,15,-.02475,-.01414,
-.026829,-.009627,
-.028094,-.004822,
-.028504,.000129,
-.028049,.005077,
-.026741,.009871,
-.02475,.01414,
-.02984,.01923,
-.032726,.013756,
-.034617,.007864,
-.035457,.001734,
-.03522,-.00445,
-.033912,-.010498,
-.031574,-.016227,
-.02984,-.01923,
-.02475,-.01414,
270.*
4,1,15,-.01414,.02475,
-.009627,.026829,
-.004822,.028094,
.000129,.028504,
.005077,.028049,
.009871,.026741,
.01414,.02475,
.01923,.02984,
.013756,.032726,
.007864,.034617,
.001734,.035457,
-.00445,.03522,
-.010498,.033912,
-.016227,.031574,
-.01923,.02984,
-.01414,.02475,
270.*
%
%ADD70MACRO70*%
%AMMACRO69*
4,1,15,.02142,.01082,
.022973,.006936,
.023829,.002841,
.02396,-.00134,
.023364,-.00548,
.022057,-.009454,
.02142,-.01082,
.02657,-.01597,
.02894,-.011114,
.03043,-.005919,
.030995,-.000545,
.030619,.004845,
.029313,.010088,
.027115,.015025,
.02657,.01597,
.02142,.01082,
180.*
4,1,15,.01082,-.02142,
.006936,-.022973,
.002841,-.023829,
-.00134,-.02396,
-.00548,-.023364,
-.009454,-.022057,
-.01082,-.02142,
-.01597,-.02657,
-.011114,-.02894,
-.005919,-.03043,
-.000545,-.030995,
.004845,-.030619,
.010088,-.029313,
.015025,-.027115,
.01597,-.02657,
.01082,-.02142,
180.*
4,1,15,-.02142,-.01082,
-.022973,-.006936,
-.023829,-.002841,
-.02396,.00134,
-.023364,.00548,
-.022057,.009454,
-.02142,.01082,
-.02657,.01597,
-.02894,.011114,
-.03043,.005919,
-.030995,.000545,
-.030619,-.004845,
-.029313,-.010088,
-.027115,-.015025,
-.02657,-.01597,
-.02142,-.01082,
180.*
4,1,15,-.01082,.02142,
-.006936,.022973,
-.002841,.023829,
.00134,.02396,
.00548,.023364,
.009454,.022057,
.01082,.02142,
.01597,.02657,
.011114,.02894,
.005919,.03043,
.000545,.030995,
-.004845,.030619,
-.010088,.029313,
-.015025,.027115,
-.01597,.02657,
-.01082,.02142,
180.*
%
%ADD69MACRO69*%
%AMMACRO68*
4,1,15,.02475,.01414,
.026829,.009627,
.028094,.004822,
.028504,-.000129,
.028049,-.005077,
.026741,-.009871,
.02475,-.01414,
.02984,-.01923,
.032726,-.013756,
.034617,-.007864,
.035457,-.001734,
.03522,.00445,
.033912,.010498,
.031574,.016227,
.02984,.01923,
.02475,.01414,
180.*
4,1,15,.01414,-.02475,
.009627,-.026829,
.004822,-.028094,
-.000129,-.028504,
-.005077,-.028049,
-.009871,-.026741,
-.01414,-.02475,
-.01923,-.02984,
-.013756,-.032726,
-.007864,-.034617,
-.001734,-.035457,
.00445,-.03522,
.010498,-.033912,
.016227,-.031574,
.01923,-.02984,
.01414,-.02475,
180.*
4,1,15,-.02475,-.01414,
-.026829,-.009627,
-.028094,-.004822,
-.028504,.000129,
-.028049,.005077,
-.026741,.009871,
-.02475,.01414,
-.02984,.01923,
-.032726,.013756,
-.034617,.007864,
-.035457,.001734,
-.03522,-.00445,
-.033912,-.010498,
-.031574,-.016227,
-.02984,-.01923,
-.02475,-.01414,
180.*
4,1,15,-.01414,.02475,
-.009627,.026829,
-.004822,.028094,
.000129,.028504,
.005077,.028049,
.009871,.026741,
.01414,.02475,
.01923,.02984,
.013756,.032726,
.007864,.034617,
.001734,.035457,
-.00445,.03522,
-.010498,.033912,
-.016227,.031574,
-.01923,.02984,
-.01414,.02475,
180.*
%
%ADD68MACRO68*%
%AMMACRO56*
4,1,18,.07103,.05689,
.07983,.043691,
.086204,.029165,
.089959,.013753,
.09098,-.002077,
.089237,-.017844,
.084783,-.033069,
.077753,-.047289,
.07103,-.05689,
.07601,-.06186,
.085597,-.047721,
.092583,-.032132,
.096757,-.015567,
.09799,.001471,
.096246,.018464,
.091577,.034897,
.084126,.050269,
.07601,.06186,
.07103,.05689,
270.*
4,1,18,.05689,-.07103,
.043691,-.07983,
.029165,-.086204,
.013753,-.089959,
-.002077,-.09098,
-.017844,-.089237,
-.033069,-.084783,
-.047289,-.077753,
-.05689,-.07103,
-.06186,-.07601,
-.047721,-.085597,
-.032132,-.092583,
-.015567,-.096757,
.001471,-.09799,
.018464,-.096246,
.034897,-.091577,
.050269,-.084126,
.06186,-.07601,
.05689,-.07103,
270.*
4,1,18,-.07103,-.05689,
-.07983,-.043691,
-.086204,-.029165,
-.089959,-.013753,
-.09098,.002077,
-.089237,.017844,
-.084783,.033069,
-.077753,.047289,
-.07103,.05689,
-.07601,.06186,
-.085597,.047721,
-.092583,.032132,
-.096757,.015567,
-.09799,-.001471,
-.096246,-.018464,
-.091577,-.034897,
-.084126,-.050269,
-.07601,-.06186,
-.07103,-.05689,
270.*
4,1,18,-.05689,.07103,
-.043691,.07983,
-.029165,.086204,
-.013753,.089959,
.002077,.09098,
.017844,.089237,
.033069,.084783,
.047289,.077753,
.05689,.07103,
.06186,.07601,
.047721,.085597,
.032132,.092583,
.015567,.096757,
-.001471,.09799,
-.018464,.096246,
-.034897,.091577,
-.050269,.084126,
-.06186,.07601,
-.05689,.07103,
270.*
%
%ADD56MACRO56*%
%AMMACRO48*
4,1,16,.02657,.01597,
.02894,.011114,
.03043,.005919,
.030995,.000545,
.030619,-.004845,
.029313,-.010088,
.027115,-.015025,
.02657,-.01597,
.03164,-.02104,
.034813,-.015226,
.036928,-.00895,
.037921,-.002401,
.037762,.00422,
.036455,.010713,
.034041,.016881,
.03164,.02104,
.02657,.01597,
180.*
4,1,16,.01597,-.02657,
.011114,-.02894,
.005919,-.03043,
.000545,-.030995,
-.004845,-.030619,
-.010088,-.029313,
-.015025,-.027115,
-.01597,-.02657,
-.02104,-.03164,
-.015226,-.034813,
-.00895,-.036928,
-.002401,-.037921,
.00422,-.037762,
.010713,-.036455,
.016881,-.034041,
.02104,-.03164,
.01597,-.02657,
180.*
4,1,16,-.02657,-.01597,
-.02894,-.011114,
-.03043,-.005919,
-.030995,-.000545,
-.030619,.004845,
-.029313,.010088,
-.027115,.015025,
-.02657,.01597,
-.03164,.02104,
-.034813,.015226,
-.036928,.00895,
-.037921,.002401,
-.037762,-.00422,
-.036455,-.010713,
-.034041,-.016881,
-.03164,-.02104,
-.02657,-.01597,
180.*
4,1,16,-.01597,.02657,
-.011114,.02894,
-.005919,.03043,
-.000545,.030995,
.004845,.030619,
.010088,.029313,
.015025,.027115,
.01597,.02657,
.02104,.03164,
.015226,.034813,
.00895,.036928,
.002401,.037921,
-.00422,.037762,
-.010713,.036455,
-.016881,.034041,
-.02104,.03164,
-.01597,.02657,
180.*
%
%ADD48MACRO48*%
%AMMACRO57*
4,1,15,.04124,.02356,
.044705,.016041,
.046811,.008034,
.047495,-.000216,
.046736,-.008461,
.044557,-.016448,
.04124,-.02356,
.04635,-.02867,
.050624,-.020186,
.05336,-.011088,
.054475,-.001654,
.053935,.007831,
.051756,.017077,
.048004,.025805,
.04635,.02867,
.04124,.02356,
0.0*
4,1,15,.02356,-.04124,
.016041,-.044705,
.008034,-.046811,
-.000216,-.047495,
-.008461,-.046736,
-.016448,-.044557,
-.02356,-.04124,
-.02867,-.04635,
-.020186,-.050624,
-.011088,-.05336,
-.001654,-.054475,
.007831,-.053935,
.017077,-.051756,
.025805,-.048004,
.02867,-.04635,
.02356,-.04124,
0.0*
4,1,15,-.04124,-.02356,
-.044705,-.016041,
-.046811,-.008034,
-.047495,.000216,
-.046736,.008461,
-.044557,.016448,
-.04124,.02356,
-.04635,.02867,
-.050624,.020186,
-.05336,.011088,
-.054475,.001654,
-.053935,-.007831,
-.051756,-.017077,
-.048004,-.025805,
-.04635,-.02867,
-.04124,-.02356,
0.0*
4,1,15,-.02356,.04124,
-.016041,.044705,
-.008034,.046811,
.000216,.047495,
.008461,.046736,
.016448,.044557,
.02356,.04124,
.02867,.04635,
.020186,.050624,
.011088,.05336,
.001654,.054475,
-.007831,.053935,
-.017077,.051756,
-.025805,.048004,
-.02867,.04635,
-.02356,.04124,
0.0*
%
%ADD57MACRO57*%
%AMMACRO77*
4,1,15,.03682,.01914,
.039584,.012455,
.041146,.005393,
.041457,-.001834,
.040509,-.009005,
.03833,-.015903,
.03682,-.01914,
.04197,-.0243,
.045552,-.016643,
.04775,-.00848,
.048497,-.000059,
.047771,.008363,
.045593,.016531,
.042029,.024197,
.04197,.0243,
.03682,.01914,
180.*
4,1,15,.01914,-.03682,
.012455,-.039584,
.005393,-.041146,
-.001834,-.041457,
-.009005,-.040509,
-.015903,-.03833,
-.01914,-.03682,
-.0243,-.04197,
-.016643,-.045552,
-.00848,-.04775,
-.000059,-.048497,
.008363,-.047771,
.016531,-.045593,
.024197,-.042029,
.0243,-.04197,
.01914,-.03682,
180.*
4,1,15,-.03682,-.01914,
-.039584,-.012455,
-.041146,-.005393,
-.041457,.001834,
-.040509,.009005,
-.03833,.015903,
-.03682,.01914,
-.04197,.0243,
-.045552,.016643,
-.04775,.00848,
-.048497,.000059,
-.047771,-.008363,
-.045593,-.016531,
-.042029,-.024197,
-.04197,-.0243,
-.03682,-.01914,
180.*
4,1,15,-.01914,.03682,
-.012455,.039584,
-.005393,.041146,
.001834,.041457,
.009005,.040509,
.015903,.03833,
.01914,.03682,
.0243,.04197,
.016643,.045552,
.00848,.04775,
.000059,.048497,
-.008363,.047771,
-.016531,.045593,
-.024197,.042029,
-.0243,.04197,
-.01914,.03682,
180.*
%
%ADD77MACRO77*%
%AMMACRO75*
4,1,15,-.03682,.01914,
-.039584,.012455,
-.041146,.005393,
-.041457,-.001834,
-.040509,-.009005,
-.03833,-.015903,
-.03682,-.01914,
-.04197,-.0243,
-.045552,-.016643,
-.04775,-.00848,
-.048497,-.000059,
-.047771,.008363,
-.045593,.016531,
-.042029,.024197,
-.04197,.0243,
-.03682,.01914,
180.*
4,1,15,-.01914,-.03682,
-.012455,-.039584,
-.005393,-.041146,
.001834,-.041457,
.009005,-.040509,
.015903,-.03833,
.01914,-.03682,
.0243,-.04197,
.016643,-.045552,
.00848,-.04775,
.000059,-.048497,
-.008363,-.047771,
-.016531,-.045593,
-.024197,-.042029,
-.0243,-.04197,
-.01914,-.03682,
180.*
4,1,15,.03682,-.01914,
.039584,-.012455,
.041146,-.005393,
.041457,.001834,
.040509,.009005,
.03833,.015903,
.03682,.01914,
.04197,.0243,
.045552,.016643,
.04775,.00848,
.048497,.000059,
.047771,-.008363,
.045593,-.016531,
.042029,-.024197,
.04197,-.0243,
.03682,-.01914,
180.*
4,1,15,.01914,.03682,
.012455,.039584,
.005393,.041146,
-.001834,.041457,
-.009005,.040509,
-.015903,.03833,
-.01914,.03682,
-.0243,.04197,
-.016643,.045552,
-.00848,.04775,
-.000059,.048497,
.008363,.047771,
.016531,.045593,
.024197,.042029,
.0243,.04197,
.01914,.03682,
180.*
%
%ADD75MACRO75*%
%ADD82C,.006*%
%ADD92C,.07005*%
%ADD99C,.07006*%
%ADD108C,.0761*%
%ADD86C,.07306*%
%ADD93C,.07608*%
%ADD96C,.07808*%
%ADD97C,.09708*%
%ADD104C,.311*%
%ADD107O,.03004X.07004*%
%ADD98C,.11006*%
%ADD103O,.03004X.06404*%
%ADD109C,.31502*%
%ADD102O,.03006X.06406*%
%ADD106O,.03004X.06904*%
%ADD90C,.16206*%
%ADD94C,.43406*%
%ADD84O,.03404X.06804*%
%ADD83C,.16506*%
%ADD105O,.03006X.06906*%
%ADD101O,.2363X.2993*%
%ADD95C,.25806*%
%ADD85O,.03406X.06806*%
%ADD89C,.19806*%
%ADD88C,.19807*%
%ADD87C,.19809*%
%ADD91C,.19786*%
%ADD100O,.43374X.77626*%
G75*
%LPD*%
G75*
G36*
G01X-476840Y-884638D02*
X5911000D01*
Y2768362D01*
X-476840D01*
Y-884638D01*
G37*
%LPC*%
G75*
G36*
G01X1007087Y132327D02*
G02X1009020Y130394I0J-1933D01*
G01Y46378D01*
G03X1018898Y36500I9878J0D01*
G01X1510244D01*
G02X1516114Y30630I0J-5870D01*
G01Y-1575D01*
G03X1525992Y-11453I9878J0D01*
G01X1796071D01*
G03X1805949Y-1575I0J9878D01*
G01Y30630D01*
G02X1811819Y36500I5870J0D01*
G01X1849606D01*
G02X1855476Y30630I0J-5870D01*
G01Y-40945D01*
G02X1849606Y-46815I-5870J0D01*
G01X7874D01*
G02X2004Y-40945I0J5870D01*
G01Y30630D01*
G02X7874Y36500I5870J0D01*
G01X35835D01*
G02X41705Y30630I0J-5870D01*
G01Y-1575D01*
G03X51583Y-11453I9878J0D01*
G01X321661D01*
G03X331539Y-1575I0J9878D01*
G01Y30630D01*
G02X337409Y36500I5870J0D01*
G01X480717D01*
G02X486587Y30630I0J-5870D01*
G01Y19212D01*
G03X496465Y9334I9878J0D01*
G01X766543D01*
G03X776421Y19212I0J9878D01*
G01Y30630D01*
G02X782291Y36500I5870J0D01*
G01X879134D01*
G03X889012Y46378I0J9878D01*
G01Y130394D01*
G02X890945Y132327I1933J0D01*
G01X1007087D01*
G37*
G36*
G01X1855476Y54252D02*
G02X1849606Y48382I-5870J0D01*
G01X1803945D01*
G03X1794067Y38504I0J-9878D01*
G01Y2204D01*
G02X1793867Y2004I-200J0D01*
G01X1528196D01*
G02X1527996Y2204I0J200D01*
G01Y38504D01*
G03X1518118Y48382I-9878J0D01*
G01X1026772D01*
G02X1020902Y54252I0J5870D01*
G01Y134331D01*
G03X1011024Y144209I-9878J0D01*
G01X887008D01*
G03X877130Y134331I0J-9878D01*
G01Y54252D01*
G02X871260Y48382I-5870J0D01*
G01X774417D01*
G03X764539Y38504I0J-9878D01*
G01Y22991D01*
G02X764339Y22791I-200J0D01*
G01X498669D01*
G02X498469Y22991I0J200D01*
G01Y38504D01*
G03X488591Y48382I-9878J0D01*
G01X329535D01*
G03X319657Y38504I0J-9878D01*
G01Y2204D01*
G02X319457Y2004I-200J0D01*
G01X53787D01*
G02X53587Y2204I0J200D01*
G01Y38504D01*
G03X43709Y48382I-9878J0D01*
G01X7874D01*
G02X2004Y54252I0J5870D01*
G01Y305795D01*
G02X3723Y309944I5869J-1D01*
G01X6985Y313206D01*
G03X9878Y320190I-6985J6985D01*
G01Y1588078D01*
G02X11597Y1592228I5870J-1D01*
G01X24701Y1605332D01*
G03X27595Y1612317I-6985J6986D01*
G01Y1732244D01*
G02X33465Y1738114I5870J0D01*
G01X765532D01*
G02X765732Y1737914I0J-200D01*
G01Y1736890D01*
G03X769705Y1732917I3973J0D01*
G01X1087854D01*
G03X1091827Y1736890I0J3973D01*
G01Y1737914D01*
G02X1092027Y1738114I200J0D01*
G01X1824016D01*
G02X1829886Y1732244I0J-5870D01*
G01Y1612316D01*
G03X1832779Y1605332I9878J1D01*
G01X1839978Y1598133D01*
G02X1841697Y1593984I-4150J-4150D01*
G01Y326095D01*
G03X1844590Y319111I9878J1D01*
G01X1853757Y309944D01*
G02X1855476Y305795I-4150J-4150D01*
G01Y54252D01*
G37*
G36*
G01X1873228Y1820942D02*
X2093700D01*
G02X2099570Y1815072I0J-5870D01*
G01Y1791450D01*
G02X2093700Y1785580I-5870J0D01*
G01X2031574D01*
G03X2021696Y1775702I0J-9878D01*
G01Y1229954D01*
G03X2031574Y1220076I9878J0D01*
G01X2093700D01*
G02X2099570Y1214206I0J-5870D01*
G01Y-40945D01*
G02X2093700Y-46815I-5870J0D01*
G01X1873228D01*
G02X1867358Y-40945I0J5870D01*
G01Y305795D01*
G03X1862159Y318346I-17750J0D01*
G01X1855299Y325206D01*
G02X1853579Y329357I4150J4151D01*
G01Y1593984D01*
G03X1848380Y1606535I-17750J0D01*
G01X1843487Y1611428D01*
G02X1841768Y1615578I4151J4150D01*
G01Y1732244D01*
G02X1847638Y1738114I5870J0D01*
G01X1857480D01*
G03X1867358Y1747992I0J9878D01*
G01Y1815072D01*
G02X1873228Y1820942I5870J0D01*
G37*
%LPD*%
G75*
G36*
G01X741579Y1609865D02*
G02X742998Y1610166I1421J-3202D01*
G02X744417Y1609865I-2J-3503D01*
G03X744579I81J183D01*
G02X745998Y1610166I1421J-3202D01*
G02X749500Y1606663I-1J-3503D01*
G01Y1606661D01*
G02X749200Y1605244I-3502J1D01*
G03Y1605082I183J-81D01*
G02X749500Y1603663I-3202J-1418D01*
G02X749157Y1602149I-3502J-2D01*
G03Y1601977I180J-86D01*
G02X749500Y1600463I-3159J-1512D01*
G02X749200Y1599044I-3502J-1D01*
G03Y1598882I183J-81D01*
G02X749500Y1597463I-3202J-1418D01*
G02X749200Y1596044I-3502J-1D01*
G03Y1595882I183J-81D01*
G02X749500Y1594463I-3202J-1418D01*
G02X745998Y1590960I-3502J-1D01*
G02X744579Y1591261I2J3503D01*
G03X744417I-81J-183D01*
G02X742998Y1590960I-1421J3202D01*
G02X741579Y1591261I2J3503D01*
G03X741417I-81J-183D01*
G02X740970Y1591098I-1421J3201D01*
G01X740913Y1591082D01*
X740837Y1590996D01*
X740770Y1590580D01*
G03X740855Y1590383I198J-32D01*
G02X742382Y1587491I-1975J-2892D01*
G02X741459Y1585121I-3504J0D01*
G03X741406Y1584986I147J-136D01*
G01Y1584866D01*
G03X741459Y1584731I200J1D01*
G02Y1579991I-2580J-2370D01*
G03X741406Y1579856I147J-136D01*
G01Y1579736D01*
G03X741459Y1579601I200J1D01*
G02X742382Y1577231I-2581J-2370D01*
G01Y1577229D01*
G02X738880Y1573728I-3502J1D01*
G02X736412Y1574746I1J3503D01*
G01X736411Y1574747D01*
G03X736271Y1574804I-140J-143D01*
G01X735989D01*
G03X735849Y1574747I0J-200D01*
G01X735848Y1574746D01*
G02X733380Y1573728I-2469J2485D01*
G02X730867Y1574791I0J3502D01*
G03X730723Y1574852I-144J-139D01*
G01X730437D01*
G03X730293Y1574791I0J-200D01*
G02X727780Y1573728I-2513J2439D01*
G02X724278Y1577231I1J3503D01*
G02X725201Y1579601I3504J0D01*
G03X725254Y1579736I-147J136D01*
G01Y1579856D01*
G03X725201Y1579991I-200J-1D01*
G02Y1584731I2580J2370D01*
G03X725254Y1584866I-147J136D01*
G01Y1584986D01*
G03X725201Y1585121I-200J-1D01*
G02X724278Y1587491I2581J2370D01*
G01Y1587493D01*
G02X727780Y1590994I3502J-1D01*
G02X730293Y1589931I0J-3502D01*
G03X730437Y1589870I144J139D01*
G01X730723D01*
G03X730867Y1589931I0J200D01*
G02X731217Y1590246I2513J-2440D01*
G03X731283Y1590468I-123J157D01*
G01X731161Y1590826D01*
G03X730973Y1590961I-189J-65D01*
G02X727496Y1594463I25J3502D01*
G01Y1594465D01*
G02X727796Y1595882I3502J-1D01*
G03Y1596044I-183J81D01*
G02X727496Y1597463I3202J1418D01*
G02X727796Y1598882I3502J1D01*
G03Y1599044I-183J81D01*
G02X727496Y1600463I3202J1418D01*
G02X727839Y1601977I3502J2D01*
G03Y1602149I-180J86D01*
G02X727496Y1603663I3159J1512D01*
G02X727796Y1605082I3502J1D01*
G03Y1605244I-183J81D01*
G02X727496Y1606663I3202J1418D01*
G02X730998Y1610166I3502J1D01*
G02X732417Y1609865I-2J-3503D01*
G03X732579I81J183D01*
G02X733998Y1610166I1421J-3202D01*
G02X735417Y1609865I-2J-3503D01*
G03X735579I81J183D01*
G02X736998Y1610166I1421J-3202D01*
G02X738417Y1609865I-2J-3503D01*
G03X738579I81J183D01*
G02X739998Y1610166I1421J-3202D01*
G02X741417Y1609865I-2J-3503D01*
G03X741579I81J183D01*
G37*
G36*
G01X916131Y1609735D02*
G02X917550Y1610036I1421J-3202D01*
G02X918969Y1609735I-2J-3503D01*
G03X919131I81J183D01*
G02X920550Y1610036I1421J-3202D01*
G02X924052Y1606533I-1J-3503D01*
G01Y1606531D01*
G02X923752Y1605114I-3502J1D01*
G03Y1604952I183J-81D01*
G02X924052Y1603535I-3202J-1418D01*
G01Y1603533D01*
G02X921161Y1600084I-3503J0D01*
G03X920999Y1599922I35J-197D01*
G02X920752Y1599114I-3449J612D01*
G03Y1598952I183J-81D01*
G02X921052Y1597533I-3202J-1418D01*
G02X920752Y1596114I-3502J-1D01*
G03Y1595952I183J-81D01*
G02X921052Y1594533I-3202J-1418D01*
G02X918832Y1591273I-3503J-1D01*
G01X918777Y1591252D01*
X918709Y1591159D01*
X918681Y1590740D01*
G03X918783Y1590552I200J-13D01*
G02X920580Y1587493I-1705J-3059D01*
G02X919656Y1585123I-3503J1D01*
G03X919603Y1584988I147J-136D01*
G01Y1584868D01*
G03X919656Y1584733I200J1D01*
G02X920580Y1582363I-2579J-2371D01*
G02X919656Y1579993I-3503J1D01*
G03X919603Y1579858I147J-136D01*
G01Y1579738D01*
G03X919656Y1579603I200J1D01*
G02X920580Y1577233I-2579J-2371D01*
G02X917077Y1573730I-3503J0D01*
G02X914609Y1574748I1J3503D01*
G01X914608Y1574749D01*
G03X914468Y1574806I-140J-143D01*
G01X914186D01*
G03X914046Y1574749I0J-200D01*
G01X914045Y1574748D01*
G02X911577Y1573730I-2469J2485D01*
G02X909064Y1574793I0J3502D01*
G03X908920Y1574854I-144J-139D01*
G01X908634D01*
G03X908490Y1574793I0J-200D01*
G02X905977Y1573730I-2513J2439D01*
G02X902474Y1577233I0J3503D01*
G02X903398Y1579603I3503J-1D01*
G03X903451Y1579738I-147J136D01*
G01Y1579858D01*
G03X903398Y1579993I-200J-1D01*
G02X902474Y1582363I2579J2371D01*
G02X903398Y1584733I3503J-1D01*
G03X903451Y1584868I-147J136D01*
G01Y1584988D01*
G03X903398Y1585123I-200J-1D01*
G02X902474Y1587493I2579J2371D01*
G02X904288Y1590561I3503J-1D01*
G03X904391Y1590748I-97J175D01*
G01X904370Y1591109D01*
G03X904244Y1591283I-200J-12D01*
G02X902048Y1594533I1307J3250D01*
G01Y1594535D01*
G02X902348Y1595952I3502J-1D01*
G03Y1596114I-183J81D01*
G02X902048Y1597533I3202J1418D01*
G02X902348Y1598952I3502J1D01*
G03Y1599114I-183J81D01*
G02X902101Y1599922I3202J1420D01*
G03X901939Y1600084I-197J-35D01*
G02X899101Y1602922I611J3449D01*
G03X898939Y1603084I-197J-35D01*
G02X896048Y1606533I612J3449D01*
G01Y1606535D01*
G02X899550Y1610036I3502J-1D01*
G02X900969Y1609735I-2J-3503D01*
G03X901131I81J183D01*
G02X902550Y1610036I1421J-3202D01*
G02X903969Y1609735I-2J-3503D01*
G03X904131I81J183D01*
G02X905550Y1610036I1421J-3202D01*
G02X906969Y1609735I-2J-3503D01*
G03X907131I81J183D01*
G02X908550Y1610036I1421J-3202D01*
G02X909969Y1609735I-2J-3503D01*
G03X910131I81J183D01*
G02X911550Y1610036I1421J-3202D01*
G02X912969Y1609735I-2J-3503D01*
G03X913131I81J183D01*
G02X914550Y1610036I1421J-3202D01*
G02X915969Y1609735I-2J-3503D01*
G03X916131I81J183D01*
G37*
G36*
G01X874131D02*
G02X875550Y1610036I1421J-3202D01*
G02X876969Y1609735I-2J-3503D01*
G03X877131I81J183D01*
G02X878550Y1610036I1421J-3202D01*
G02X882052Y1606533I-1J-3503D01*
G01Y1606531D01*
G02X881752Y1605114I-3502J1D01*
G03Y1604952I183J-81D01*
G02X882052Y1603535I-3202J-1418D01*
G01Y1603533D01*
G02X879161Y1600084I-3503J0D01*
G03X878999Y1599922I35J-197D01*
G02X878752Y1599114I-3449J612D01*
G03Y1598952I183J-81D01*
G02X879052Y1597533I-3202J-1418D01*
G02X878752Y1596114I-3502J-1D01*
G03Y1595952I183J-81D01*
G02X879052Y1594533I-3202J-1418D01*
G02X876832Y1591273I-3503J-1D01*
G01X876777Y1591252D01*
X876709Y1591159D01*
X876681Y1590740D01*
G03X876783Y1590552I200J-13D01*
G02X878580Y1587493I-1705J-3059D01*
G02X877656Y1585123I-3503J1D01*
G03X877603Y1584988I147J-136D01*
G01Y1584868D01*
G03X877656Y1584733I200J1D01*
G02X878580Y1582363I-2579J-2371D01*
G02X877656Y1579993I-3503J1D01*
G03X877603Y1579858I147J-136D01*
G01Y1579738D01*
G03X877656Y1579603I200J1D01*
G02X878580Y1577233I-2579J-2371D01*
G02X875077Y1573730I-3503J0D01*
G02X872609Y1574748I1J3503D01*
G01X872608Y1574749D01*
G03X872468Y1574806I-140J-143D01*
G01X872186D01*
G03X872046Y1574749I0J-200D01*
G01X872045Y1574748D01*
G02X869577Y1573730I-2469J2485D01*
G02X867064Y1574793I0J3502D01*
G03X866920Y1574854I-144J-139D01*
G01X866634D01*
G03X866490Y1574793I0J-200D01*
G02X863977Y1573730I-2513J2439D01*
G02X860474Y1577233I0J3503D01*
G02X861398Y1579603I3503J-1D01*
G03X861451Y1579738I-147J136D01*
G01Y1579858D01*
G03X861398Y1579993I-200J-1D01*
G02X860474Y1582363I2579J2371D01*
G02X861398Y1584733I3503J-1D01*
G03X861451Y1584868I-147J136D01*
G01Y1584988D01*
G03X861398Y1585123I-200J-1D01*
G02X860474Y1587493I2579J2371D01*
G02X862288Y1590561I3503J-1D01*
G03X862391Y1590748I-97J175D01*
G01X862370Y1591109D01*
G03X862244Y1591283I-200J-12D01*
G02X860048Y1594533I1307J3250D01*
G01Y1594535D01*
G02X860348Y1595952I3502J-1D01*
G03Y1596114I-183J81D01*
G02X860048Y1597533I3202J1418D01*
G02X860348Y1598952I3502J1D01*
G03Y1599114I-183J81D01*
G02X860101Y1599922I3202J1420D01*
G03X859939Y1600084I-197J-35D01*
G02X857101Y1602922I611J3449D01*
G03X856939Y1603084I-197J-35D01*
G02X854048Y1606533I612J3449D01*
G01Y1606535D01*
G02X857550Y1610036I3502J-1D01*
G02X858969Y1609735I-2J-3503D01*
G03X859131I81J183D01*
G02X860550Y1610036I1421J-3202D01*
G02X861969Y1609735I-2J-3503D01*
G03X862131I81J183D01*
G02X863550Y1610036I1421J-3202D01*
G02X864969Y1609735I-2J-3503D01*
G03X865131I81J183D01*
G02X866550Y1610036I1421J-3202D01*
G02X867969Y1609735I-2J-3503D01*
G03X868131I81J183D01*
G02X869550Y1610036I1421J-3202D01*
G02X870969Y1609735I-2J-3503D01*
G03X871131I81J183D01*
G02X872550Y1610036I1421J-3202D01*
G02X873969Y1609735I-2J-3503D01*
G03X874131I81J183D01*
G37*
G36*
G01X832131D02*
G02X833550Y1610036I1421J-3202D01*
G02X834969Y1609735I-2J-3503D01*
G03X835131I81J183D01*
G02X836550Y1610036I1421J-3202D01*
G02X840052Y1606533I-1J-3503D01*
G01Y1606531D01*
G02X839752Y1605114I-3502J1D01*
G03Y1604952I183J-81D01*
G02X840052Y1603535I-3202J-1418D01*
G01Y1603533D01*
G02X837161Y1600084I-3503J0D01*
G03X836999Y1599922I35J-197D01*
G02X836752Y1599114I-3449J612D01*
G03Y1598952I183J-81D01*
G02X837052Y1597533I-3202J-1418D01*
G02X836752Y1596114I-3502J-1D01*
G03Y1595952I183J-81D01*
G02X837052Y1594533I-3202J-1418D01*
G02X834832Y1591273I-3503J-1D01*
G01X834777Y1591252D01*
X834709Y1591159D01*
X834681Y1590740D01*
G03X834783Y1590552I200J-13D01*
G02X836580Y1587493I-1705J-3059D01*
G02X835656Y1585123I-3503J1D01*
G03X835603Y1584988I147J-136D01*
G01Y1584868D01*
G03X835656Y1584733I200J1D01*
G02X836580Y1582363I-2579J-2371D01*
G02X835656Y1579993I-3503J1D01*
G03X835603Y1579858I147J-136D01*
G01Y1579738D01*
G03X835656Y1579603I200J1D01*
G02X836580Y1577233I-2579J-2371D01*
G02X833077Y1573730I-3503J0D01*
G02X830609Y1574748I1J3503D01*
G01X830608Y1574749D01*
G03X830468Y1574806I-140J-143D01*
G01X830186D01*
G03X830046Y1574749I0J-200D01*
G01X830045Y1574748D01*
G02X827577Y1573730I-2469J2485D01*
G02X825064Y1574793I0J3502D01*
G03X824920Y1574854I-144J-139D01*
G01X824634D01*
G03X824490Y1574793I0J-200D01*
G02X821977Y1573730I-2513J2439D01*
G02X818474Y1577233I0J3503D01*
G02X819398Y1579603I3503J-1D01*
G03X819451Y1579738I-147J136D01*
G01Y1579858D01*
G03X819398Y1579993I-200J-1D01*
G02X818474Y1582363I2579J2371D01*
G02X819398Y1584733I3503J-1D01*
G03X819451Y1584868I-147J136D01*
G01Y1584988D01*
G03X819398Y1585123I-200J-1D01*
G02X818474Y1587493I2579J2371D01*
G02X820288Y1590561I3503J-1D01*
G03X820391Y1590748I-97J175D01*
G01X820370Y1591109D01*
G03X820244Y1591283I-200J-12D01*
G02X818048Y1594533I1307J3250D01*
G01Y1594535D01*
G02X818348Y1595952I3502J-1D01*
G03Y1596114I-183J81D01*
G02X818048Y1597533I3202J1418D01*
G02X818348Y1598952I3502J1D01*
G03Y1599114I-183J81D01*
G02X818101Y1599922I3202J1420D01*
G03X817939Y1600084I-197J-35D01*
G02X815101Y1602922I611J3449D01*
G03X814939Y1603084I-197J-35D01*
G02X812048Y1606533I612J3449D01*
G01Y1606535D01*
G02X815550Y1610036I3502J-1D01*
G02X816969Y1609735I-2J-3503D01*
G03X817131I81J183D01*
G02X818550Y1610036I1421J-3202D01*
G02X819969Y1609735I-2J-3503D01*
G03X820131I81J183D01*
G02X821550Y1610036I1421J-3202D01*
G02X822969Y1609735I-2J-3503D01*
G03X823131I81J183D01*
G02X824550Y1610036I1421J-3202D01*
G02X825969Y1609735I-2J-3503D01*
G03X826131I81J183D01*
G02X827550Y1610036I1421J-3202D01*
G02X828969Y1609735I-2J-3503D01*
G03X829131I81J183D01*
G02X830550Y1610036I1421J-3202D01*
G02X831969Y1609735I-2J-3503D01*
G03X832131I81J183D01*
G37*
G36*
G01X787131D02*
G02X788550Y1610036I1421J-3202D01*
G02X789969Y1609735I-2J-3503D01*
G03X790131I81J183D01*
G02X791550Y1610036I1421J-3202D01*
G02X795052Y1606533I-1J-3503D01*
G01Y1606531D01*
G02X794752Y1605114I-3502J1D01*
G03Y1604952I183J-81D01*
G02X795052Y1603533I-3202J-1418D01*
G02X794752Y1602114I-3502J-1D01*
G03Y1601952I183J-81D01*
G02X795052Y1600533I-3202J-1418D01*
G02X794752Y1599114I-3502J-1D01*
G03Y1598952I183J-81D01*
G02X795052Y1597533I-3202J-1418D01*
G02X794752Y1596114I-3502J-1D01*
G03Y1595952I183J-81D01*
G02X795052Y1594533I-3202J-1418D01*
G02X792832Y1591273I-3503J-1D01*
G01X792777Y1591252D01*
X792709Y1591159D01*
X792681Y1590740D01*
G03X792783Y1590552I200J-13D01*
G02X794580Y1587493I-1705J-3059D01*
G02X793656Y1585123I-3503J1D01*
G03X793603Y1584988I147J-136D01*
G01Y1584868D01*
G03X793656Y1584733I200J1D01*
G02X794580Y1582363I-2579J-2371D01*
G02X793656Y1579993I-3503J1D01*
G03X793603Y1579858I147J-136D01*
G01Y1579738D01*
G03X793656Y1579603I200J1D01*
G02X794580Y1577233I-2579J-2371D01*
G02X791077Y1573730I-3503J0D01*
G02X788609Y1574748I1J3503D01*
G01X788608Y1574749D01*
G03X788468Y1574806I-140J-143D01*
G01X788186D01*
G03X788046Y1574749I0J-200D01*
G01X788045Y1574748D01*
G02X785577Y1573730I-2469J2485D01*
G02X783064Y1574793I0J3502D01*
G03X782920Y1574854I-144J-139D01*
G01X782634D01*
G03X782490Y1574793I0J-200D01*
G02X779977Y1573730I-2513J2439D01*
G02X776474Y1577233I0J3503D01*
G02X777398Y1579603I3503J-1D01*
G03X777451Y1579738I-147J136D01*
G01Y1579858D01*
G03X777398Y1579993I-200J-1D01*
G02X776474Y1582363I2579J2371D01*
G02X777398Y1584733I3503J-1D01*
G03X777451Y1584868I-147J136D01*
G01Y1584988D01*
G03X777398Y1585123I-200J-1D01*
G02X776474Y1587493I2579J2371D01*
G02X778288Y1590561I3503J-1D01*
G03X778391Y1590748I-97J175D01*
G01X778370Y1591109D01*
G03X778244Y1591283I-200J-12D01*
G02X778131Y1591331I1313J3247D01*
G03X777969I-81J-183D01*
G02X776550Y1591030I-1421J3202D01*
G02X773048Y1594533I1J3503D01*
G01Y1594535D01*
G02X773348Y1595952I3502J-1D01*
G03Y1596114I-183J81D01*
G02X773048Y1597533I3202J1418D01*
G02X773348Y1598952I3502J1D01*
G03Y1599114I-183J81D01*
G02X773048Y1600533I3202J1418D01*
G02X773348Y1601952I3502J1D01*
G03Y1602114I-183J81D01*
G02X773048Y1603533I3202J1418D01*
G02X773348Y1604952I3502J1D01*
G03Y1605114I-183J81D01*
G02X773048Y1606533I3202J1418D01*
G02X776550Y1610036I3502J1D01*
G02X777969Y1609735I-2J-3503D01*
G03X778131I81J183D01*
G02X779550Y1610036I1421J-3202D01*
G02X780969Y1609735I-2J-3503D01*
G03X781131I81J183D01*
G02X782550Y1610036I1421J-3202D01*
G02X783969Y1609735I-2J-3503D01*
G03X784131I81J183D01*
G02X785550Y1610036I1421J-3202D01*
G02X786969Y1609735I-2J-3503D01*
G03X787131I81J183D01*
G37*
G36*
G01X1028439Y1536432D02*
X1028441D01*
G02X1029859Y1536132I0J-3502D01*
G03X1030021I81J183D01*
G02X1031438Y1536432I1418J-3202D01*
G01X1031440D01*
G02X1034942Y1532930I0J-3502D01*
G01Y1532928D01*
G02X1033668Y1530227I-3502J1D01*
G01X1033622Y1530190D01*
X1033586Y1530079D01*
X1033692Y1529672D01*
G03X1033850Y1529525I194J50D01*
G02X1036720Y1526080I-633J-3445D01*
G01Y1526078D01*
G02X1036420Y1524661I-3502J1D01*
G03Y1524499I183J-81D01*
G02X1036720Y1523080I-3202J-1418D01*
G02X1036420Y1521661I-3502J-1D01*
G03Y1521499I183J-81D01*
G02X1036720Y1520082I-3202J-1418D01*
G01Y1520080D01*
G02X1029716I-3502J0D01*
G01Y1520082D01*
G02X1030016Y1521499I3502J-1D01*
G03Y1521661I-183J81D01*
G02X1029716Y1523080I3202J1418D01*
G02X1030016Y1524499I3502J1D01*
G03Y1524661I-183J81D01*
G02X1029716Y1526080I3202J1418D01*
G02X1030990Y1528783I3502J1D01*
G01X1031036Y1528820D01*
X1031072Y1528931D01*
X1030966Y1529338D01*
G03X1030808Y1529485I-194J-50D01*
G02X1030021Y1529728I633J3445D01*
G03X1029859I-81J-183D01*
G02X1028441Y1529428I-1418J3202D01*
G01X1028439D01*
G02X1027021Y1529728I0J3502D01*
G03X1026859I-81J-183D01*
G02X1025441Y1529428I-1418J3202D01*
G01X1025439D01*
G02X1024021Y1529728I0J3502D01*
G03X1023859I-81J-183D01*
G02X1022441Y1529428I-1418J3202D01*
G01X1022439D01*
G02X1021021Y1529728I0J3502D01*
G03X1020859I-81J-183D01*
G02X1019442Y1529428I-1418J3202D01*
G01X1019440D01*
G02Y1536432I0J3502D01*
G01X1019442D01*
G02X1020859Y1536132I-1J-3502D01*
G03X1021021I81J183D01*
G02X1022439Y1536432I1418J-3202D01*
G01X1022441D01*
G02X1023859Y1536132I0J-3502D01*
G03X1024021I81J183D01*
G02X1025439Y1536432I1418J-3202D01*
G01X1025441D01*
G02X1026859Y1536132I0J-3502D01*
G03X1027021I81J183D01*
G02X1028439Y1536432I1418J-3202D01*
G37*
G36*
G01X1729836Y56026D02*
G02X1731332Y54658I0J-1502D01*
G03X1731443Y54496I199J18D01*
G02X1733398Y51354I-1547J-3142D01*
G02X1733316Y50602I-3503J1D01*
G03X1733334Y50465I195J-44D01*
G02X1733744Y48822I-3093J-1644D01*
G02X1733586Y47785I-3503J3D01*
G01X1733567Y47725D01*
X1733604Y47607D01*
X1733950Y47338D01*
G03X1734177Y47325I123J158D01*
G02X1736004Y47840I1828J-2987D01*
G01X1736006D01*
G02X1739508Y44338I0J-3502D01*
G01Y44335D01*
G02X1739303Y43155I-3502J1D01*
G03Y43021I188J-67D01*
G02X1739508Y41841I-3297J-1181D01*
G01Y41838D01*
G02X1732504I-3502J0D01*
G01Y41841D01*
G02X1732709Y43021I3502J-1D01*
G03Y43155I-188J67D01*
G02X1732504Y44335I3297J1181D01*
G01Y44338D01*
G02X1732661Y45375I3503J0D01*
G01X1732680Y45435D01*
X1732643Y45553D01*
X1732297Y45822D01*
G03X1732070Y45835I-123J-158D01*
G02X1730241Y45320I-1828J2987D01*
G02X1728585Y45735I-2J3502D01*
G03X1728397I-94J-176D01*
G02X1726741Y45320I-1654J3087D01*
G02X1725085Y45735I-2J3502D01*
G03X1724897I-94J-176D01*
G02X1723241Y45320I-1654J3087D01*
G02X1719738Y48822I-1J3502D01*
G02X1721117Y51607I3503J0D01*
G03X1721195Y51749I-121J159D01*
G02X1724685Y54956I3490J-295D01*
G02X1725575Y54842I4J-3502D01*
G03X1725722Y54860I51J193D01*
G01X1725828Y54918D01*
G03X1725920Y55026I-96J175D01*
G02X1727336Y56026I1416J-503D01*
G02X1728323Y55656I0J-1501D01*
G01X1728324D01*
Y55655D01*
G03X1728454Y55607I130J152D01*
G01X1728718D01*
G03X1728848Y55655I0J200D01*
G01X1728849Y55656D01*
G02X1729836Y56026I987J-1131D01*
G37*
G36*
G01X1421732Y1712135D02*
X1421691Y1712101D01*
X1421654Y1712004D01*
X1421716Y1711612D01*
G03X1421837Y1711458I198J31D01*
G02X1430690Y1698268I-5399J-13190D01*
G02X1402184I-14253J0D01*
G02X1402186Y1698468I14253J-43D01*
G01X1402185D01*
G02X1411037Y1711458I14252J-201D01*
G01X1411086Y1711478D01*
X1411150Y1711560D01*
X1411219Y1712004D01*
X1411182Y1712102D01*
X1411142Y1712135D01*
G02X1421732I5295J6330D01*
G37*
G36*
G01X446338D02*
X446297Y1712101D01*
X446260Y1712004D01*
X446322Y1711612D01*
G03X446443Y1711458I198J31D01*
G02X455296Y1698268I-5399J-13190D01*
G02X426790I-14253J0D01*
G02X435643Y1711458I14252J0D01*
G01X435692Y1711478D01*
X435756Y1711560D01*
X435826Y1712004D01*
X435789Y1712101D01*
X435748Y1712135D01*
G02X446338I5295J6330D01*
G37*
G36*
G01X408078Y1575148D02*
Y1575462D01*
G03X408001Y1575620I-200J0D01*
G02X407422Y1576805I923J1185D01*
G02X410428I1503J0D01*
G02X409849Y1575620I-1502J0D01*
G03X409772Y1575462I123J-158D01*
G01Y1575148D01*
G03X409849Y1574990I200J0D01*
G02X410428Y1573805I-923J-1185D01*
G02X407422I-1503J0D01*
G02X408001Y1574990I1502J0D01*
G03X408078Y1575148I-123J158D01*
G37*
G36*
G01X1060109Y1536352D02*
X1060111D01*
G02X1061529Y1536052I0J-3502D01*
G03X1061691I81J183D01*
G02X1063108Y1536352I1418J-3202D01*
G01X1063110D01*
G02Y1529348I0J-3502D01*
G01X1063108D01*
G02X1061691Y1529648I1J3502D01*
G03X1061529I-81J-183D01*
G02X1060111Y1529348I-1418J3202D01*
G01X1060109D01*
G02X1058691Y1529648I0J3502D01*
G03X1058529I-81J-183D01*
G02X1058372Y1529583I-1418J3203D01*
G03X1058244Y1529412I71J-187D01*
G01X1058236Y1529302D01*
G03X1058335Y1529114I199J-15D01*
G02X1060086Y1526080I-1753J-3034D01*
G01Y1526078D01*
G02X1059786Y1524661I-3502J1D01*
G03Y1524499I183J-81D01*
G02X1060086Y1523080I-3202J-1418D01*
G02X1059786Y1521661I-3502J-1D01*
G03Y1521499I183J-81D01*
G02X1060086Y1520082I-3202J-1418D01*
G01Y1520080D01*
G02X1053082I-3502J0D01*
G01Y1520082D01*
G02X1053382Y1521499I3502J-1D01*
G03Y1521661I-183J81D01*
G02X1053082Y1523080I3202J1418D01*
G02X1053382Y1524499I3502J1D01*
G03Y1524661I-183J81D01*
G02X1053082Y1526080I3202J1418D01*
G02X1054212Y1528657I3502J1D01*
G01X1054257Y1528698D01*
X1054285Y1528815D01*
X1054138Y1529220D01*
G03X1053959Y1529351I-188J-69D01*
G01X1053958D01*
G02X1052691Y1529648I152J3499D01*
G03X1052529I-81J-183D01*
G02X1051112Y1529348I-1418J3202D01*
G01X1051110D01*
G02Y1536352I0J3502D01*
G01X1051112D01*
G02X1052529Y1536052I-1J-3502D01*
G03X1052691I81J183D01*
G02X1054109Y1536352I1418J-3202D01*
G01X1054111D01*
G02X1055529Y1536052I0J-3502D01*
G03X1055691I81J183D01*
G02X1057109Y1536352I1418J-3202D01*
G01X1057111D01*
G02X1058529Y1536052I0J-3502D01*
G03X1058691I81J183D01*
G02X1060109Y1536352I1418J-3202D01*
G37*
G36*
G01X997279Y1536262D02*
X997281D01*
G02X998699Y1535962I0J-3502D01*
G03X998861I81J183D01*
G02X1000278Y1536262I1418J-3202D01*
G01X1000280D01*
G02Y1529258I0J-3502D01*
G01X1000278D01*
G02X998861Y1529558I1J3502D01*
G03X998699I-81J-183D01*
G02X997281Y1529258I-1418J3202D01*
G01X997279D01*
G02X995861Y1529558I0J3502D01*
G03X995699I-81J-183D01*
G02X994281Y1529258I-1418J3202D01*
G01X994279D01*
G02X992861Y1529558I0J3502D01*
G03X992699I-81J-183D01*
G02X991281Y1529258I-1418J3202D01*
G01X991279D01*
G02X989861Y1529558I0J3502D01*
G03X989699I-81J-183D01*
G02X989042Y1529341I-1422J3201D01*
G01X988987Y1529329D01*
X988907Y1529252D01*
X988786Y1528802D01*
X988817Y1528695D01*
X988858Y1528657D01*
G02X989988Y1526080I-2372J-2576D01*
G02X989688Y1524661I-3502J-1D01*
G03Y1524499I183J-81D01*
G02X989988Y1523080I-3202J-1418D01*
G02X989688Y1521661I-3502J-1D01*
G03Y1521499I183J-81D01*
G02X989988Y1520082I-3202J-1418D01*
G01Y1520080D01*
G02X982984I-3502J0D01*
G01Y1520082D01*
G02X983284Y1521499I3502J-1D01*
G03Y1521661I-183J81D01*
G02X982984Y1523080I3202J1418D01*
G02X983284Y1524499I3502J1D01*
G03Y1524661I-183J81D01*
G02X982984Y1526078I3202J1418D01*
G01Y1526080D01*
G02X985724Y1529499I3503J0D01*
G01X985779Y1529511D01*
X985859Y1529588D01*
X985980Y1530038D01*
X985949Y1530145D01*
X985908Y1530183D01*
G02X984778Y1532759I2372J2576D01*
G01Y1532760D01*
G02X988280Y1536262I3502J0D01*
G01X988282D01*
G02X989699Y1535962I-1J-3502D01*
G03X989861I81J183D01*
G02X991279Y1536262I1418J-3202D01*
G01X991281D01*
G02X992699Y1535962I0J-3502D01*
G03X992861I81J183D01*
G02X994279Y1536262I1418J-3202D01*
G01X994281D01*
G02X995699Y1535962I0J-3502D01*
G03X995861I81J183D01*
G02X997279Y1536262I1418J-3202D01*
G37*
G36*
G01X964349D02*
X964351D01*
G02X965769Y1535962I0J-3502D01*
G03X965931I81J183D01*
G02X967348Y1536262I1418J-3202D01*
G01X967350D01*
G02Y1529258I0J-3502D01*
G01X967348D01*
G02X965931Y1529558I1J3502D01*
G03X965769I-81J-183D01*
G02X965495Y1529450I-1420J3202D01*
G01X965444Y1529432D01*
X965374Y1529351D01*
X965300Y1528955D01*
G03X965369Y1528765I197J-36D01*
G02X966622Y1526080I-2250J-2685D01*
G01Y1526078D01*
G02X966322Y1524661I-3502J1D01*
G03Y1524499I183J-81D01*
G02X966622Y1523080I-3202J-1418D01*
G02X966322Y1521661I-3502J-1D01*
G03Y1521499I183J-81D01*
G02X966622Y1520082I-3202J-1418D01*
G01Y1520080D01*
G02X959618I-3502J0D01*
G01Y1520082D01*
G02X959918Y1521499I3502J-1D01*
G03Y1521661I-183J81D01*
G02X959618Y1523080I3202J1418D01*
G02X959918Y1524499I3502J1D01*
G03Y1524661I-183J81D01*
G02X959618Y1526080I3202J1418D01*
G02X960752Y1528661I3502J1D01*
G01X960793Y1528698D01*
X960824Y1528805D01*
X960704Y1529256D01*
X960626Y1529332D01*
X960571Y1529345D01*
G02X959931Y1529558I781J3414D01*
G03X959769I-81J-183D01*
G02X958351Y1529258I-1418J3202D01*
G01X958349D01*
G02X956931Y1529558I0J3502D01*
G03X956769I-81J-183D01*
G02X955352Y1529258I-1418J3202D01*
G01X955350D01*
G02Y1536262I0J3502D01*
G01X955352D01*
G02X956769Y1535962I-1J-3502D01*
G03X956931I81J183D01*
G02X958349Y1536262I1418J-3202D01*
G01X958351D01*
G02X959769Y1535962I0J-3502D01*
G03X959931I81J183D01*
G02X961349Y1536262I1418J-3202D01*
G01X961351D01*
G02X962769Y1535962I0J-3502D01*
G03X962931I81J183D01*
G02X964349Y1536262I1418J-3202D01*
G37*
G36*
G01X1093299Y1536162D02*
X1093301D01*
G02X1094719Y1535862I0J-3502D01*
G03X1094881I81J183D01*
G02X1096298Y1536162I1418J-3202D01*
G01X1096300D01*
G02Y1529158I0J-3502D01*
G01X1096298D01*
G02X1094881Y1529458I1J3502D01*
G03X1094719I-81J-183D01*
G02X1093301Y1529158I-1418J3202D01*
G01X1093299D01*
G02X1091881Y1529458I0J3502D01*
G03X1091719I-81J-183D01*
G02X1090301Y1529158I-1418J3202D01*
G01X1090299D01*
G02X1088881Y1529458I0J3502D01*
G03X1088719I-81J-183D01*
G02X1087302Y1529158I-1418J3202D01*
G01X1087300D01*
G02Y1536162I0J3502D01*
G01X1087302D01*
G02X1088719Y1535862I-1J-3502D01*
G03X1088881I81J183D01*
G02X1090299Y1536162I1418J-3202D01*
G01X1090301D01*
G02X1091719Y1535862I0J-3502D01*
G03X1091881I81J183D01*
G02X1093299Y1536162I1418J-3202D01*
G37*
G36*
G01X1006350Y1523080D02*
G02X1006650Y1524499I3502J1D01*
G03Y1524661I-183J81D01*
G02X1006350Y1526078I3202J1418D01*
G01Y1526080D01*
G02X1013354I3502J0D01*
G01Y1526078D01*
G02X1013054Y1524661I-3502J1D01*
G03Y1524499I183J-81D01*
G02X1013354Y1523080I-3202J-1418D01*
G02X1013054Y1521661I-3502J-1D01*
G03Y1521499I183J-81D01*
G02X1013354Y1520082I-3202J-1418D01*
G01Y1520080D01*
G02X1006350I-3502J0D01*
G01Y1520082D01*
G02X1006650Y1521499I3502J-1D01*
G03Y1521661I-183J81D01*
G02X1006350Y1523080I3202J1418D01*
G37*
G36*
G01X728916Y1423122D02*
G02X729216Y1424541I3502J1D01*
G03Y1424703I-183J81D01*
G02X728916Y1426120I3202J1418D01*
G01Y1426122D01*
G02X732418Y1429624I3502J0D01*
G01X732420D01*
G02X733837Y1429324I-1J-3502D01*
G03X733999I81J183D01*
G02X735416Y1429624I1418J-3202D01*
G01X735418D01*
G02X738920Y1426122I0J-3502D01*
G01Y1426120D01*
G02X738620Y1424703I-3502J1D01*
G03Y1424541I183J-81D01*
G02X738920Y1423122I-3202J-1418D01*
G02X738620Y1421703I-3502J-1D01*
G03Y1421541I183J-81D01*
G02X738920Y1420124I-3202J-1418D01*
G01Y1420122D01*
G02X735418Y1416620I-3502J0D01*
G01X735416D01*
G02X733999Y1416920I1J3502D01*
G03X733837I-81J-183D01*
G02X732420Y1416620I-1418J3202D01*
G01X732418D01*
G02X728916Y1420122I0J3502D01*
G01Y1420124D01*
G02X729216Y1421541I3502J-1D01*
G03Y1421703I-183J81D01*
G02X728916Y1423122I3202J1418D01*
G37*
G36*
G01X1710944Y1420213D02*
G02X1711245Y1421632I3503J-2D01*
G03Y1421794I-183J81D01*
G02X1710944Y1423213I3202J1421D01*
G02X1714447Y1426716I3503J0D01*
G02X1715866Y1426415I-2J-3503D01*
G03X1716028I81J183D01*
G02X1717447Y1426716I1421J-3202D01*
G02X1720950Y1423213I0J-3503D01*
G02X1720649Y1421794I-3503J2D01*
G03Y1421632I183J-81D01*
G02X1720950Y1420213I-3202J-1421D01*
G02X1720649Y1418794I-3503J2D01*
G03Y1418632I183J-81D01*
G02X1720950Y1417213I-3202J-1421D01*
G02X1717447Y1413710I-3503J0D01*
G02X1716028Y1414011I2J3503D01*
G03X1715866I-81J-183D01*
G02X1714447Y1413710I-1421J3202D01*
G02X1710944Y1417213I0J3503D01*
G02X1711245Y1418632I3503J-2D01*
G03Y1418794I-183J81D01*
G02X1710944Y1420213I3202J1421D01*
G37*
G36*
G01X159370Y1411611D02*
G02X159748Y1413192I3503J-2D01*
G03X159760Y1413343I-178J90D01*
G02X159596Y1414400I3339J1059D01*
G02X166602I3503J0D01*
G02X166224Y1412819I-3503J2D01*
G03X166212Y1412668I178J-90D01*
G02X166376Y1411611I-3339J-1059D01*
G02X166238Y1410639I-3503J2D01*
G03X166249Y1410501I192J-54D01*
G02X166564Y1409048I-3188J-1452D01*
G02X166358Y1407866I-3503J2D01*
G03Y1407730I188J-68D01*
G02X166564Y1406548I-3297J-1184D01*
G02X159558I-3503J0D01*
G02X159764Y1407730I3503J-2D01*
G03Y1407866I-188J68D01*
G02X159558Y1409048I3297J1184D01*
G02X159696Y1410020I3503J-2D01*
G03X159685Y1410158I-192J54D01*
G02X159370Y1411611I3188J1452D01*
G37*
G36*
G01X169474Y1411460D02*
G02X169851Y1413041I3502J0D01*
G03X169863Y1413192I-178J90D01*
G02X169700Y1414249I3340J1056D01*
G02X176704I3502J0D01*
G01Y1414248D01*
G02X176327Y1412668I-3502J1D01*
G03X176315Y1412517I178J-90D01*
G02X176478Y1411460I-3340J-1056D01*
G02X176341Y1410488I-3502J-2D01*
G03X176351Y1410350I192J-55D01*
G02X176666Y1408897I-3187J-1452D01*
G02X176461Y1407714I-3502J-2D01*
G03Y1407580I188J-67D01*
G02X176666Y1406400I-3297J-1181D01*
G01Y1406397D01*
G02X169662I-3502J0D01*
G01Y1406400D01*
G02X169867Y1407580I3502J-1D01*
G03Y1407714I-188J67D01*
G02X169662Y1408897I3297J1181D01*
G02X169799Y1409869I3502J2D01*
G03X169789Y1410007I-192J55D01*
G02X169474Y1411460I3187J1452D01*
G37*
G36*
G01X194307Y1413378D02*
G02X195490Y1413173I2J-3502D01*
G03X195624I67J188D01*
G02X196807Y1413378I1181J-3297D01*
G02X197990Y1413173I2J-3502D01*
G03X198124I67J188D01*
G02X199307Y1413378I1181J-3297D01*
G02X202810Y1409876I1J-3502D01*
G02X202672Y1408904I-3503J2D01*
G03X202683Y1408766I192J-54D01*
G02X202998Y1407313I-3188J-1452D01*
G02X202792Y1406131I-3503J2D01*
G03Y1405995I188J-68D01*
G02X202998Y1404813I-3297J-1184D01*
G02X199495Y1401310I-3503J0D01*
G02X198313Y1401516I2J3503D01*
G03X198177I-68J-188D01*
G02X196995Y1401310I-1184J3297D01*
G02X195813Y1401516I2J3503D01*
G03X195677I-68J-188D01*
G02X194495Y1401310I-1184J3297D01*
G02X193313Y1401516I2J3503D01*
G03X193177I-68J-188D01*
G02X191995Y1401310I-1184J3297D01*
G02X190434Y1401678I2J3503D01*
G03X190256I-89J-179D01*
G02X188695Y1401310I-1563J3135D01*
G02X185192Y1404813I0J3503D01*
G02X185398Y1405995I3503J-2D01*
G03Y1406131I-188J68D01*
G02X185192Y1407313I3297J1184D01*
G02X185330Y1408285I3503J-2D01*
G03X185319Y1408423I-192J54D01*
G02X185004Y1409876I3188J1452D01*
G02X188507Y1413378I3503J-1D01*
G02X190068Y1413011I0J-3503D01*
G03X190246I89J179D01*
G02X191807Y1413378I1561J-3136D01*
G01X191810D01*
G02X192990Y1413173I-1J-3502D01*
G03X193124I67J188D01*
G02X194307Y1413378I1181J-3297D01*
G37*
G36*
G01X1132465Y1407380D02*
G02X1133647Y1407174I-2J-3503D01*
G03X1133783I68J188D01*
G02X1134965Y1407380I1184J-3297D01*
G02X1136147Y1407174I-2J-3503D01*
G03X1136283I68J188D01*
G02X1137465Y1407380I1184J-3297D01*
G02X1140968Y1403877I0J-3503D01*
G02X1140762Y1402695I-3503J2D01*
G03Y1402559I188J-68D01*
G02X1140968Y1401377I-3297J-1184D01*
G02X1140718Y1400079I-3503J2D01*
G03X1140716Y1399936I186J-74D01*
G02X1140928Y1398737I-3291J-1200D01*
G02X1137425Y1395234I-3503J0D01*
G02X1136243Y1395440I2J3503D01*
G03X1136107I-68J-188D01*
G02X1134925Y1395234I-1184J3297D01*
G02X1133743Y1395440I2J3503D01*
G03X1133607I-68J-188D01*
G02X1132425Y1395234I-1184J3297D01*
G02X1131243Y1395440I2J3503D01*
G03X1131107I-68J-188D01*
G02X1129925Y1395234I-1184J3297D01*
G02X1128743Y1395440I2J3503D01*
G03X1128607I-68J-188D01*
G02X1127425Y1395234I-1184J3297D01*
G02X1123922Y1398737I0J3503D01*
G02X1124172Y1400035I3503J-2D01*
G03X1124174Y1400178I-186J74D01*
G02X1123962Y1401377I3291J1200D01*
G02X1124168Y1402559I3503J-2D01*
G03Y1402695I-188J68D01*
G02X1123962Y1403877I3297J1184D01*
G02X1127465Y1407380I3503J0D01*
G02X1128647Y1407174I-2J-3503D01*
G03X1128783I68J188D01*
G02X1129965Y1407380I1184J-3297D01*
G02X1131147Y1407174I-2J-3503D01*
G03X1131283I68J188D01*
G02X1132465Y1407380I1184J-3297D01*
G37*
G36*
G01X758089Y1394448D02*
G02X759238Y1394253I3J-3467D01*
G03X759370I66J189D01*
G02X759781Y1394369I1146J-3273D01*
G02X759780Y1394414I3501J100D01*
G01Y1394418D01*
G02X760060Y1395788I3503J-2D01*
G03Y1395944I-184J78D01*
G02X759780Y1397316I3223J1372D01*
G02X763283Y1400818I3503J-1D01*
G01X763284D01*
G02X765454Y1400064I-1J-3502D01*
G03X765685Y1400052I124J157D01*
G02X767549Y1400588I1862J-2967D01*
G02X771052Y1397086I1J-3502D01*
G02X770772Y1395714I-3503J0D01*
G03Y1395558I184J-78D01*
G02X771052Y1394186I-3223J-1372D01*
G02X770772Y1392814I-3503J0D01*
G03Y1392658I184J-78D01*
G02X771052Y1391286I-3223J-1372D01*
G02X767549Y1387784I-3503J1D01*
G02X764748Y1389183I0J3504D01*
G03X764631Y1389258I-160J-120D01*
G02X764581Y1389269I728J3426D01*
G01X764422Y1389099D01*
G03X764373Y1388913I145J-138D01*
G02X764482Y1388046I-3393J-867D01*
G02X764202Y1386674I-3502J0D01*
G03Y1386518I184J-78D01*
G02X764482Y1385147I-3222J-1372D01*
G01Y1385146D01*
G02X757478I-3502J0D01*
G01Y1385147D01*
G02X757758Y1386518I3502J-1D01*
G03X757757Y1386674I-185J77D01*
G02X757533Y1387427I3224J1369D01*
G03X757377Y1387587I-197J-36D01*
G02X756940Y1387709I712J3394D01*
G03X756808I-66J-189D01*
G02X755663Y1387514I-1146J3272D01*
G01X755659D01*
G02Y1394448I0J3467D01*
G01X755663D01*
G02X756808Y1394253I-1J-3467D01*
G03X756940I66J189D01*
G02X758089Y1394448I1146J-3272D01*
G37*
G36*
G01X725307Y1394348D02*
G02X726456Y1394153I3J-3467D01*
G03X726588I66J189D01*
G02X726999Y1394269I1146J-3273D01*
G02X726998Y1394314I3501J100D01*
G01Y1394318D01*
G02X727278Y1395688I3503J-2D01*
G03Y1395844I-184J78D01*
G02X726998Y1397216I3223J1372D01*
G02X730501Y1400718I3503J-1D01*
G01X730502D01*
G02X732672Y1399964I-1J-3502D01*
G03X732903Y1399952I124J157D01*
G02X734767Y1400488I1862J-2967D01*
G02X738270Y1396986I1J-3502D01*
G02X737990Y1395614I-3503J0D01*
G03Y1395458I184J-78D01*
G02X738270Y1394086I-3223J-1372D01*
G02X737990Y1392714I-3503J0D01*
G03Y1392558I184J-78D01*
G02X738270Y1391186I-3223J-1372D01*
G02X734767Y1387684I-3503J1D01*
G02X731966Y1389083I0J3504D01*
G03X731849Y1389158I-160J-120D01*
G02X731821Y1389164I720J3428D01*
G01X731661Y1388997D01*
G03X731611Y1388814I145J-138D01*
G02X731700Y1388026I-3413J-785D01*
G02X731420Y1386654I-3502J0D01*
G03Y1386498I184J-78D01*
G02X731700Y1385127I-3222J-1372D01*
G01Y1385126D01*
G02X724696I-3502J0D01*
G01Y1385127D01*
G02X724976Y1386498I3502J-1D01*
G03Y1386654I-184J78D01*
G02X724766Y1387328I3222J1373D01*
G03X724610Y1387484I-196J-40D01*
G02X724158Y1387609I696J3397D01*
G03X724026I-66J-189D01*
G02X722881Y1387414I-1146J3272D01*
G01X722877D01*
G02Y1394348I0J3467D01*
G01X722881D01*
G02X724026Y1394153I-1J-3467D01*
G03X724158I66J189D01*
G02X725307Y1394348I1146J-3272D01*
G37*
G36*
G01X1707794Y1395233D02*
G02X1707514Y1396605I3222J1372D01*
G02X1711016Y1400108I3502J1D01*
G02X1713187Y1399353I-1J-3503D01*
G03X1713418Y1399341I124J157D01*
G02X1715282Y1399878I1864J-2967D01*
G02X1718784Y1396375I-1J-3503D01*
G01Y1396374D01*
G02X1718504Y1395003I-3502J1D01*
G03Y1394847I184J-78D01*
G02X1718784Y1393475I-3222J-1372D01*
G02X1718504Y1392103I-3502J0D01*
G03Y1391947I184J-78D01*
G02X1718784Y1390575I-3222J-1372D01*
G02X1715282Y1387072I-3502J-1D01*
G02X1712481Y1388472I0J3502D01*
G03X1712363Y1388547I-159J-121D01*
G02X1712314Y1388558I743J3423D01*
G01X1712155Y1388389D01*
G03X1712107Y1388202I146J-137D01*
G02X1712216Y1387335I-3394J-867D01*
G02X1711936Y1385963I-3503J0D01*
G03Y1385807I184J-78D01*
G02X1712216Y1384435I-3223J-1372D01*
G02X1705210I-3503J0D01*
G02X1705490Y1385807I3503J0D01*
G03Y1385963I-184J78D01*
G02X1705266Y1386716I3224J1369D01*
G03X1705110Y1386876I-197J-36D01*
G02X1704673Y1386998I712J3394D01*
G03X1704541I-66J-189D01*
G02X1703392Y1386802I-1149J3272D01*
G02Y1393738I0J3468D01*
G02X1704541Y1393542I0J-3468D01*
G03X1704673I66J189D01*
G02X1705822Y1393738I1149J-3272D01*
G02X1706971Y1393542I0J-3468D01*
G03X1707103I66J189D01*
G02X1707514Y1393658I1146J-3273D01*
G01Y1393705D01*
G02X1707794Y1395077I3502J0D01*
G03Y1395233I-184J78D01*
G37*
G36*
G01X1675012Y1395133D02*
G02X1674732Y1396505I3222J1372D01*
G02X1678234Y1400008I3502J1D01*
G02X1680405Y1399253I-1J-3503D01*
G03X1680636Y1399241I124J157D01*
G02X1682500Y1399778I1864J-2967D01*
G02X1686002Y1396275I-1J-3503D01*
G01Y1396274D01*
G02X1685722Y1394903I-3502J1D01*
G03Y1394747I184J-78D01*
G02X1686002Y1393375I-3222J-1372D01*
G02X1685722Y1392003I-3502J0D01*
G03Y1391847I184J-78D01*
G02X1686002Y1390475I-3222J-1372D01*
G02X1682500Y1386972I-3502J-1D01*
G02X1679699Y1388372I0J3502D01*
G03X1679581Y1388447I-159J-121D01*
G02X1679532Y1388458I743J3423D01*
G01X1679373Y1388289D01*
G03X1679325Y1388102I146J-137D01*
G02X1679434Y1387235I-3394J-867D01*
G02X1679154Y1385863I-3503J0D01*
G03Y1385707I184J-78D01*
G02X1679434Y1384335I-3223J-1372D01*
G02X1672428I-3503J0D01*
G02X1672708Y1385707I3503J0D01*
G03Y1385863I-184J78D01*
G02X1672484Y1386616I3224J1369D01*
G03X1672328Y1386776I-197J-36D01*
G02X1671891Y1386898I712J3394D01*
G03X1671759I-66J-189D01*
G02X1670610Y1386702I-1149J3272D01*
G02Y1393638I0J3468D01*
G02X1671759Y1393442I0J-3468D01*
G03X1671891I66J189D01*
G02X1673040Y1393638I1149J-3272D01*
G02X1674189Y1393442I0J-3468D01*
G03X1674321I66J189D01*
G02X1674732Y1393558I1146J-3273D01*
G01Y1393605D01*
G02X1675012Y1394977I3502J0D01*
G03Y1395133I-184J78D01*
G37*
G36*
G01X291182Y1387040D02*
G02X291534Y1388572I3502J2D01*
G03Y1388747I-180J88D01*
G02X291180Y1390281I3149J1535D01*
G02X298186I3503J0D01*
G02X297833Y1388748I-3504J0D01*
G03Y1388574I180J-87D01*
G02X298186Y1387040I-3149J-1532D01*
G02X297879Y1385605I-3502J-1D01*
G03X297871Y1385462I183J-82D01*
G02X298036Y1384401I-3338J-1062D01*
G02X297860Y1383305I-3503J0D01*
G03X297870Y1383154I190J-63D01*
G02X298228Y1381612I-3145J-1543D01*
G02X291222I-3503J0D01*
G02X291398Y1382708I3503J0D01*
G03X291388Y1382859I-190J63D01*
G02X291030Y1384401I3145J1543D01*
G02X291338Y1385836I3503J-1D01*
G03X291346Y1385979I-183J82D01*
G02X291182Y1387040I3338J1059D01*
G37*
G36*
G01X1343712Y1393306D02*
G02X1344895Y1393101I2J-3502D01*
G03X1345029I67J188D01*
G02X1346212Y1393306I1181J-3297D01*
G02X1347395Y1393101I2J-3502D01*
G03X1347529I67J188D01*
G02X1348712Y1393306I1181J-3297D01*
G02X1350387Y1392879I-1J-3502D01*
G03X1350577I95J176D01*
G02X1352225Y1393290I1646J-3091D01*
G02X1355728Y1389788I1J-3502D01*
G02X1355431Y1388378I-3503J2D01*
G03Y1388216I183J-81D01*
G02X1355728Y1386804I-3205J-1411D01*
G02X1355428Y1385385I-3502J-1D01*
G03Y1385223I183J-81D01*
G02X1355728Y1383806I-3202J-1418D01*
G01Y1383804D01*
G02X1352226Y1380302I-3502J0D01*
G02X1351121Y1380480I-3J3502D01*
G03X1350977Y1380473I-63J-190D01*
G02X1349556Y1380172I-1420J3201D01*
G02X1348137Y1380472I-1J3502D01*
G03X1347975I-81J-183D01*
G02X1346556Y1380172I-1418J3202D01*
G02X1345137Y1380472I-1J3502D01*
G03X1344975I-81J-183D01*
G02X1343556Y1380172I-1418J3202D01*
G02X1342137Y1380472I-1J3502D01*
G03X1341975I-81J-183D01*
G02X1340556Y1380172I-1418J3202D01*
G02X1339137Y1380472I-1J3502D01*
G03X1338975I-81J-183D01*
G02X1337558Y1380172I-1418J3202D01*
G01X1337556D01*
G02X1334054Y1383674I0J3502D01*
G01Y1383676D01*
G02X1334354Y1385093I3502J-1D01*
G03Y1385255I-183J81D01*
G02X1334054Y1386674I3202J1418D01*
G02X1334350Y1388084I3502J1D01*
G03Y1388246I-183J81D01*
G02X1334052Y1389658I3205J1414D01*
G02X1337555Y1393160I3503J-1D01*
G01X1337556D01*
G02X1339163Y1392769I-1J-3502D01*
G03X1339360Y1392777I91J178D01*
G02X1341212Y1393306I1851J-2973D01*
G02X1342395Y1393101I2J-3502D01*
G03X1342529I67J188D01*
G02X1343712Y1393306I1181J-3297D01*
G37*
G36*
G01X301660Y1386889D02*
G02X301918Y1388209I3503J1D01*
G03Y1388359I-185J75D01*
G02X301660Y1389678I3245J1319D01*
G02X308666I3503J0D01*
G02X308408Y1388359I-3503J0D01*
G03Y1388209I185J-75D01*
G02X308666Y1386889I-3245J-1319D01*
G02X308358Y1385454I-3503J1D01*
G03X308350Y1385311I183J-82D01*
G02X308514Y1384250I-3338J-1059D01*
G02X308338Y1383153I-3502J-1D01*
G03X308349Y1383003I190J-61D01*
G02X308706Y1381463I-3145J-1541D01*
G01Y1381461D01*
G02X301702I-3502J0D01*
G01Y1381465D01*
G02X301878Y1382558I3502J-3D01*
G03X301867Y1382708I-190J61D01*
G02X301510Y1384250I3145J1541D01*
G02X301817Y1385685I3502J1D01*
G03X301825Y1385828I-183J82D01*
G02X301660Y1386889I3338J1062D01*
G37*
G36*
G01X320208Y1376259D02*
G02X320560Y1377791I3502J2D01*
G03Y1377966I-180J88D01*
G02X320206Y1379500I3149J1535D01*
G02X327212I3503J0D01*
G02X326859Y1377967I-3504J0D01*
G03Y1377793I180J-87D01*
G02X327212Y1376259I-3149J-1532D01*
G02X326905Y1374824I-3502J-1D01*
G03X326897Y1374681I183J-82D01*
G02X327062Y1373620I-3338J-1062D01*
G02X326886Y1372524I-3503J0D01*
G03X326896Y1372373I190J-63D01*
G02X327254Y1370831I-3145J-1543D01*
G02X320248I-3503J0D01*
G02X320424Y1371927I3503J0D01*
G03X320414Y1372078I-190J63D01*
G02X320056Y1373620I3145J1543D01*
G02X320364Y1375055I3503J-1D01*
G03X320372Y1375198I-183J82D01*
G02X320208Y1376259I3338J1059D01*
G37*
G36*
G01X250442Y1376309D02*
G02X250722Y1377679I3503J-2D01*
G03Y1377835I-184J78D01*
G02X250442Y1379207I3223J1372D01*
G02X253945Y1382710I3503J0D01*
G02X256116Y1381955I-1J-3503D01*
G03X256347Y1381943I124J157D01*
G02X258211Y1382480I1864J-2967D01*
G02X261714Y1378977I0J-3503D01*
G02X261434Y1377605I-3503J0D01*
G03Y1377449I184J-78D01*
G02X261714Y1376077I-3223J-1372D01*
G02X261434Y1374705I-3503J0D01*
G03Y1374549I184J-78D01*
G02X261714Y1373177I-3223J-1372D01*
G02X258211Y1369674I-3503J0D01*
G02X256286Y1370251I1J3503D01*
G01X256285Y1370252D01*
G03X256088Y1370264I-109J-168D01*
G01X255731Y1370090D01*
X255671Y1370002D01*
X255667Y1369950D01*
G02X255396Y1368861I-3456J282D01*
G03Y1368703I184J-79D01*
G02X255678Y1367335I-3185J-1370D01*
G01Y1367332D01*
G02X248744I-3467J0D01*
G01Y1367335D01*
G02X249026Y1368703I3467J-2D01*
G03Y1368861I-184J79D01*
G02X248843Y1369406I3184J1372D01*
G02X248752Y1369404I-122J3465D01*
G01X248750D01*
G02X247602Y1369600I1J3468D01*
G03X247470I-66J-189D01*
G02X246321Y1369404I-1149J3272D01*
G02Y1376340I0J3468D01*
G02X247470Y1376144I0J-3468D01*
G03X247602I66J189D01*
G02X248751Y1376340I1149J-3272D01*
G02X249900Y1376144I0J-3468D01*
G03X250032I66J189D01*
G02X250443Y1376260I1146J-3273D01*
G02X250442Y1376305I3501J100D01*
G01Y1376309D01*
G37*
G36*
G01X217642D02*
G02X217922Y1377679I3503J-2D01*
G03Y1377835I-184J78D01*
G02X217642Y1379207I3223J1372D01*
G02X221145Y1382710I3503J0D01*
G02X223316Y1381955I-1J-3503D01*
G03X223547Y1381943I124J157D01*
G02X225411Y1382480I1864J-2967D01*
G02X228914Y1378977I0J-3503D01*
G02X228634Y1377605I-3503J0D01*
G03Y1377449I184J-78D01*
G02X228914Y1376077I-3223J-1372D01*
G02X228634Y1374705I-3503J0D01*
G03Y1374549I184J-78D01*
G02X228914Y1373177I-3223J-1372D01*
G02X225411Y1369674I-3503J0D01*
G02X223516Y1370231I0J3502D01*
G01X223471Y1370260D01*
X223364Y1370266D01*
X222960Y1370056D01*
X222902Y1369966D01*
X222900Y1369913D01*
G02X222624Y1368695I-3499J153D01*
G03Y1368539I184J-78D01*
G02X222904Y1367167I-3223J-1372D01*
G02X215898I-3503J0D01*
G02X216178Y1368539I3503J0D01*
G03X216179Y1368695I-184J79D01*
G02X215962Y1369405I3222J1373D01*
G01X215960D01*
G02X215942Y1369404I-20J199D01*
G02X214802Y1369600I9J3468D01*
G03X214670I-66J-189D01*
G02X213521Y1369404I-1149J3272D01*
G02Y1376340I0J3468D01*
G02X214670Y1376144I0J-3468D01*
G03X214802I66J189D01*
G02X215951Y1376340I1149J-3272D01*
G02X217100Y1376144I0J-3468D01*
G03X217232I66J189D01*
G02X217643Y1376260I1146J-3273D01*
G02X217642Y1376305I3501J100D01*
G01Y1376309D01*
G37*
G36*
G01X184742D02*
G02X185022Y1377679I3503J-2D01*
G03Y1377835I-184J78D01*
G02X184742Y1379207I3223J1372D01*
G02X188245Y1382710I3503J0D01*
G02X190416Y1381955I-1J-3503D01*
G03X190647Y1381943I124J157D01*
G02X192511Y1382480I1864J-2967D01*
G02X196014Y1378977I0J-3503D01*
G02X195734Y1377605I-3503J0D01*
G03Y1377449I184J-78D01*
G02X196014Y1376077I-3223J-1372D01*
G02X195734Y1374705I-3503J0D01*
G03Y1374549I184J-78D01*
G02X196014Y1373177I-3223J-1372D01*
G02X192511Y1369674I-3503J0D01*
G02X190595Y1370245I1J3503D01*
G01X190550Y1370275D01*
X190445Y1370281D01*
X190087Y1370101D01*
G03X189977Y1369934I90J-179D01*
G02X189704Y1368775I-3496J212D01*
G03Y1368619I184J-78D01*
G02X189984Y1367247I-3223J-1372D01*
G02X182978I-3503J0D01*
G02X183258Y1368619I3503J0D01*
G03Y1368775I-184J78D01*
G02X183058Y1369405I3224J1370D01*
G02X183051Y1369404I-489J3398D01*
G02X181902Y1369600I0J3468D01*
G03X181770I-66J-189D01*
G02X180621Y1369404I-1149J3272D01*
G02Y1376340I0J3468D01*
G02X181770Y1376144I0J-3468D01*
G03X181902I66J189D01*
G02X183051Y1376340I1149J-3272D01*
G02X184200Y1376144I0J-3468D01*
G03X184332I66J189D01*
G02X184743Y1376260I1146J-3273D01*
G02X184742Y1376305I3501J100D01*
G01Y1376309D01*
G37*
G36*
G01X152042D02*
G02X152322Y1377679I3503J-2D01*
G03Y1377835I-184J78D01*
G02X152042Y1379207I3223J1372D01*
G02X155545Y1382710I3503J0D01*
G02X157716Y1381955I-1J-3503D01*
G03X157947Y1381943I124J157D01*
G02X159811Y1382480I1864J-2967D01*
G02X163314Y1378977I0J-3503D01*
G02X163034Y1377605I-3503J0D01*
G03Y1377449I184J-78D01*
G02X163314Y1376077I-3223J-1372D01*
G02X163034Y1374705I-3503J0D01*
G03Y1374549I184J-78D01*
G02X163314Y1373177I-3223J-1372D01*
G02X159811Y1369674I-3503J0D01*
G02X157865Y1370265I1J3503D01*
G01X157819Y1370295D01*
X157709Y1370301D01*
X157350Y1370111D01*
G03X157243Y1369938I93J-177D01*
G01Y1369937D01*
G02X156963Y1368605I-3502J41D01*
G03X156964Y1368449I185J-77D01*
G02X157244Y1367077I-3223J-1372D01*
G02X150238I-3503J0D01*
G02X150518Y1368449I3503J0D01*
G03X150519Y1368605I-184J79D01*
G02X150315Y1369253I3223J1371D01*
G03X150132Y1369411I-196J-42D01*
G02X149202Y1369600I219J3461D01*
G03X149070I-66J-189D01*
G02X147921Y1369404I-1149J3272D01*
G02Y1376340I0J3468D01*
G02X149070Y1376144I0J-3468D01*
G03X149202I66J189D01*
G02X150351Y1376340I1149J-3272D01*
G02X151500Y1376144I0J-3468D01*
G03X151632I66J189D01*
G02X152043Y1376260I1146J-3273D01*
G02X152042Y1376305I3501J100D01*
G01Y1376309D01*
G37*
G36*
G01X119442D02*
G02X119722Y1377679I3503J-2D01*
G03Y1377835I-184J78D01*
G02X119442Y1379207I3223J1372D01*
G02X122945Y1382710I3503J0D01*
G02X125116Y1381955I-1J-3503D01*
G03X125347Y1381943I124J157D01*
G02X127211Y1382480I1864J-2967D01*
G02X130714Y1378977I0J-3503D01*
G02X130434Y1377605I-3503J0D01*
G03Y1377449I184J-78D01*
G02X130714Y1376077I-3223J-1372D01*
G02X130434Y1374705I-3503J0D01*
G03Y1374549I184J-78D01*
G02X130714Y1373177I-3223J-1372D01*
G02X127211Y1369674I-3503J0D01*
G02X125355Y1370207I1J3503D01*
G03X125153Y1370213I-106J-169D01*
G01X124800Y1370022D01*
X124744Y1369930D01*
X124743Y1369876D01*
G02X124464Y1368575I-3502J71D01*
G03Y1368419I184J-78D01*
G02X124744Y1367047I-3223J-1372D01*
G02X122784Y1363903I-3502J0D01*
G03X122672Y1363714I88J-180D01*
G02X122674Y1363643I-1465J-77D01*
G02X119740I-1467J0D01*
G02X119743Y1363743I1467J6D01*
G03X119635Y1363934I-199J13D01*
G02X117738Y1367047I1606J3113D01*
G02X118018Y1368419I3503J0D01*
G03X118019Y1368575I-184J79D01*
G02X117781Y1369405I3222J1373D01*
G02X117754Y1369404I-142J3463D01*
G01X117748D01*
G02X116602Y1369600I3J3468D01*
G03X116470I-66J-189D01*
G02X115321Y1369404I-1149J3272D01*
G02Y1376340I0J3468D01*
G02X116470Y1376144I0J-3468D01*
G03X116602I66J189D01*
G02X117751Y1376340I1149J-3272D01*
G02X118900Y1376144I0J-3468D01*
G03X119032I66J189D01*
G02X119443Y1376260I1146J-3273D01*
G02X119442Y1376305I3501J100D01*
G01Y1376309D01*
G37*
G36*
G01X1220489Y1376320D02*
G02X1221638Y1376125I3J-3467D01*
G03X1221770I66J189D01*
G02X1222181Y1376241I1146J-3273D01*
G02X1222180Y1376286I3501J100D01*
G01Y1376290D01*
G02X1222460Y1377660I3503J-2D01*
G03Y1377816I-184J78D01*
G02X1222180Y1379188I3223J1372D01*
G02X1225683Y1382690I3503J-1D01*
G01X1225684D01*
G02X1227854Y1381936I-1J-3502D01*
G03X1228085Y1381924I124J157D01*
G02X1229949Y1382460I1862J-2967D01*
G02X1233452Y1378958I1J-3502D01*
G02X1233172Y1377586I-3503J0D01*
G03Y1377430I184J-78D01*
G02X1233452Y1376058I-3223J-1372D01*
G02X1233172Y1374686I-3503J0D01*
G03Y1374530I184J-78D01*
G02X1233452Y1373158I-3223J-1372D01*
G02X1229949Y1369656I-3503J1D01*
G01X1229948D01*
G02X1228009Y1370242I0J3502D01*
G01X1227964Y1370272D01*
X1227857Y1370279D01*
X1227497Y1370097D01*
G03X1227388Y1369927I91J-178D01*
G02X1227112Y1368716I-3499J161D01*
G03Y1368560I184J-78D01*
G02X1227392Y1367188I-3223J-1372D01*
G02X1220386I-3503J0D01*
G02X1220666Y1368560I3503J0D01*
G03X1220667Y1368716I-184J79D01*
G02X1220491Y1369239I3221J1375D01*
G03X1220308Y1369391I-194J-48D01*
G02X1219340Y1369581I177J3463D01*
G03X1219208I-66J-189D01*
G02X1218063Y1369386I-1146J3272D01*
G01X1218059D01*
G02Y1376320I0J3467D01*
G01X1218063D01*
G02X1219208Y1376125I-1J-3467D01*
G03X1219340I66J189D01*
G02X1220489Y1376320I1146J-3272D01*
G37*
G36*
G01X1187689D02*
G02X1188838Y1376125I3J-3467D01*
G03X1188970I66J189D01*
G02X1189381Y1376241I1146J-3273D01*
G02X1189380Y1376286I3501J100D01*
G01Y1376290D01*
G02X1189660Y1377660I3503J-2D01*
G03Y1377816I-184J78D01*
G02X1189380Y1379188I3223J1372D01*
G02X1192883Y1382690I3503J-1D01*
G01X1192884D01*
G02X1195054Y1381936I-1J-3502D01*
G03X1195285Y1381924I124J157D01*
G02X1197149Y1382460I1862J-2967D01*
G02X1200652Y1378958I1J-3502D01*
G02X1200372Y1377586I-3503J0D01*
G03Y1377430I184J-78D01*
G02X1200652Y1376058I-3223J-1372D01*
G02X1200372Y1374686I-3503J0D01*
G03Y1374530I184J-78D01*
G02X1200652Y1373158I-3223J-1372D01*
G02X1197149Y1369656I-3503J1D01*
G01X1197146D01*
G02X1195174Y1370265I2J3502D01*
G01X1195129Y1370296D01*
X1195021Y1370304D01*
X1194609Y1370097D01*
X1194551Y1370006D01*
X1194549Y1369951D01*
G02X1194272Y1368716I-3500J136D01*
G03Y1368560I184J-78D01*
G02X1194552Y1367188I-3223J-1372D01*
G02X1187546I-3503J0D01*
G02X1187826Y1368560I3503J0D01*
G03X1187827Y1368716I-184J79D01*
G02X1187651Y1369241I3222J1372D01*
G03X1187469Y1369392I-194J-49D01*
G02X1186540Y1369581I220J3461D01*
G03X1186408I-66J-189D01*
G02X1185263Y1369386I-1146J3272D01*
G01X1185259D01*
G02Y1376320I0J3467D01*
G01X1185263D01*
G02X1186408Y1376125I-1J-3467D01*
G03X1186540I66J189D01*
G02X1187689Y1376320I1146J-3272D01*
G37*
G36*
G01X1154789D02*
G02X1155938Y1376125I3J-3467D01*
G03X1156070I66J189D01*
G02X1156481Y1376241I1146J-3273D01*
G02X1156480Y1376286I3501J100D01*
G01Y1376290D01*
G02X1156760Y1377660I3503J-2D01*
G03Y1377816I-184J78D01*
G02X1156480Y1379188I3223J1372D01*
G02X1159983Y1382690I3503J-1D01*
G01X1159984D01*
G02X1162154Y1381936I-1J-3502D01*
G03X1162385Y1381924I124J157D01*
G02X1164249Y1382460I1862J-2967D01*
G02X1167752Y1378958I1J-3502D01*
G02X1167472Y1377586I-3503J0D01*
G03Y1377430I184J-78D01*
G02X1167752Y1376058I-3223J-1372D01*
G02X1167472Y1374686I-3503J0D01*
G03Y1374530I184J-78D01*
G02X1167752Y1373158I-3223J-1372D01*
G02X1164249Y1369656I-3503J1D01*
G01X1164247D01*
G02X1162195Y1370321I1J3502D01*
G01X1162149Y1370354D01*
X1162036Y1370362D01*
X1161617Y1370144D01*
X1161560Y1370046D01*
X1161561Y1369989D01*
G02X1161562Y1369918I-3502J-85D01*
G02X1161282Y1368546I-3503J0D01*
G03Y1368390I184J-78D01*
G02X1161562Y1367018I-3223J-1372D01*
G02X1154556I-3503J0D01*
G02X1154836Y1368390I3503J0D01*
G03Y1368546I-184J78D01*
G02X1154622Y1369242I3223J1372D01*
G03X1154446Y1369403I-196J-38D01*
G02X1153640Y1369581I339J3451D01*
G03X1153508I-66J-189D01*
G02X1152363Y1369386I-1146J3272D01*
G01X1152359D01*
G02Y1376320I0J3467D01*
G01X1152363D01*
G02X1153508Y1376125I-1J-3467D01*
G03X1153640I66J189D01*
G02X1154789Y1376320I1146J-3272D01*
G37*
G36*
G01X1122089D02*
G02X1123238Y1376125I3J-3467D01*
G03X1123370I66J189D01*
G02X1123781Y1376241I1146J-3273D01*
G02X1123780Y1376286I3501J100D01*
G01Y1376290D01*
G02X1124060Y1377660I3503J-2D01*
G03Y1377816I-184J78D01*
G02X1123780Y1379188I3223J1372D01*
G02X1127283Y1382690I3503J-1D01*
G01X1127284D01*
G02X1129454Y1381936I-1J-3502D01*
G03X1129685Y1381924I124J157D01*
G02X1131549Y1382460I1862J-2967D01*
G02X1135052Y1378958I1J-3502D01*
G02X1134772Y1377586I-3503J0D01*
G03Y1377430I184J-78D01*
G02X1135052Y1376058I-3223J-1372D01*
G02X1134772Y1374686I-3503J0D01*
G03Y1374530I184J-78D01*
G02X1135052Y1373158I-3223J-1372D01*
G02X1131549Y1369656I-3503J1D01*
G01X1131548D01*
G02X1129594Y1370252I0J3502D01*
G01X1129593Y1370253D01*
G03X1129390Y1370264I-111J-167D01*
G01X1129030Y1370077D01*
X1128972Y1369984D01*
X1128971Y1369929D01*
G02X1128692Y1368636I-3502J79D01*
G03Y1368480I184J-78D01*
G02X1128972Y1367108I-3223J-1372D01*
G02X1121966I-3503J0D01*
G02X1122246Y1368480I3503J0D01*
G03Y1368636I-184J78D01*
G02X1122052Y1369237I3223J1372D01*
G03X1121870Y1369392I-195J-44D01*
G02X1120940Y1369581I219J3461D01*
G03X1120808I-66J-189D01*
G02X1119663Y1369386I-1146J3272D01*
G01X1119659D01*
G02Y1376320I0J3467D01*
G01X1119663D01*
G02X1120808Y1376125I-1J-3467D01*
G03X1120940I66J189D01*
G02X1122089Y1376320I1146J-3272D01*
G37*
G36*
G01X1089489D02*
G02X1090638Y1376125I3J-3467D01*
G03X1090770I66J189D01*
G02X1091181Y1376241I1146J-3273D01*
G02X1091180Y1376286I3501J100D01*
G01Y1376290D01*
G02X1091460Y1377660I3503J-2D01*
G03Y1377816I-184J78D01*
G02X1091180Y1379188I3223J1372D01*
G02X1094683Y1382690I3503J-1D01*
G01X1094684D01*
G02X1096854Y1381936I-1J-3502D01*
G03X1097085Y1381924I124J157D01*
G02X1098949Y1382460I1862J-2967D01*
G02X1102452Y1378958I1J-3502D01*
G02X1102172Y1377586I-3503J0D01*
G03Y1377430I184J-78D01*
G02X1102452Y1376058I-3223J-1372D01*
G02X1102172Y1374686I-3503J0D01*
G03Y1374530I184J-78D01*
G02X1102452Y1373158I-3223J-1372D01*
G02X1098949Y1369656I-3503J1D01*
G01X1098947D01*
G02X1097004Y1370245I1J3502D01*
G01X1096960Y1370274D01*
X1096853Y1370282D01*
X1096494Y1370105D01*
G03X1096383Y1369939I89J-179D01*
G02X1096111Y1368806I-3494J240D01*
G03X1096112Y1368650I185J-77D01*
G02X1096392Y1367278I-3223J-1372D01*
G02X1089386I-3503J0D01*
G02X1089666Y1368650I3503J0D01*
G03Y1368806I-184J78D01*
G02X1089513Y1369243I3222J1373D01*
G03X1089330Y1369390I-193J-53D01*
G02X1088340Y1369581I155J3464D01*
G03X1088208I-66J-189D01*
G02X1087063Y1369386I-1146J3272D01*
G01X1087059D01*
G02Y1376320I0J3467D01*
G01X1087063D01*
G02X1088208Y1376125I-1J-3467D01*
G03X1088340I66J189D01*
G02X1089489Y1376320I1146J-3272D01*
G37*
G36*
G01X330686Y1376108D02*
G02X330944Y1377427I3503J0D01*
G03Y1377577I-185J75D01*
G02X330686Y1378897I3245J1319D01*
G02X337692I3503J0D01*
G02X337434Y1377577I-3503J-1D01*
G03Y1377427I185J-75D01*
G02X337692Y1376108I-3245J-1319D01*
G02X337384Y1374673I-3503J1D01*
G03X337376Y1374530I183J-82D01*
G02X337540Y1373469I-3338J-1059D01*
G02X337364Y1372372I-3502J-1D01*
G03X337375Y1372222I190J-61D01*
G02X337732Y1370682I-3145J-1541D01*
G01Y1370680D01*
G02X330728I-3502J0D01*
G01Y1370684D01*
G02X330904Y1371777I3502J-3D01*
G03X330893Y1371927I-190J61D01*
G02X330536Y1373469I3145J1541D01*
G02X330843Y1374904I3502J1D01*
G03X330851Y1375047I-183J82D01*
G02X330686Y1376108I3338J1062D01*
G37*
G36*
G01X362223Y1368226D02*
G02X363406Y1368021I2J-3502D01*
G03X363540I67J188D01*
G02X364723Y1368226I1181J-3297D01*
G02X368226Y1364724I1J-3502D01*
G02X367918Y1363289I-3503J1D01*
G03X367910Y1363146I183J-82D01*
G02X368074Y1362085I-3338J-1059D01*
G02X367898Y1360988I-3502J-1D01*
G03X367909Y1360838I190J-61D01*
G02X368266Y1359298I-3145J-1541D01*
G01Y1359296D01*
G02X364764Y1355794I-3502J0D01*
G01X364761D01*
G02X363581Y1355999I1J3502D01*
G03X363447I-67J-188D01*
G02X362264Y1355794I-1181J3297D01*
G02X361081Y1355999I-2J3502D01*
G03X360947I-67J-188D01*
G02X359764Y1355794I-1181J3297D01*
G02X358345Y1356094I-1J3502D01*
G03X358183I-81J-183D01*
G02X356764Y1355794I-1418J3202D01*
G02X355581Y1355999I-2J3502D01*
G03X355447I-67J-188D01*
G02X354264Y1355794I-1181J3297D01*
G02X353135Y1355981I0J3502D01*
G03X352993Y1355976I-64J-190D01*
G02X351632Y1355700I-1363J3227D01*
G02X348130Y1359203I1J3503D01*
G01Y1359206D01*
G02X348476Y1360723I3502J-1D01*
G03X348484Y1360878I-180J87D01*
G02X348270Y1362085I3288J1205D01*
G02X348577Y1363520I3502J1D01*
G03X348585Y1363663I-183J82D01*
G02X348420Y1364724I3338J1062D01*
G02X351923Y1368226I3503J-1D01*
G01X351926D01*
G02X353106Y1368021I-1J-3502D01*
G03X353240I67J188D01*
G02X354423Y1368226I1181J-3297D01*
G02X355606Y1368021I2J-3502D01*
G03X355740I67J188D01*
G02X356923Y1368226I1181J-3297D01*
G02X358106Y1368021I2J-3502D01*
G03X358240I67J188D01*
G02X359423Y1368226I1181J-3297D01*
G02X360747Y1367967I2J-3502D01*
G03X360899I76J185D01*
G02X362223Y1368226I1322J-3243D01*
G37*
G36*
G01X415198Y1349687D02*
G02X415452Y1350638I3477J-419D01*
G03Y1350794I-184J78D01*
G02X415172Y1352166I3223J1372D01*
G02X417978Y1355599I3503J0D01*
G03X418121Y1355713I-39J196D01*
G02X421315Y1357778I3194J-1438D01*
G01X421317D01*
G02X424818Y1354276I-1J-3502D01*
G02X424538Y1352904I-3503J0D01*
G03Y1352748I184J-78D01*
G02X424818Y1351376I-3223J-1372D01*
G02X424505Y1349928I-3502J-1D01*
G03X424499Y1349777I182J-83D01*
G02X424708Y1348586I-3294J-1192D01*
G02X424428Y1347214I-3503J0D01*
G03Y1347058I184J-78D01*
G02X424708Y1345686I-3223J-1372D01*
G02X421205Y1342184I-3503J1D01*
G01X421203D01*
G02X420507Y1342254I1J3502D01*
G03X420282Y1342132I-39J-196D01*
G02X420248Y1342052I-3208J1316D01*
G03Y1341894I184J-79D01*
G02X420530Y1340526I-3185J-1370D01*
G01Y1340523D01*
G02X413596I-3467J0D01*
G01Y1340526D01*
G02X413878Y1341894I3467J-2D01*
G03Y1342052I-184J79D01*
G02X413670Y1342707I3185J1372D01*
G02X413533Y1342704I-144J3465D01*
G02X412384Y1342900I0J3468D01*
G03X412252I-66J-189D01*
G02X411103Y1342704I-1149J3272D01*
G02Y1349640I0J3468D01*
G02X412252Y1349444I0J-3468D01*
G03X412384I66J189D01*
G02X413533Y1349640I1149J-3272D01*
G02X414682Y1349444I0J-3468D01*
G03X414814I66J189D01*
G02X415052Y1349518I1148J-3272D01*
G03X415198Y1349687I-53J193D01*
G37*
G36*
G01X1389662Y1349620D02*
G02X1390811Y1349425I3J-3467D01*
G03X1390943I66J189D01*
G02X1391354Y1349541I1146J-3273D01*
G01Y1349588D01*
G02X1391634Y1350960I3502J0D01*
G03Y1351116I-184J78D01*
G02X1391354Y1352487I3222J1372D01*
G01Y1352488D01*
G02X1394856Y1355990I3502J0D01*
G01X1394857D01*
G02X1397027Y1355236I-1J-3502D01*
G03X1397258Y1355224I124J157D01*
G02X1399119Y1355760I1862J-2967D01*
G01X1399122D01*
G02X1402624Y1352258I0J-3502D01*
G01Y1352257D01*
G02X1402344Y1350886I-3502J1D01*
G03Y1350730I184J-78D01*
G02X1402624Y1349358I-3222J-1372D01*
G02X1402344Y1347986I-3502J0D01*
G03Y1347830I184J-78D01*
G02X1402624Y1346459I-3222J-1372D01*
G01Y1346458D01*
G02X1399122Y1342956I-3502J0D01*
G01X1399120D01*
G02X1397123Y1343582I1J3502D01*
G01X1397122D01*
G03X1397009Y1343618I-114J-164D01*
G01X1397008D01*
G03X1396808Y1343418I0J-200D01*
G01Y1343414D01*
G02X1396528Y1342043I-3502J1D01*
G03Y1341887I184J-78D01*
G02X1396808Y1340516I-3222J-1372D01*
G01Y1340515D01*
G02X1389804I-3502J0D01*
G01Y1340516D01*
G02X1390084Y1341887I3502J-1D01*
G03Y1342043I-184J78D01*
G02X1389916Y1342536I3222J1373D01*
G03X1389719Y1342686I-194J-50D01*
G01X1389662D01*
G02X1388513Y1342881I-3J3467D01*
G03X1388381I-66J-189D01*
G02X1387236Y1342686I-1146J3272D01*
G01X1387232D01*
G02Y1349620I0J3467D01*
G01X1387236D01*
G02X1388381Y1349425I-1J-3467D01*
G03X1388513I66J189D01*
G02X1389662Y1349620I1146J-3272D01*
G37*
G36*
G01X380951Y1330308D02*
G02X382100Y1330113I3J-3467D01*
G03X382232I66J189D01*
G02X382643Y1330229I1146J-3273D01*
G02X382642Y1330274I3501J100D01*
G01Y1330278D01*
G02X382922Y1331648I3503J-2D01*
G03Y1331804I-184J78D01*
G02X382642Y1333176I3223J1372D01*
G02X383188Y1335053I3503J-1D01*
G03X383213Y1335208I-169J107D01*
G02X383108Y1336056I3398J851D01*
G02X385773Y1339457I3503J0D01*
G03X385890Y1339537I-47J194D01*
G02X388771Y1341048I2881J-1991D01*
G01X388773D01*
G02X392274Y1337546I-1J-3502D01*
G02X391973Y1336127I-3503J2D01*
G03Y1335965I183J-81D01*
G02X392274Y1334546I-3202J-1421D01*
G02X391711Y1332643I-3503J1D01*
G03X391686Y1332481I168J-109D01*
G02X391814Y1331546I-3375J-938D01*
G02X391464Y1330021I-3503J1D01*
G03X391459Y1329859I180J-87D01*
G02X391714Y1328546I-3248J-1312D01*
G02X388300Y1325045I-3502J0D01*
G01X388298D01*
G03X388152Y1324974I7J-200D01*
G01X387930Y1324713D01*
X387907Y1324630D01*
X387913Y1324588D01*
G02X387948Y1324092I-3432J-491D01*
G02X387666Y1322721I-3467J-1D01*
G03Y1322563I184J-79D01*
G02X387948Y1321195I-3185J-1370D01*
G01Y1321192D01*
G02X381014I-3467J0D01*
G01Y1321195D01*
G02X381296Y1322563I3467J-2D01*
G03Y1322721I-184J79D01*
G02X381088Y1323376I3185J1372D01*
G02X380952Y1323374I-119J3465D01*
G01X380950D01*
G02X379802Y1323569I-2J3467D01*
G03X379670I-66J-189D01*
G02X378525Y1323374I-1146J3272D01*
G01X378521D01*
G02Y1330308I0J3467D01*
G01X378525D01*
G02X379670Y1330113I-1J-3467D01*
G03X379802I66J189D01*
G02X380951Y1330308I1146J-3272D01*
G37*
G36*
G01X1357080Y1323354D02*
G02X1355931Y1323550I0J3468D01*
G03X1355799I-66J-189D01*
G02X1354650Y1323354I-1149J3272D01*
G02Y1330290I0J3468D01*
G02X1355799Y1330094I0J-3468D01*
G03X1355931I66J189D01*
G02X1357080Y1330290I1149J-3272D01*
G02X1358229Y1330094I0J-3468D01*
G03X1358361I66J189D01*
G02X1358772Y1330210I1146J-3273D01*
G01Y1330257D01*
G02X1359052Y1331629I3502J0D01*
G03Y1331785I-184J78D01*
G02X1358772Y1333157I3222J1372D01*
G02X1359052Y1334529I3502J0D01*
G03Y1334685I-184J78D01*
G02X1358772Y1336056I3222J1372D01*
G01Y1336057D01*
G02X1361459Y1339463I3502J0D01*
G03X1361576Y1339543I-47J194D01*
G02X1364440Y1341030I2865J-2016D01*
G02X1367942Y1337527I-1J-3503D01*
G01Y1337525D01*
G02X1367642Y1336108I-3502J1D01*
G03Y1335946I183J-81D01*
G02X1367942Y1334527I-3202J-1418D01*
G02X1367642Y1333108I-3502J-1D01*
G03Y1332946I183J-81D01*
G02X1367942Y1331527I-3202J-1418D01*
G02X1367593Y1330002I-3502J-1D01*
G03X1367587Y1329840I180J-88D01*
G02X1367842Y1328531I-3247J-1312D01*
G01Y1328527D01*
G02X1364563Y1325032I-3502J0D01*
G01X1364561D01*
G03X1364420Y1324959I14J-200D01*
G01X1364208Y1324699D01*
X1364186Y1324618D01*
X1364192Y1324576D01*
G02X1364226Y1324084I-3468J-487D01*
G02X1363946Y1322712I-3502J0D01*
G03Y1322556I184J-78D01*
G02X1364226Y1321185I-3222J-1372D01*
G01Y1321184D01*
G02X1357222I-3502J0D01*
G01Y1321185D01*
G02X1357502Y1322556I3502J-1D01*
G03Y1322712I-184J78D01*
G02X1357334Y1323205I3222J1373D01*
G03X1357137Y1323355I-194J-50D01*
G02X1357080Y1323354I-89J3466D01*
G37*
G36*
G01X284042Y1330163D02*
G02X284322Y1331533I3503J-2D01*
G03Y1331689I-184J78D01*
G02X284042Y1333061I3223J1372D01*
G02X287545Y1336564I3503J0D01*
G02X289716Y1335809I-1J-3503D01*
G03X289947Y1335797I124J157D01*
G02X291811Y1336334I1864J-2967D01*
G02X295314Y1332831I0J-3503D01*
G02X295034Y1331459I-3503J0D01*
G03Y1331303I184J-78D01*
G02X295314Y1329931I-3223J-1372D01*
G02X295034Y1328559I-3503J0D01*
G03Y1328403I184J-78D01*
G02X295314Y1327031I-3223J-1372D01*
G02X291811Y1323528I-3503J0D01*
G02X289967Y1324053I1J3503D01*
G01X289921Y1324082D01*
X289815Y1324085D01*
X289415Y1323871D01*
X289358Y1323780D01*
X289357Y1323727D01*
G02X289076Y1322471I-3466J116D01*
G03Y1322313I184J-79D01*
G02X289358Y1320945I-3185J-1370D01*
G01Y1320942D01*
G02X282424I-3467J0D01*
G01Y1320945D01*
G02X282706Y1322313I3467J-2D01*
G03Y1322471I-184J79D01*
G02X282473Y1323261I3186J1369D01*
G02X282352Y1323258I-146J3464D01*
G01X282350D01*
G02X281202Y1323454I1J3468D01*
G03X281070I-66J-189D01*
G02X279921Y1323258I-1149J3272D01*
G02Y1330194I0J3468D01*
G02X281070Y1329998I0J-3468D01*
G03X281202I66J189D01*
G02X282351Y1330194I1149J-3272D01*
G02X283500Y1329998I0J-3468D01*
G03X283632I66J189D01*
G02X284043Y1330114I1146J-3273D01*
G02X284042Y1330159I3501J100D01*
G01Y1330163D01*
G37*
G36*
G01X1258480Y1330174D02*
G02X1259629Y1329979I3J-3467D01*
G03X1259761I66J189D01*
G02X1260172Y1330095I1146J-3273D01*
G01Y1330142D01*
G02X1260452Y1331514I3502J0D01*
G03Y1331670I-184J78D01*
G02X1260172Y1333041I3222J1372D01*
G01Y1333042D01*
G02X1263674Y1336544I3502J0D01*
G01X1263675D01*
G02X1265845Y1335790I-1J-3502D01*
G03X1266076Y1335778I124J157D01*
G02X1267937Y1336314I1862J-2967D01*
G01X1267940D01*
G02X1271442Y1332812I0J-3502D01*
G01Y1332811D01*
G02X1271162Y1331440I-3502J1D01*
G03Y1331284I184J-78D01*
G02X1271442Y1329912I-3222J-1372D01*
G02X1271162Y1328540I-3502J0D01*
G03Y1328384I184J-78D01*
G02X1271442Y1327013I-3222J-1372D01*
G01Y1327012D01*
G02X1267940Y1323510I-3502J0D01*
G01X1267938D01*
G02X1266154Y1323999I1J3502D01*
G01X1266108Y1324026D01*
X1266003Y1324028D01*
X1265607Y1323810D01*
X1265552Y1323720D01*
X1265551Y1323667D01*
G02X1265273Y1322406I-3501J111D01*
G03X1265272Y1322250I184J-79D01*
G02X1265552Y1320879I-3222J-1372D01*
G01Y1320878D01*
G02X1258548I-3502J0D01*
G01Y1320879D01*
G02X1258828Y1322250I3502J-1D01*
G03Y1322406I-184J78D01*
G02X1258589Y1323241I3222J1374D01*
G02X1258481Y1323240I-86J3466D01*
G01X1258479D01*
G02X1257331Y1323435I-2J3467D01*
G03X1257199I-66J-189D01*
G02X1256054Y1323240I-1146J3272D01*
G01X1256050D01*
G02Y1330174I0J3467D01*
G01X1256054D01*
G02X1257199Y1329979I-1J-3467D01*
G03X1257331I66J189D01*
G02X1258480Y1330174I1146J-3272D01*
G37*
G36*
G01X316938Y1330135D02*
G02X317218Y1331505I3503J-2D01*
G03Y1331661I-184J78D01*
G02X316938Y1333033I3223J1372D01*
G02X320441Y1336536I3503J0D01*
G02X322612Y1335781I-1J-3503D01*
G03X322843Y1335769I124J157D01*
G02X324707Y1336306I1864J-2967D01*
G02X328210Y1332803I0J-3503D01*
G02X327930Y1331431I-3503J0D01*
G03Y1331275I184J-78D01*
G02X328210Y1329903I-3223J-1372D01*
G02X327930Y1328531I-3503J0D01*
G03Y1328375I184J-78D01*
G02X328210Y1327003I-3223J-1372D01*
G02X324707Y1323500I-3503J0D01*
G02X322884Y1324012I0J3503D01*
G01X322838Y1324040D01*
X322732Y1324043D01*
X322381Y1323853D01*
G03X322276Y1323684I95J-176D01*
G02X321996Y1322431I-3465J117D01*
G03Y1322273I184J-79D01*
G02X322278Y1320905I-3185J-1370D01*
G01Y1320902D01*
G02X315344I-3467J0D01*
G01Y1320905D01*
G02X315626Y1322273I3467J-2D01*
G03Y1322431I-184J79D01*
G02X315390Y1323233I3184J1373D01*
G02X315247Y1323230I-144J3465D01*
G02X314098Y1323426I0J3468D01*
G03X313966I-66J-189D01*
G02X312817Y1323230I-1149J3272D01*
G02Y1330166I0J3468D01*
G02X313966Y1329970I0J-3468D01*
G03X314098I66J189D01*
G02X315247Y1330166I1149J-3272D01*
G02X316396Y1329970I0J-3468D01*
G03X316528I66J189D01*
G02X316939Y1330086I1146J-3273D01*
G02X316938Y1330131I3501J100D01*
G01Y1330135D01*
G37*
G36*
G01X1291376Y1330146D02*
G02X1292525Y1329951I3J-3467D01*
G03X1292657I66J189D01*
G02X1293068Y1330067I1146J-3273D01*
G01Y1330114D01*
G02X1293348Y1331486I3502J0D01*
G03Y1331642I-184J78D01*
G02X1293068Y1333013I3222J1372D01*
G01Y1333014D01*
G02X1296570Y1336516I3502J0D01*
G01X1296571D01*
G02X1298741Y1335762I-1J-3502D01*
G03X1298972Y1335750I124J157D01*
G02X1300833Y1336286I1862J-2967D01*
G01X1300836D01*
G02X1304338Y1332784I0J-3502D01*
G01Y1332783D01*
G02X1304058Y1331412I-3502J1D01*
G03Y1331256I184J-78D01*
G02X1304338Y1329884I-3222J-1372D01*
G02X1304058Y1328512I-3502J0D01*
G03Y1328356I184J-78D01*
G02X1304338Y1326985I-3222J-1372D01*
G01Y1326984D01*
G02X1300836Y1323482I-3502J0D01*
G02X1299056Y1323968I0J3503D01*
G03X1298860Y1323972I-102J-172D01*
G01X1298512Y1323785D01*
X1298456Y1323697D01*
X1298453Y1323645D01*
G02X1298178Y1322462I-3497J189D01*
G03Y1322306I184J-78D01*
G02X1298458Y1320935I-3222J-1372D01*
G01Y1320934D01*
G02X1291454I-3502J0D01*
G01Y1320935D01*
G02X1291734Y1322306I3502J-1D01*
G03Y1322462I-184J78D01*
G02X1291509Y1323214I3222J1374D01*
G02X1291376Y1323212I-119J3465D01*
G02X1290227Y1323407I-3J3467D01*
G03X1290095I-66J-189D01*
G02X1288950Y1323212I-1146J3272D01*
G01X1288946D01*
G02Y1330146I0J3467D01*
G01X1288950D01*
G02X1290095Y1329951I-1J-3467D01*
G03X1290227I66J189D01*
G02X1291376Y1330146I1146J-3272D01*
G37*
G36*
G01X348151Y1330108D02*
G02X349300Y1329913I3J-3467D01*
G03X349432I66J189D01*
G02X349843Y1330029I1146J-3273D01*
G02X349842Y1330074I3501J100D01*
G01Y1330078D01*
G02X350122Y1331448I3503J-2D01*
G03Y1331604I-184J78D01*
G02X349842Y1332976I3223J1372D01*
G02X353345Y1336478I3503J-1D01*
G01X353346D01*
G02X355516Y1335724I-1J-3502D01*
G03X355747Y1335712I124J157D01*
G02X357611Y1336248I1862J-2967D01*
G02X361114Y1332746I1J-3502D01*
G02X360834Y1331374I-3503J0D01*
G03Y1331218I184J-78D01*
G02X361114Y1329846I-3223J-1372D01*
G02X360834Y1328474I-3503J0D01*
G03Y1328318I184J-78D01*
G02X361114Y1326946I-3223J-1372D01*
G02X357611Y1323444I-3503J1D01*
G01X357609D01*
G02X355729Y1323992I1J3502D01*
G01X355683Y1324021D01*
X355578Y1324026D01*
X355222Y1323842D01*
G03X355114Y1323675I92J-178D01*
G01Y1323674D01*
G02X354836Y1322471I-3463J167D01*
G03Y1322313I184J-79D01*
G02X355118Y1320945I-3185J-1370D01*
G01Y1320942D01*
G02X348184I-3467J0D01*
G01Y1320945D01*
G02X348466Y1322313I3467J-2D01*
G03Y1322471I-184J79D01*
G02X348248Y1323175I3185J1372D01*
G02X348151Y1323174I-84J3466D01*
G02X347002Y1323369I-3J3467D01*
G03X346870I-66J-189D01*
G02X345725Y1323174I-1146J3272D01*
G01X345721D01*
G02Y1330108I0J3467D01*
G01X345725D01*
G02X346870Y1329913I-1J-3467D01*
G03X347002I66J189D01*
G02X348151Y1330108I1146J-3272D01*
G37*
G36*
G01X1326252Y1331585D02*
G02X1325972Y1332957I3222J1372D01*
G02X1329474Y1336460I3502J1D01*
G02X1331645Y1335705I-1J-3503D01*
G03X1331876Y1335693I124J157D01*
G02X1333740Y1336230I1864J-2967D01*
G02X1337242Y1332727I-1J-3503D01*
G01Y1332726D01*
G02X1336962Y1331355I-3502J1D01*
G03Y1331199I184J-78D01*
G02X1337242Y1329827I-3222J-1372D01*
G02X1336962Y1328455I-3502J0D01*
G03Y1328299I184J-78D01*
G02X1337242Y1326927I-3222J-1372D01*
G02X1333740Y1323424I-3502J-1D01*
G02X1331971Y1323904I1J3503D01*
G01X1331926Y1323930D01*
X1331823Y1323932D01*
X1331476Y1323750D01*
G03X1331370Y1323587I94J-177D01*
G02X1331099Y1322462I-3494J247D01*
G03X1331098Y1322306I184J-79D01*
G02X1331378Y1320935I-3222J-1372D01*
G01Y1320934D01*
G02X1324374I-3502J0D01*
G01Y1320935D01*
G02X1324654Y1322306I3502J-1D01*
G03X1324653Y1322462I-185J77D01*
G02X1324439Y1323158I3223J1372D01*
G02X1324280Y1323154I-167J3464D01*
G02X1323131Y1323350I0J3468D01*
G03X1322999I-66J-189D01*
G02X1321850Y1323154I-1149J3272D01*
G02Y1330090I0J3468D01*
G02X1322999Y1329894I0J-3468D01*
G03X1323131I66J189D01*
G02X1324280Y1330090I1149J-3272D01*
G02X1325429Y1329894I0J-3468D01*
G03X1325561I66J189D01*
G02X1325972Y1330010I1146J-3273D01*
G01Y1330057D01*
G02X1326252Y1331429I3502J0D01*
G03Y1331585I-184J78D01*
G37*
G36*
G01X1521562Y714544D02*
G02X1521842Y715916I3502J0D01*
G03Y716072I-184J78D01*
G02X1521562Y717443I3222J1372D01*
G01Y717444D01*
G02X1528566I3502J0D01*
G01Y717443D01*
G02X1528286Y716072I-3502J1D01*
G03X1528287Y715916I185J-77D01*
G02X1528506Y715190I-3224J-1369D01*
G03X1528662Y715031I197J37D01*
G02X1529106Y714908I-702J-3396D01*
G03X1529238I66J189D01*
G02X1530387Y715104I1149J-3272D01*
G02Y708168I0J-3468D01*
G02X1529238Y708364I0J3468D01*
G03X1529106I-66J-189D01*
G02X1527957Y708168I-1149J3272D01*
G02X1526808Y708364I0J3468D01*
G03X1526676I-66J-189D01*
G02X1526265Y708248I-1146J3273D01*
G02X1526266Y708203I-3501J-100D01*
G01Y708199D01*
G02X1525986Y706829I-3503J2D01*
G03Y706673I184J-78D01*
G02X1526266Y705301I-3223J-1372D01*
G02X1522763Y701798I-3503J0D01*
G02X1520592Y702553I1J3503D01*
G03X1520361Y702565I-124J-157D01*
G02X1518497Y702028I-1864J2967D01*
G02X1514994Y705531I0J3503D01*
G02X1515274Y706903I3503J0D01*
G03Y707059I-184J78D01*
G02X1514994Y708431I3223J1372D01*
G02X1515274Y709803I3503J0D01*
G03Y709959I-184J78D01*
G02X1514994Y711331I3223J1372D01*
G02X1518497Y714834I3503J0D01*
G02X1521298Y713434I0J-3502D01*
G03X1521415Y713359I160J120D01*
G02X1521455Y713350I-749J-3421D01*
G01X1521615Y713519D01*
G03X1521664Y713704I-146J138D01*
G02X1521562Y714544I3400J839D01*
G37*
G36*
G01X1488762D02*
G02X1489042Y715916I3502J0D01*
G03Y716072I-184J78D01*
G02X1488762Y717443I3222J1372D01*
G01Y717444D01*
G02X1495766I3502J0D01*
G01Y717443D01*
G02X1495486Y716072I-3502J1D01*
G03X1495487Y715916I185J-77D01*
G02X1495706Y715190I-3224J-1369D01*
G03X1495862Y715031I197J37D01*
G02X1496306Y714908I-702J-3396D01*
G03X1496438I66J189D01*
G02X1497587Y715104I1149J-3272D01*
G02Y708168I0J-3468D01*
G02X1496438Y708364I0J3468D01*
G03X1496306I-66J-189D01*
G02X1495157Y708168I-1149J3272D01*
G02X1494008Y708364I0J3468D01*
G03X1493876I-66J-189D01*
G02X1493465Y708248I-1146J3273D01*
G02X1493466Y708203I-3501J-100D01*
G01Y708199D01*
G02X1493186Y706829I-3503J2D01*
G03Y706673I184J-78D01*
G02X1493466Y705301I-3223J-1372D01*
G02X1489963Y701798I-3503J0D01*
G02X1487792Y702553I1J3503D01*
G03X1487561Y702565I-124J-157D01*
G02X1485697Y702028I-1864J2967D01*
G02X1482194Y705531I0J3503D01*
G02X1482474Y706903I3503J0D01*
G03Y707059I-184J78D01*
G02X1482194Y708431I3223J1372D01*
G02X1482474Y709803I3503J0D01*
G03Y709959I-184J78D01*
G02X1482194Y711331I3223J1372D01*
G02X1485697Y714834I3503J0D01*
G02X1488498Y713434I0J-3502D01*
G03X1488615Y713359I160J120D01*
G02X1488655Y713350I-749J-3421D01*
G01X1488815Y713519D01*
G03X1488864Y713704I-146J138D01*
G02X1488762Y714544I3400J839D01*
G37*
G36*
G01X312410Y714500D02*
G02X312690Y715872I3502J0D01*
G03Y716028I-184J78D01*
G02X312410Y717399I3222J1372D01*
G01Y717400D01*
G02X319414I3502J0D01*
G01Y717399D01*
G02X319134Y716028I-3502J1D01*
G03X319135Y715872I185J-77D01*
G02X319346Y715189I-3224J-1370D01*
G03X319502Y715033I196J40D01*
G02X319954Y714908I-696J-3397D01*
G03X320086I66J189D01*
G02X321235Y715104I1149J-3272D01*
G02Y708168I0J-3468D01*
G02X320086Y708364I0J3468D01*
G03X319954I-66J-189D01*
G02X318805Y708168I-1149J3272D01*
G02X317656Y708364I0J3468D01*
G03X317524I-66J-189D01*
G02X317113Y708248I-1146J3273D01*
G02X317114Y708203I-3501J-100D01*
G01Y708199D01*
G02X316834Y706829I-3503J2D01*
G03Y706673I184J-78D01*
G02X317114Y705301I-3223J-1372D01*
G02X316143Y702881I-3503J1D01*
G03X316089Y702719I144J-138D01*
G02X316114Y702301I-3478J-418D01*
G02X313343Y698876I-3502J0D01*
G03X313226Y698802I42J-196D01*
G02X310445Y697428I-2782J2129D01*
G02X306942Y700931I0J3503D01*
G02X307243Y702350I3503J-2D01*
G03Y702512I-183J81D01*
G02X306942Y703931I3202J1421D01*
G02X307913Y706351I3503J-1D01*
G03X307967Y706513I-144J138D01*
G02X307942Y706931I3478J418D01*
G02X308292Y708456I3503J-1D01*
G03X308297Y708618I-180J87D01*
G02X308042Y709931I3248J1312D01*
G02X311545Y713434I3503J0D01*
G02X312019Y713401I-6J-3503D01*
G01X312067Y713394D01*
X312157Y713426D01*
X312415Y713696D01*
G03X312467Y713869I-145J138D01*
G01Y713870D01*
G02X312410Y714500I3445J629D01*
G37*
G36*
G01X1455274Y714194D02*
G02X1455554Y715566I3503J0D01*
G03Y715722I-184J78D01*
G02X1455274Y717094I3223J1372D01*
G02X1462280I3503J0D01*
G02X1462000Y715723I-3503J1D01*
G03Y715566I184J-78D01*
G02X1462059Y715418I-3223J-1371D01*
G03X1462235Y715288I188J70D01*
G02X1463194Y715098I-188J-3462D01*
G03X1463326I66J189D01*
G02X1464475Y715294I1149J-3272D01*
G02Y708358I0J-3468D01*
G02X1463326Y708554I0J3468D01*
G03X1463194I-66J-189D01*
G02X1462045Y708358I-1149J3272D01*
G02X1460896Y708554I0J3468D01*
G03X1460764I-66J-189D01*
G02X1460530Y708481I-1149J3272D01*
G03X1460383Y708283I53J-193D01*
G02X1460384Y708201I-3502J-84D01*
G02X1460104Y706829I-3503J0D01*
G03Y706673I184J-78D01*
G02X1460384Y705301I-3223J-1372D01*
G02X1458218Y702064I-3502J0D01*
G03X1458101Y701828I76J-185D01*
G02X1458218Y700932I-3386J-898D01*
G01Y700931D01*
G02X1451212I-3503J0D01*
G02X1451371Y701972I3503J-2D01*
G03X1451362Y702115I-191J60D01*
G01X1451313Y702222D01*
G03X1451211Y702323I-182J-82D01*
G02X1449112Y705531I1403J3209D01*
G02X1451314Y708783I3502J0D01*
G03X1451433Y709021I-74J186D01*
G02X1451312Y709931I3382J913D01*
G02X1454814Y713434I3503J0D01*
G01X1454816D01*
G02X1454883Y713433I-19J-3503D01*
G01X1454926Y713432D01*
X1455005Y713465D01*
X1455237Y713716D01*
G03X1455290Y713870I-146J136D01*
G02X1455274Y714194I3486J335D01*
G37*
G36*
G01X378310Y714157D02*
Y714161D01*
G02X378590Y715532I3502J-1D01*
G03Y715688I-184J78D01*
G02X378310Y717059I3222J1372D01*
G01Y717060D01*
G02X385314I3502J0D01*
G01Y717059D01*
G02X385034Y715688I-3502J1D01*
G03Y715532I184J-78D01*
G02X385207Y715020I-3221J-1374D01*
G03X385374Y714871I194J49D01*
G02X386054Y714708I-464J-3436D01*
G03X386186I66J189D01*
G02X387335Y714904I1149J-3272D01*
G02Y707968I0J-3468D01*
G02X386186Y708164I0J3468D01*
G03X386054I-66J-189D01*
G02X384905Y707968I-1149J3272D01*
G02X383756Y708164I0J3468D01*
G03X383624I-66J-189D01*
G02X383213Y708048I-1146J3273D01*
G02X383214Y708003I-3501J-100D01*
G01Y707999D01*
G02X382934Y706629I-3503J2D01*
G03Y706473I184J-78D01*
G02X383214Y705101I-3223J-1372D01*
G02X379711Y701598I-3503J0D01*
G02X377540Y702353I1J3503D01*
G03X377309Y702365I-124J-157D01*
G02X375445Y701828I-1864J2967D01*
G02X371942Y705331I0J3503D01*
G02X372222Y706703I3503J0D01*
G03Y706859I-184J78D01*
G02X371942Y708231I3223J1372D01*
G02X372222Y709603I3503J0D01*
G03Y709759I-184J78D01*
G02X371942Y711131I3223J1372D01*
G02X375445Y714634I3503J0D01*
G02X377657Y713847I0J-3502D01*
G01X377702Y713810D01*
X377816Y713796D01*
X378196Y713977D01*
G03X378310Y714157I-86J181D01*
G37*
G36*
G01X345172Y715688D02*
G02X344892Y717060I3223J1372D01*
G02X351898I3503J0D01*
G02X351618Y715688I-3503J0D01*
G03Y715532I184J-78D01*
G02X351832Y714835I-3223J-1371D01*
G02X351862Y714836I130J-3464D01*
G01X351868D01*
G02X353014Y714640I-3J-3468D01*
G03X353146I66J189D01*
G02X354295Y714836I1149J-3272D01*
G02Y707900I0J-3468D01*
G02X353146Y708096I0J3468D01*
G03X353014I-66J-189D01*
G02X351865Y707900I-1149J3272D01*
G02X350716Y708096I0J3468D01*
G03X350584I-66J-189D01*
G02X350173Y707980I-1146J3273D01*
G02X350174Y707935I-3501J-100D01*
G01Y707931D01*
G02X349894Y706561I-3503J2D01*
G03Y706405I184J-78D01*
G02X350174Y705033I-3223J-1372D01*
G02X346671Y701530I-3503J0D01*
G02X344500Y702285I1J3503D01*
G03X344269Y702297I-124J-157D01*
G02X342405Y701760I-1864J2967D01*
G02X338902Y705263I0J3503D01*
G02X339182Y706635I3503J0D01*
G03Y706791I-184J78D01*
G02X338902Y708163I3223J1372D01*
G02X339182Y709535I3503J0D01*
G03Y709691I-184J78D01*
G02X338902Y711063I3223J1372D01*
G02X342405Y714566I3503J0D01*
G02X344283Y714019I-2J-3503D01*
G01X344328Y713990D01*
X344434Y713986D01*
X344789Y714169D01*
G03X344897Y714337I-92J178D01*
G02X345172Y715532I3498J-176D01*
G03Y715688I-184J78D01*
G37*
G36*
G01X411210Y696540D02*
G02X411490Y697912I3502J0D01*
G03Y698068I-184J78D01*
G02X411210Y699439I3222J1372D01*
G01Y699440D01*
G02X418214I3502J0D01*
G01Y699439D01*
G02X417934Y698068I-3502J1D01*
G03X417935Y697912I185J-77D01*
G02X418145Y697237I-3223J-1373D01*
G03X418317Y697079I196J40D01*
G02X419054Y696908I-411J-3443D01*
G03X419186I66J189D01*
G02X420335Y697104I1149J-3272D01*
G02Y690168I0J-3468D01*
G02X419186Y690364I0J3468D01*
G03X419054I-66J-189D01*
G02X417905Y690168I-1149J3272D01*
G02X416756Y690364I0J3468D01*
G03X416624I-66J-189D01*
G02X416213Y690248I-1146J3273D01*
G02X416214Y690203I-3501J-100D01*
G01Y690199D01*
G02X415934Y688829I-3503J2D01*
G03Y688673I184J-78D01*
G02X416214Y687301I-3223J-1372D01*
G02X412711Y683798I-3503J0D01*
G02X410540Y684553I1J3503D01*
G03X410309Y684565I-124J-157D01*
G02X408445Y684028I-1864J2967D01*
G02X404942Y687531I0J3503D01*
G02X405222Y688903I3503J0D01*
G03Y689059I-184J78D01*
G02X404942Y690431I3223J1372D01*
G02X405222Y691803I3503J0D01*
G03Y691959I-184J78D01*
G02X404942Y693331I3223J1372D01*
G02X408445Y696834I3503J0D01*
G02X410567Y696116I-3J-3502D01*
G01X410569D01*
Y696115D01*
G03X410780Y696097I120J160D01*
G01X411102Y696262D01*
G03X411211Y696445I-91J178D01*
G02X411210Y696540I3501J84D01*
G37*
G36*
G01X1429187Y688892D02*
G02X1428038Y689087I-3J3467D01*
G03X1427906I-66J-189D01*
G02X1427612Y688998I-1151J3271D01*
G03X1427461Y688794I49J-194D01*
G02X1427466Y688624I-3497J-188D01*
G02X1427186Y687252I-3503J0D01*
G03Y687096I184J-78D01*
G02X1427466Y685724I-3223J-1372D01*
G02X1423963Y682222I-3503J1D01*
G01X1423962D01*
G02X1421792Y682976I1J3502D01*
G03X1421561Y682988I-124J-157D01*
G02X1419697Y682452I-1862J2967D01*
G02X1416194Y685954I-1J3502D01*
G02X1416474Y687326I3503J0D01*
G03Y687482I-184J78D01*
G02X1416194Y688854I3223J1372D01*
G02X1416474Y690226I3503J0D01*
G03Y690382I-184J78D01*
G02X1416194Y691754I3223J1372D01*
G02X1419697Y695256I3503J-1D01*
G02X1422498Y693857I0J-3504D01*
G03X1422615Y693782I160J120D01*
G02X1422652Y693774I-722J-3427D01*
G01X1422812Y693943D01*
G03X1422861Y694127I-145J137D01*
G02X1422762Y694954I3405J827D01*
G01Y694955D01*
G02X1423042Y696326I3502J-1D01*
G03Y696482I-184J78D01*
G02X1422762Y697853I3222J1372D01*
G01Y697854D01*
G02X1429766I3502J0D01*
G01Y697853D01*
G02X1429486Y696482I-3502J1D01*
G03Y696326I184J-78D01*
G02X1429631Y695916I-3223J-1370D01*
G03X1429789Y695773I193J54D01*
G02X1430336Y695631I-595J-3416D01*
G03X1430468I66J189D01*
G02X1431613Y695826I1146J-3272D01*
G01X1431617D01*
G02Y688892I0J-3467D01*
G01X1431613D01*
G02X1430468Y689087I1J3467D01*
G03X1430336I-66J-189D01*
G02X1429187Y688892I-1146J3272D01*
G37*
G36*
G01X286035Y688026D02*
G02X284886Y688221I-3J3467D01*
G03X284754I-66J-189D01*
G02X284343Y688105I-1146J3273D01*
G02X284344Y688052I-3501J-93D01*
G01Y688050D01*
G02X284064Y686679I-3503J1D01*
G03Y686523I184J-78D01*
G02X284344Y685151I-3223J-1372D01*
G02X280841Y681648I-3503J0D01*
G02X278670Y682403I1J3503D01*
G03X278439Y682415I-124J-157D01*
G02X276575Y681878I-1864J2967D01*
G02X273072Y685381I0J3503D01*
G02X273352Y686753I3503J0D01*
G03Y686909I-184J78D01*
G02X273072Y688281I3223J1372D01*
G02X273352Y689653I3503J0D01*
G03Y689809I-184J78D01*
G02X273072Y691181I3223J1372D01*
G02X276575Y694684I3503J0D01*
G02X278885Y693814I0J-3502D01*
G01X278930Y693774D01*
X279050Y693758D01*
X279437Y693949D01*
G03X279548Y694142I-88J179D01*
G02X279540Y694380I3494J237D01*
G02X279820Y695752I3502J0D01*
G03Y695908I-184J78D01*
G02X279540Y697279I3222J1372D01*
G01Y697280D01*
G02X286544I3502J0D01*
G01Y697279D01*
G02X286264Y695908I-3502J1D01*
G03Y695752I184J-78D01*
G02X286477Y695066I-3221J-1376D01*
G03X286638Y694908I196J39D01*
G02X287184Y694765I-603J-3415D01*
G03X287316I66J189D01*
G02X288461Y694960I1146J-3272D01*
G01X288465D01*
G02Y688026I0J-3467D01*
G01X288461D01*
G02X287316Y688221I1J3467D01*
G03X287184I-66J-189D01*
G02X286035Y688026I-1146J3272D01*
G37*
G36*
G01X1554692Y692501D02*
G02X1554992Y693920I3502J1D01*
G03Y694082I-183J81D01*
G02X1554692Y695499I3202J1418D01*
G01Y695501D01*
G02X1561696I3502J0D01*
G01Y695499D01*
G02X1561396Y694082I-3502J1D01*
G03Y693920I183J-81D01*
G02X1561616Y693249I-3201J-1421D01*
G03X1561772Y693095I196J42D01*
G02X1562236Y692968I-681J-3400D01*
G03X1562368I66J189D01*
G02X1563517Y693164I1149J-3272D01*
G02Y686228I0J-3468D01*
G02X1562368Y686424I0J3468D01*
G03X1562236I-66J-189D01*
G02X1561087Y686228I-1149J3272D01*
G02X1559938Y686424I0J3468D01*
G03X1559806I-66J-189D01*
G02X1559395Y686308I-1146J3273D01*
G02X1559396Y686263I-3501J-100D01*
G01Y686259D01*
G02X1559116Y684889I-3503J2D01*
G03Y684733I184J-78D01*
G02X1559396Y683361I-3223J-1372D01*
G02X1559161Y682101I-3503J1D01*
G03X1559168Y681940I186J-73D01*
G02X1559530Y680391I-3141J-1551D01*
G02X1556581Y676933I-3502J0D01*
G03X1556453Y676856I32J-198D01*
G02X1553657Y675462I-2797J2109D01*
G02X1550154Y678965I0J3503D01*
G02X1550455Y680384I3503J-2D01*
G03Y680546I-183J81D01*
G02X1550154Y681965I3202J1421D01*
G02X1550494Y683470I3503J0D01*
G03X1550498Y683634I-180J86D01*
G02X1550224Y684991I3229J1358D01*
G02X1550574Y686516I3503J-1D01*
G03X1550579Y686678I-180J87D01*
G02X1550324Y687991I3248J1312D01*
G02X1554292Y691463I3503J0D01*
G01X1554340Y691456D01*
X1554429Y691487D01*
X1554686Y691752D01*
G03X1554739Y691925I-144J139D01*
G02X1554692Y692501I3455J572D01*
G37*
G36*
G01X443990Y673168D02*
G02X443710Y674539I3222J1372D01*
G01Y674540D01*
G02X450714I3502J0D01*
G01Y674539D01*
G02X450434Y673168I-3502J1D01*
G03X450435Y673012I185J-77D01*
G02X450575Y672618I-3225J-1368D01*
G03X450742Y672476I192J56D01*
G02X451454Y672308I-436J-3440D01*
G03X451586I66J189D01*
G02X452735Y672504I1149J-3272D01*
G02Y665568I0J-3468D01*
G02X451586Y665764I0J3468D01*
G03X451454I-66J-189D01*
G02X450305Y665568I-1149J3272D01*
G02X449156Y665764I0J3468D01*
G03X449024I-66J-189D01*
G02X448613Y665648I-1146J3273D01*
G02X448614Y665603I-3501J-100D01*
G01Y665599D01*
G02X448334Y664229I-3503J2D01*
G03Y664073I184J-78D01*
G02X448614Y662701I-3223J-1372D01*
G02X445111Y659198I-3503J0D01*
G02X442940Y659953I1J3503D01*
G03X442709Y659965I-124J-157D01*
G02X440845Y659428I-1864J2967D01*
G02X437342Y662931I0J3503D01*
G02X437622Y664303I3503J0D01*
G03Y664459I-184J78D01*
G02X437342Y665831I3223J1372D01*
G02X437622Y667203I3503J0D01*
G03Y667359I-184J78D01*
G02X437342Y668731I3223J1372D01*
G02X440845Y672234I3503J0D01*
G02X443057Y671445I-2J-3502D01*
G01X443059D01*
Y671444D01*
G03X443267Y671418I125J156D01*
G01X443594Y671567D01*
G03X443711Y671743I-83J182D01*
G01Y671744D01*
G02X443990Y673012I3501J-106D01*
G03Y673168I-184J78D01*
G37*
G36*
G01X1396557Y656012D02*
G02X1395408Y656207I-3J3467D01*
G03X1395276I-66J-189D01*
G02X1394865Y656091I-1146J3273D01*
G02X1394866Y656046I-3501J-100D01*
G01Y656042D01*
G02X1394586Y654672I-3503J2D01*
G03Y654516I184J-78D01*
G02X1394866Y653144I-3223J-1372D01*
G02X1391363Y649642I-3503J1D01*
G01X1391362D01*
G02X1389192Y650396I1J3502D01*
G03X1388961Y650408I-124J-157D01*
G02X1387097Y649872I-1862J2967D01*
G02X1383594Y653374I-1J3502D01*
G02X1383874Y654746I3503J0D01*
G03Y654902I-184J78D01*
G02X1383594Y656274I3223J1372D01*
G02X1383874Y657646I3503J0D01*
G03Y657802I-184J78D01*
G02X1383594Y659174I3223J1372D01*
G02X1387097Y662676I3503J-1D01*
G02X1389897Y661278I0J-3503D01*
G03X1390016Y661202I160J120D01*
G02X1390055Y661194I-684J-3435D01*
G01X1390214Y661362D01*
G03X1390263Y661547I-145J138D01*
G02X1390162Y662384I3401J835D01*
G02X1390442Y663756I3502J0D01*
G03Y663912I-184J78D01*
G02X1390162Y665283I3222J1372D01*
G01Y665284D01*
G02X1397166I3502J0D01*
G01Y665283D01*
G02X1396886Y663912I-3502J1D01*
G03Y663756I184J-78D01*
G02X1397105Y663033I-3223J-1371D01*
G03X1397261Y662874I197J37D01*
G02X1397706Y662751I-699J-3396D01*
G03X1397838I66J189D01*
G02X1398983Y662946I1146J-3272D01*
G01X1398987D01*
G02Y656012I0J-3467D01*
G01X1398983D01*
G02X1397838Y656207I1J3467D01*
G03X1397706I-66J-189D01*
G02X1396557Y656012I-1146J3272D01*
G37*
G36*
G01X253305Y653778D02*
G02X252156Y653973I-3J3467D01*
G03X252024I-66J-189D01*
G02X251613Y653857I-1146J3273D01*
G02X251614Y653812I-3501J-100D01*
G01Y653808D01*
G02X251334Y652438I-3503J2D01*
G03Y652282I184J-78D01*
G02X251614Y650910I-3223J-1372D01*
G02X248111Y647408I-3503J1D01*
G01X248110D01*
G02X245940Y648162I1J3502D01*
G03X245709Y648174I-124J-157D01*
G02X243845Y647638I-1862J2967D01*
G02X240342Y651140I-1J3502D01*
G02X240622Y652512I3503J0D01*
G03Y652668I-184J78D01*
G02X240342Y654040I3223J1372D01*
G02X240622Y655412I3503J0D01*
G03Y655568I-184J78D01*
G02X240342Y656940I3223J1372D01*
G02X243845Y660442I3503J-1D01*
G01X243846D01*
G02X246158Y659570I0J-3502D01*
G01X246204Y659529D01*
X246324Y659514D01*
X246711Y659708D01*
G03X246821Y659902I-89J179D01*
G02X246810Y660180I3491J277D01*
G02X247090Y661552I3502J0D01*
G03Y661708I-184J78D01*
G02X246810Y663079I3222J1372D01*
G01Y663080D01*
G02X253814I3502J0D01*
G01Y663079D01*
G02X253534Y661708I-3502J1D01*
G03X253535Y661552I185J-77D01*
G02X253756Y660818I-3223J-1371D01*
G03X253917Y660658I197J37D01*
G02X254454Y660517I-609J-3414D01*
G03X254586I66J189D01*
G02X255731Y660712I1146J-3272D01*
G01X255735D01*
G02Y653778I0J-3467D01*
G01X255731D01*
G02X254586Y653973I1J3467D01*
G03X254454I-66J-189D01*
G02X253305Y653778I-1146J3272D01*
G37*
G36*
G01X1593857Y652460D02*
G02X1592708Y652655I-3J3467D01*
G03X1592576I-66J-189D01*
G02X1592165Y652539I-1146J3273D01*
G02X1592166Y652494I-3501J-100D01*
G01Y652490D01*
G02X1591886Y651120I-3503J2D01*
G03Y650964I184J-78D01*
G02X1592166Y649592I-3223J-1372D01*
G02X1588663Y646090I-3503J1D01*
G01X1588662D01*
G02X1586492Y646844I1J3502D01*
G03X1586261Y646856I-124J-157D01*
G02X1584397Y646320I-1862J2967D01*
G02X1580894Y649822I-1J3502D01*
G02X1581174Y651194I3503J0D01*
G03Y651350I-184J78D01*
G02X1580894Y652722I3223J1372D01*
G02X1581174Y654094I3503J0D01*
G03Y654250I-184J78D01*
G02X1580894Y655622I3223J1372D01*
G02X1584397Y659124I3503J-1D01*
G02X1587198Y657726I1J-3504D01*
G03X1587316Y657650I160J119D01*
G02X1587330Y657647I-727J-3426D01*
G01X1587490Y657813D01*
G03X1587542Y657994I-143J139D01*
G02X1587462Y658741I3422J744D01*
G02X1587762Y660160I3502J1D01*
G03Y660322I-183J81D01*
G02X1587462Y661739I3202J1418D01*
G01Y661741D01*
G02X1594466I3502J0D01*
G01Y661739D01*
G02X1594166Y660322I-3502J1D01*
G03Y660160I183J-81D01*
G02X1594387Y659480I-3203J-1417D01*
G03X1594543Y659326I196J42D01*
G02X1595006Y659199I-684J-3400D01*
G03X1595138I66J189D01*
G02X1596283Y659394I1146J-3272D01*
G01X1596287D01*
G02Y652460I0J-3467D01*
G01X1596283D01*
G02X1595138Y652655I1J3467D01*
G03X1595006I-66J-189D01*
G02X1593857Y652460I-1146J3272D01*
G37*
G36*
G01X1454046Y653872D02*
G02X1455229Y653667I2J-3502D01*
G03X1455363I67J188D01*
G02X1456546Y653872I1181J-3297D01*
G02X1457918Y653592I0J-3502D01*
G03X1458074I78J184D01*
G02X1459445Y653872I1372J-3222D01*
G01X1459446D01*
G02X1462948Y650370I0J-3502D01*
G01Y650365D01*
G02X1462701Y649077I-3502J4D01*
G03X1462699Y648936I186J-73D01*
G02X1462898Y647770I-3303J-1164D01*
G02X1462693Y646587I-3502J-2D01*
G03Y646453I188J-67D01*
G02X1462898Y645273I-3297J-1181D01*
G01Y645270D01*
G02X1459396Y641768I-3502J0D01*
G01X1459395D01*
G02X1458024Y642048I1J3502D01*
G03X1457868I-78J-184D01*
G02X1456496Y641768I-1372J3222D01*
G02X1455313Y641973I-2J3502D01*
G03X1455179I-67J-188D01*
G02X1453996Y641768I-1181J3297D01*
G02X1452813Y641973I-2J3502D01*
G03X1452679I-67J-188D01*
G02X1451496Y641768I-1181J3297D01*
G02X1450313Y641973I-2J3502D01*
G03X1450179I-67J-188D01*
G02X1448996Y641768I-1181J3297D01*
G02X1447757Y641994I-1J3502D01*
G03X1447615I-71J-187D01*
G02X1446376Y641768I-1238J3276D01*
G02X1445193Y641973I-2J3502D01*
G03X1445059I-67J-188D01*
G02X1443879Y641768I-1181J3297D01*
G01X1443876D01*
G02X1440374Y645270I0J3502D01*
G01Y645273D01*
G02X1440579Y646453I3502J-1D01*
G03Y646587I-188J67D01*
G02X1440374Y647770I3297J1181D01*
G02X1440621Y649063I3502J1D01*
G03X1440623Y649204I-186J73D01*
G02X1440424Y650366I3303J1164D01*
G01Y650370D01*
G02X1443926Y653872I3502J0D01*
G01X1443929D01*
G02X1445109Y653667I-1J-3502D01*
G03X1445243I67J188D01*
G02X1446426Y653872I1181J-3297D01*
G02X1447665Y653646I1J-3502D01*
G03X1447807I71J187D01*
G02X1449046Y653872I1238J-3276D01*
G02X1450229Y653667I2J-3502D01*
G03X1450363I67J188D01*
G02X1451546Y653872I1181J-3297D01*
G02X1452729Y653667I2J-3502D01*
G03X1452863I67J188D01*
G02X1454046Y653872I1181J-3297D01*
G37*
G36*
G01X476590Y646768D02*
G02X476310Y648139I3222J1372D01*
G01Y648140D01*
G02X483314I3502J0D01*
G01Y648139D01*
G02X483034Y646768I-3502J1D01*
G03X483035Y646612I185J-77D01*
G02X483202Y646120I-3224J-1369D01*
G03X483369Y645972I194J50D01*
G02X484054Y645808I-461J-3437D01*
G03X484186I66J189D01*
G02X485335Y646004I1149J-3272D01*
G02Y639068I0J-3468D01*
G02X484186Y639264I0J3468D01*
G03X484054I-66J-189D01*
G02X482905Y639068I-1149J3272D01*
G02X481756Y639264I0J3468D01*
G03X481624I-66J-189D01*
G02X481213Y639148I-1146J3273D01*
G02X481214Y639103I-3501J-100D01*
G01Y639099D01*
G02X480934Y637729I-3503J2D01*
G03Y637573I184J-78D01*
G02X481214Y636201I-3223J-1372D01*
G02X477711Y632698I-3503J0D01*
G02X475540Y633453I1J3503D01*
G03X475309Y633465I-124J-157D01*
G02X473445Y632928I-1864J2967D01*
G02X469942Y636431I0J3503D01*
G02X470222Y637803I3503J0D01*
G03Y637959I-184J78D01*
G02X469942Y639331I3223J1372D01*
G02X470222Y640703I3503J0D01*
G03Y640859I-184J78D01*
G02X469942Y642231I3223J1372D01*
G02X473445Y645734I3503J0D01*
G02X475657Y644947I0J-3502D01*
G03X475869Y644921I127J155D01*
G01X476196Y645075D01*
G03X476310Y645255I-86J181D01*
G02X476590Y646612I3502J-15D01*
G03Y646768I-184J78D01*
G37*
G36*
G01X350095Y649556D02*
G02X351278Y649351I2J-3502D01*
G03X351412I67J188D01*
G02X352595Y649556I1181J-3297D01*
G02X353774Y649352I1J-3502D01*
G03X353915Y649354I68J188D01*
G02X355195Y649596I1279J-3260D01*
G02X358698Y646094I1J-3502D01*
G02X358517Y644986I-3502J3D01*
G03X358522Y644848I190J-62D01*
G02X358778Y643534I-3247J-1315D01*
G02X358572Y642352I-3503J2D01*
G03Y642216I188J-68D01*
G02X358778Y641034I-3297J-1184D01*
G02X355275Y637532I-3503J1D01*
G01X355272D01*
G02X354096Y637736I2J3502D01*
G03X353955Y637734I-68J-188D01*
G02X352675Y637492I-1279J3260D01*
G02X351492Y637697I-2J3502D01*
G03X351358I-67J-188D01*
G02X350175Y637492I-1181J3297D01*
G02X348992Y637697I-2J3502D01*
G03X348858I-67J-188D01*
G02X347675Y637492I-1181J3297D01*
G02X346492Y637697I-2J3502D01*
G03X346358I-67J-188D01*
G02X345175Y637492I-1181J3297D01*
G02X343992Y637697I-2J3502D01*
G03X343858I-67J-188D01*
G02X342675Y637492I-1181J3297D01*
G02X339172Y640994I-1J3502D01*
G02X339378Y642176I3503J-2D01*
G03Y642312I-188J68D01*
G02X339172Y643494I3297J1184D01*
G02X339353Y644602I3502J-3D01*
G03X339348Y644740I-190J62D01*
G02X339092Y646054I3247J1315D01*
G02X342595Y649556I3503J-1D01*
G01X342598D01*
G02X343778Y649351I-1J-3502D01*
G03X343912I67J188D01*
G02X345095Y649556I1181J-3297D01*
G02X346278Y649351I2J-3502D01*
G03X346412I67J188D01*
G02X347595Y649556I1181J-3297D01*
G02X348778Y649351I2J-3502D01*
G03X348912I67J188D01*
G02X350095Y649556I1181J-3297D01*
G37*
G36*
G01X1626857Y633460D02*
G02X1625708Y633655I-3J3467D01*
G03X1625576I-66J-189D01*
G02X1625165Y633539I-1146J3273D01*
G02X1625166Y633494I-3501J-100D01*
G01Y633490D01*
G02X1624886Y632120I-3503J2D01*
G03Y631964I184J-78D01*
G02X1625166Y630592I-3223J-1372D01*
G02X1621663Y627090I-3503J1D01*
G01X1621662D01*
G02X1619492Y627844I1J3502D01*
G03X1619261Y627856I-124J-157D01*
G02X1617397Y627320I-1862J2967D01*
G02X1613894Y630822I-1J3502D01*
G02X1614174Y632194I3503J0D01*
G03Y632350I-184J78D01*
G02X1613894Y633722I3223J1372D01*
G02X1614174Y635094I3503J0D01*
G03Y635250I-184J78D01*
G02X1613894Y636622I3223J1372D01*
G02X1617397Y640124I3503J-1D01*
G02X1620198Y638726I1J-3504D01*
G03X1620316Y638650I160J119D01*
G02X1620330Y638647I-727J-3426D01*
G01X1620490Y638813D01*
G03X1620542Y638994I-143J139D01*
G02X1620462Y639741I3422J744D01*
G02X1620762Y641160I3502J1D01*
G03Y641322I-183J81D01*
G02X1620462Y642739I3202J1418D01*
G01Y642741D01*
G02X1627466I3502J0D01*
G01Y642739D01*
G02X1627166Y641322I-3502J1D01*
G03Y641160I183J-81D01*
G02X1627387Y640480I-3203J-1417D01*
G03X1627543Y640326I196J42D01*
G02X1628006Y640199I-684J-3400D01*
G03X1628138I66J189D01*
G02X1629283Y640394I1146J-3272D01*
G01X1629287D01*
G02Y633460I0J-3467D01*
G01X1629283D01*
G02X1628138Y633655I1J3467D01*
G03X1628006I-66J-189D01*
G02X1626857Y633460I-1146J3272D01*
G37*
G36*
G01X1363857Y623112D02*
G02X1362708Y623307I-3J3467D01*
G03X1362576I-66J-189D01*
G02X1362165Y623191I-1146J3273D01*
G02X1362166Y623146I-3501J-100D01*
G01Y623142D01*
G02X1361886Y621772I-3503J2D01*
G03Y621616I184J-78D01*
G02X1362166Y620244I-3223J-1372D01*
G02X1358663Y616742I-3503J1D01*
G01X1358662D01*
G02X1356492Y617496I1J3502D01*
G03X1356261Y617508I-124J-157D01*
G02X1354397Y616972I-1862J2967D01*
G02X1350894Y620474I-1J3502D01*
G02X1351174Y621846I3503J0D01*
G03Y622002I-184J78D01*
G02X1350894Y623374I3223J1372D01*
G02X1351174Y624746I3503J0D01*
G03Y624902I-184J78D01*
G02X1350894Y626274I3223J1372D01*
G02X1354397Y629776I3503J-1D01*
G02X1357197Y628378I0J-3503D01*
G03X1357316Y628302I160J120D01*
G02X1357363Y628292I-705J-3431D01*
G01X1357522Y628461D01*
G03X1357570Y628647I-146J137D01*
G02X1357462Y629514I3394J863D01*
G02X1357742Y630886I3502J0D01*
G03Y631042I-184J78D01*
G02X1357462Y632413I3222J1372D01*
G01Y632414D01*
G02X1364466I3502J0D01*
G01Y632413D01*
G02X1364186Y631042I-3502J1D01*
G03X1364187Y630886I185J-77D01*
G02X1364411Y630133I-3224J-1369D01*
G03X1364567Y629973I197J36D01*
G02X1365006Y629851I-707J-3395D01*
G03X1365138I66J189D01*
G02X1366283Y630046I1146J-3272D01*
G01X1366287D01*
G02Y623112I0J-3467D01*
G01X1366283D01*
G02X1365138Y623307I1J3467D01*
G03X1365006I-66J-189D01*
G02X1363857Y623112I-1146J3272D01*
G37*
G36*
G01X1521274Y615618D02*
G02X1521480Y616800I3503J-2D01*
G03Y616936I-188J68D01*
G02X1521274Y618118I3297J1184D01*
G02X1524777Y621620I3503J-1D01*
G01X1524780D01*
G02X1525960Y621415I-1J-3502D01*
G03X1526094I67J188D01*
G02X1527277Y621620I1181J-3297D01*
G02X1530780Y618118I1J-3502D01*
G02X1530574Y616936I-3503J2D01*
G03Y616800I188J-68D01*
G02X1530780Y615618I-3297J-1184D01*
G02X1530569Y614421I-3503J0D01*
G03Y614285I188J-68D01*
G02X1530780Y613088I-3292J-1197D01*
G02X1530574Y611906I-3503J2D01*
G03Y611770I188J-68D01*
G02X1530780Y610588I-3297J-1184D01*
G02X1530556Y609358I-3503J2D01*
G03Y609218I188J-70D01*
G02X1530780Y607988I-3279J-1232D01*
G02X1530574Y606806I-3503J2D01*
G03Y606670I188J-68D01*
G02X1530780Y605488I-3297J-1184D01*
G02X1527277Y601986I-3503J1D01*
G01X1527274D01*
G02X1526094Y602191I1J3502D01*
G03X1525960I-67J-188D01*
G02X1524777Y601986I-1181J3297D01*
G02X1521274Y605488I-1J3502D01*
G02X1521480Y606670I3503J-2D01*
G03Y606806I-188J68D01*
G02X1521274Y607988I3297J1184D01*
G02X1521498Y609218I3503J-2D01*
G03Y609358I-188J70D01*
G02X1521274Y610588I3279J1232D01*
G02X1521480Y611770I3503J-2D01*
G03Y611906I-188J68D01*
G02X1521274Y613088I3297J1184D01*
G02X1521485Y614285I3503J0D01*
G03Y614421I-188J68D01*
G02X1521274Y615618I3292J1197D01*
G37*
G36*
G01X509790Y612568D02*
G02X509510Y613939I3222J1372D01*
G01Y613940D01*
G02X516514I3502J0D01*
G01Y613939D01*
G02X516234Y612568I-3502J1D01*
G03X516235Y612412I185J-77D01*
G02X516372Y612030I-3223J-1372D01*
G03X516544Y611887I192J56D01*
G02X517354Y611708I-338J-3451D01*
G03X517486I66J189D01*
G02X518635Y611904I1149J-3272D01*
G02Y604968I0J-3468D01*
G02X517486Y605164I0J3468D01*
G03X517354I-66J-189D01*
G02X516205Y604968I-1149J3272D01*
G02X515056Y605164I0J3468D01*
G03X514924I-66J-189D01*
G02X514513Y605048I-1146J3273D01*
G02X514514Y605003I-3501J-100D01*
G01Y604999D01*
G02X514234Y603629I-3503J2D01*
G03Y603473I184J-78D01*
G02X514514Y602101I-3223J-1372D01*
G02X511011Y598598I-3503J0D01*
G02X508840Y599353I1J3503D01*
G03X508609Y599365I-124J-157D01*
G02X506745Y598828I-1864J2967D01*
G02X503242Y602331I0J3503D01*
G02X503522Y603703I3503J0D01*
G03Y603859I-184J78D01*
G02X503242Y605231I3223J1372D01*
G02X503522Y606603I3503J0D01*
G03Y606759I-184J78D01*
G02X503242Y608131I3223J1372D01*
G02X506745Y611634I3503J0D01*
G02X508871Y610914I-1J-3503D01*
G01X508916Y610880D01*
X509025Y610868D01*
X509449Y611065D01*
X509511Y611157D01*
X509514Y611212D01*
G02X509790Y612412I3498J-173D01*
G03Y612568I-184J78D01*
G37*
G36*
G01X465331Y604516D02*
G02X466514Y604311I2J-3502D01*
G03X466648I67J188D01*
G02X467831Y604516I1181J-3297D01*
G02X469014Y604311I2J-3502D01*
G03X469148I67J188D01*
G02X470331Y604516I1181J-3297D01*
G02X473834Y601014I1J-3502D01*
G02X473628Y599832I-3503J2D01*
G03Y599696I188J-68D01*
G02X473834Y598514I-3297J-1184D01*
G02X470331Y595012I-3503J1D01*
G01X470328D01*
G02X469148Y595217I1J3502D01*
G03X469014I-67J-188D01*
G02X467831Y595012I-1181J3297D01*
G02X466648Y595217I-2J3502D01*
G03X466514I-67J-188D01*
G02X465331Y595012I-1181J3297D01*
G02X464148Y595217I-2J3502D01*
G03X464014I-67J-188D01*
G02X462831Y595012I-1181J3297D01*
G02X461592Y595238I-1J3502D01*
G03X461450I-71J-187D01*
G02X460211Y595012I-1238J3276D01*
G02X459028Y595217I-2J3502D01*
G03X458894I-67J-188D01*
G02X457711Y595012I-1181J3297D01*
G02X454208Y598514I-1J3502D01*
G02X454414Y599696I3503J-2D01*
G03Y599832I-188J68D01*
G02X454208Y601014I3297J1184D01*
G02X457711Y604516I3503J-1D01*
G01X457714D01*
G02X458894Y604311I-1J-3502D01*
G03X459028I67J188D01*
G02X460211Y604516I1181J-3297D01*
G02X461450Y604290I1J-3502D01*
G03X461592I71J187D01*
G02X462831Y604516I1238J-3276D01*
G02X464014Y604311I2J-3502D01*
G03X464148I67J188D01*
G02X465331Y604516I1181J-3297D01*
G37*
G36*
G01X981891Y205046D02*
G02X983641Y205656I1987J-2884D01*
G03X983827Y205842I-14J200D01*
G02X987321Y209102I3494J-242D01*
G02X987564Y209093I-8J-3503D01*
G03X987721Y209152I15J199D01*
G02X990221Y210202I2501J-2453D01*
G02X993724Y206699I0J-3503D01*
G02X993308Y205044I-3503J1D01*
G03Y204854I176J-95D01*
G02X993724Y203199I-3087J-1656D01*
G02X993308Y201544I-3503J1D01*
G03Y201354I176J-95D01*
G02X993724Y199699I-3087J-1656D01*
G02X990221Y196196I-3503J0D01*
G02X989978Y196205I8J3503D01*
G03X989821Y196146I-15J-199D01*
G02X989542Y195890I-2504J2449D01*
G03X989471Y195701I126J-155D01*
G02X989524Y195099I-3450J-607D01*
G02X982518I-3503J0D01*
G02X983800Y197808I3503J0D01*
G03X983871Y197997I-126J155D01*
G02X983818Y198598I3450J607D01*
G01Y198600D01*
G02X983819Y198660I3503J-28D01*
G02X982055Y199171I59J3502D01*
G03X981837Y199165I-104J-170D01*
G02X979849Y198546I-1988J2884D01*
G02X977910Y199132I1J3503D01*
G03X977688I-111J-166D01*
G02X975749Y198546I-1940J2917D01*
G02X972359Y201167I0J3503D01*
G03X972153Y201317I-194J-50D01*
G02X971943Y201310I-222J3496D01*
G02X970051Y201866I2J3503D01*
G03X969835I-108J-169D01*
G02X967943Y201310I-1894J2947D01*
G02X964686Y203525I0J3502D01*
G03X964536Y203648I-186J-74D01*
G02X963305Y205125I271J1477D01*
G02X964807Y206627I1502J0D01*
G01X964833D01*
G03X965004Y206718I3J200D01*
G02X967943Y208316I2939J-1904D01*
G02X969835Y207760I-2J-3503D01*
G03X970051I108J169D01*
G02X971943Y208316I1894J-2947D01*
G02X974028Y207627I-1J-3503D01*
G01X974059Y207604D01*
X974131Y207584D01*
X974478Y207624D01*
X974544Y207658D01*
X974569Y207687D01*
G02X977221Y208902I2652J-2287D01*
G02X980718Y205584I0J-3502D01*
G03X980860Y205403I200J11D01*
G02X981673Y205040I-1010J-3354D01*
G03X981891Y205046I104J170D01*
G37*
G36*
G01X943221Y179892D02*
G02X944403Y179686I-2J-3503D01*
G03X944539I68J188D01*
G02X945721Y179892I1184J-3297D01*
G02X946854Y179703I-2J-3503D01*
G03X946999Y179709I65J189D01*
G02X948401Y180002I1402J-3210D01*
G02X951904Y176499I0J-3503D01*
G02X949342Y173125I-3503J0D01*
G03X949197Y172957I54J-193D01*
G02X945721Y169886I-3476J432D01*
G02X944539Y170092I2J3503D01*
G03X944403I-68J-188D01*
G02X943221Y169886I-1184J3297D01*
G02X942039Y170092I2J3503D01*
G03X941903I-68J-188D01*
G02X940721Y169886I-1184J3297D01*
G02X939510Y170103I3J3503D01*
G03X939372I-69J-188D01*
G02X938161Y169886I-1214J3286D01*
G02X937002Y170084I2J3503D01*
G03X936861Y170081I-67J-189D01*
G02X935551Y169826I-1312J3248D01*
G02X932048Y173329I0J3503D01*
G02X932313Y174663I3503J-2D01*
G03X932315Y174810I-185J76D01*
G02X932088Y176049I3276J1240D01*
G02X935591Y179552I3503J0D01*
G02X936376Y179463I0J-3503D01*
G03X936515Y179481I45J195D01*
G02X938161Y179892I1646J-3091D01*
G02X939372Y179675I-3J-3503D01*
G03X939510I69J188D01*
G02X940721Y179892I1214J-3286D01*
G02X941903Y179686I-2J-3503D01*
G03X942039I68J188D01*
G02X943221Y179892I1184J-3297D01*
G37*
G36*
G01X959170Y167763D02*
G02X959376Y168945I3503J-2D01*
G03Y169081I-188J68D01*
G02X959170Y170263I3297J1184D01*
G02X966176I3503J0D01*
G02X965970Y169081I-3503J2D01*
G03Y168945I188J-68D01*
G02X966176Y167763I-3297J-1184D01*
G02X959170I-3503J0D01*
G37*
G36*
G01X975691Y157718D02*
G02Y164722I0J3502D01*
G01X975693D01*
G02X978131Y163733I-1J-3502D01*
G01X978159Y163705D01*
X978231Y163676D01*
X978548Y163675D01*
G03X978686Y163730I0J200D01*
G01X978687Y163731D01*
G02X981112Y164706I2425J-2528D01*
G02Y157702I0J-3502D01*
G01X981110D01*
G02X978672Y158691I1J3502D01*
G01X978644Y158719D01*
X978572Y158748D01*
X978255Y158749D01*
G03X978117Y158694I0J-200D01*
G01X978116Y158693D01*
G02X975691Y157718I-2425J2528D01*
G37*
G36*
G01X786322Y149471D02*
G02X783651Y146068I-3503J0D01*
G03X783507Y145933I47J-194D01*
G02X780159Y143458I-3348J1027D01*
G02X776656Y146961I0J3503D01*
G02X779327Y150364I3503J0D01*
G03X779471Y150499I-47J194D01*
G02X782819Y152974I3348J-1027D01*
G02X786322Y149471I0J-3503D01*
G37*
G36*
G01X787681Y124450D02*
G02X788863Y124244I-2J-3503D01*
G03X788999I68J188D01*
G02X790181Y124450I1184J-3297D01*
G02X791363Y124244I-2J-3503D01*
G03X791499I68J188D01*
G02X792681Y124450I1184J-3297D01*
G02Y117444I0J-3503D01*
G02X792393Y117456I2J3503D01*
G03X792191Y117331I-16J-199D01*
G02X788941Y115134I-3250J1305D01*
G02X787759Y115340I2J3503D01*
G03X787623I-68J-188D01*
G02X786441Y115134I-1184J3297D01*
G02X785259Y115340I2J3503D01*
G03X785123I-68J-188D01*
G02X783941Y115134I-1184J3297D01*
G02X782759Y115340I2J3503D01*
G03X782623I-68J-188D01*
G02X781441Y115134I-1184J3297D01*
G02Y122140I0J3503D01*
G02X781729Y122128I-2J-3503D01*
G03X781931Y122253I16J199D01*
G02X785181Y124450I3250J-1305D01*
G02X786363Y124244I-2J-3503D01*
G03X786499I68J188D01*
G02X787681Y124450I1184J-3297D01*
G37*
G36*
G01X694221Y108364D02*
X694223D01*
G02X695877Y107949I0J-3502D01*
G03X696065I94J176D01*
G02X697721Y108364I1654J-3087D01*
G02X699377Y107949I2J-3502D01*
G03X699565I94J176D01*
G02X701219Y108364I1654J-3087D01*
G01X701221D01*
G02X704713Y105131I0J-3502D01*
G03X704794Y104985I200J15D01*
G02X705722Y103968I-2073J-2823D01*
G03X705938Y103876I171J103D01*
G02X706716Y103964I780J-3414D01*
G01X706721D01*
G02Y96960I0J-3502D01*
G02X703720Y98656I0J3503D01*
G03X703504Y98748I-171J-103D01*
G02X702721Y98660I-780J3414D01*
G02X701065Y99075I-2J3502D01*
G03X700877I-94J-176D01*
G02X699221Y98660I-1654J3087D01*
G02X697565Y99075I-2J3502D01*
G03X697377I-94J-176D01*
G02X695723Y98660I-1654J3087D01*
G01X695721D01*
G02X692229Y101893I0J3502D01*
G03X692148Y102039I-200J-15D01*
G02X690718Y104862I2071J2823D01*
G02X694221Y108364I3503J-1D01*
G37*
G36*
G01X1736731Y105796D02*
G02X1738386Y105380I-1J-3503D01*
G03X1738576I95J176D01*
G02X1740231Y105796I1656J-3087D01*
G02X1741886Y105380I-1J-3503D01*
G03X1742076I95J176D01*
G02X1743731Y105796I1656J-3087D01*
G02X1747049Y103414I0J-3502D01*
G03X1747141Y103303I190J64D01*
G02X1748844Y101047I-1706J-3059D01*
G03X1749019Y100894I195J46D01*
G02X1752188Y97408I-333J-3486D01*
G02X1748686Y93906I-3502J0D01*
G02X1745277Y96605I0J3502D01*
G03X1745102Y96758I-195J-46D01*
G02X1743779Y97157I330J3487D01*
G03X1743591I-94J-176D01*
G02X1741935Y96742I-1654J3087D01*
G02X1740279Y97157I-2J3502D01*
G03X1740091I-94J-176D01*
G02X1738437Y96742I-1654J3087D01*
G01X1738435D01*
G02X1735117Y99123I0J3502D01*
G03X1735025Y99234I-190J-64D01*
G02X1733228Y102293I1705J3059D01*
G02X1736731Y105796I3503J0D01*
G37*
G36*
G01X261416Y104168D02*
G02X263071Y103752I-1J-3503D01*
G03X263261I95J176D01*
G02X264916Y104168I1656J-3087D01*
G02X266571Y103752I-1J-3503D01*
G03X266761I95J176D01*
G02X268416Y104168I1656J-3087D01*
G02X271908Y100934I0J-3502D01*
G03X271989Y100788I200J15D01*
G02X272651Y100153I-2073J-2823D01*
G03X272851Y100083I156J125D01*
G02X273616Y100168I767J-3418D01*
G02Y93162I0J-3503D01*
G02X270881Y94477I0J3502D01*
G03X270681Y94547I-156J-125D01*
G02X269916Y94462I-767J3418D01*
G02X268261Y94878I1J3503D01*
G03X268071I-95J-176D01*
G02X266416Y94462I-1656J3087D01*
G02X264761Y94878I1J3503D01*
G03X264571I-95J-176D01*
G02X262916Y94462I-1656J3087D01*
G02X259424Y97696I0J3502D01*
G03X259343Y97842I-200J-15D01*
G02X257914Y100665I2073J2823D01*
G02X261416Y104168I3502J1D01*
G37*
G36*
G01X746532Y89988D02*
Y89989D01*
G02X746812Y91360I3502J-1D01*
G03Y91516I-184J78D01*
G02X746532Y92887I3222J1372D01*
G01Y92888D01*
G02X753536I3502J0D01*
G01Y92887D01*
G02X753256Y91516I-3502J1D01*
G03Y91360I184J-78D01*
G02X753536Y89989I-3222J-1372D01*
G01Y89988D01*
G02X746532I-3502J0D01*
G37*
G36*
G01X693226Y81552D02*
G02X693431Y82735I3502J2D01*
G03Y82869I-188J67D01*
G02X693226Y84049I3297J1181D01*
G01Y84052D01*
G02X695374Y87282I3503J0D01*
G03X695481Y87389I-77J184D01*
G02X698711Y89538I3230J-1353D01*
G02X702214Y86035I0J-3503D01*
G02X700174Y82852I-3503J0D01*
G03X700067Y82610I84J-182D01*
G02X700230Y81556I-3339J-1056D01*
G01Y81552D01*
G02X699726Y79743I-3501J1D01*
G03X699707Y79578I171J-103D01*
G02X699874Y78512I-3336J-1069D01*
G02X692868I-3503J0D01*
G02X693373Y80321I3502J-3D01*
G03X693392Y80486I-171J103D01*
G02X693226Y81552I3336J1065D01*
G37*
G36*
G01X1734114Y79140D02*
G02X1734320Y80322I3503J-2D01*
G03Y80458I-188J68D01*
G02X1734114Y81640I3297J1184D01*
G02X1737617Y85142I3503J-1D01*
G01X1737620D01*
G02X1738824Y84928I-1J-3502D01*
G03X1739040Y84981I68J188D01*
G02X1741621Y86116I2581J-2367D01*
G02X1745124Y82613I0J-3503D01*
G02X1744918Y81431I-3503J2D01*
G03Y81295I188J-68D01*
G02X1745124Y80113I-3297J-1184D01*
G02X1744708Y78458I-3503J1D01*
G03Y78268I176J-95D01*
G02X1745124Y76613I-3087J-1656D01*
G02X1744918Y75431I-3503J2D01*
G03Y75295I188J-68D01*
G02X1745124Y74113I-3297J-1184D01*
G02X1741621Y70610I-3503J0D01*
G02X1740414Y70825I1J3503D01*
G03X1740198Y70772I-68J-188D01*
G02X1737617Y69638I-2580J2368D01*
G02X1734114Y73140I-1J3502D01*
G02X1734320Y74322I3503J-2D01*
G03Y74458I-188J68D01*
G02X1734114Y75640I3297J1184D01*
G02X1734530Y77295I3503J-1D01*
G03Y77485I-176J95D01*
G02X1734114Y79140I3087J1656D01*
G37*
G36*
G01X1454786Y76366D02*
G02Y84312I0J3973D01*
G01X1454886D01*
G02X1458808Y80389I-1J-3923D01*
G02X1454786Y76366I-4022J-1D01*
G37*
G36*
G01X259390Y77529D02*
G02X259596Y78711I3503J-2D01*
G03Y78847I-188J68D01*
G02X259390Y80029I3297J1184D01*
G02X266396I3503J0D01*
G02X266190Y78847I-3503J2D01*
G03Y78711I188J-68D01*
G02X266396Y77529I-3297J-1184D01*
G02X265926Y75777I-3503J1D01*
G03X265941Y75554I173J-100D01*
G02X266353Y74883I-2760J-2157D01*
G01Y74881D01*
G03X266515Y74768I181J86D01*
G01X266858Y74735D01*
G03X267037Y74814I19J199D01*
G01X267038Y74815D01*
G02X269860Y76244I2823J-2074D01*
G02Y69238I0J-3503D01*
G02X266689Y71254I0J3503D01*
G01Y71256D01*
G03X266527Y71369I-181J-86D01*
G01X266184Y71402D01*
G03X266005Y71323I-19J-199D01*
G01X266004Y71322D01*
G02X263182Y69894I-2822J2074D01*
G02X259680Y73396I0J3502D01*
G01Y73397D01*
G02X260149Y75148I3502J0D01*
G03X260134Y75371I-173J100D01*
G02X259390Y77529I2758J2158D01*
G37*
G36*
G01X1776242Y70073D02*
Y70074D01*
G02X1776522Y71445I3502J-1D01*
G03Y71601I-184J78D01*
G02X1776242Y72972I3222J1372D01*
G01Y72973D01*
G02X1783246I3502J0D01*
G01Y72972D01*
G02X1782966Y71601I-3502J1D01*
G03Y71445I184J-78D01*
G02X1783246Y70074I-3222J-1372D01*
G01Y70073D01*
G02X1776242I-3502J0D01*
G37*
G36*
G01X311150Y68906D02*
G02X311430Y70278I3503J0D01*
G03Y70434I-184J78D01*
G02X311150Y71806I3223J1372D01*
G02X318156I3503J0D01*
G02X317876Y70434I-3503J0D01*
G03Y70278I184J-78D01*
G02X318156Y68906I-3223J-1372D01*
G02X311150I-3503J0D01*
G37*
G36*
G01X1225541Y63504D02*
X1225441D01*
G02X1221518Y67427I0J3923D01*
G02X1225540Y71450I4023J0D01*
G01X1225541D01*
G02Y63504I0J-3973D01*
G37*
G36*
G01X306470Y61658D02*
X306466D01*
G02X305379Y61832I3J3502D01*
G03X305238Y61825I-61J-190D01*
G02X303854Y61540I-1384J3217D01*
G01X303852D01*
G02Y68544I0J3502D01*
G01X303856D01*
G02X304943Y68370I-3J-3502D01*
G03X305084Y68377I61J190D01*
G02X306468Y68662I1384J-3217D01*
G01X306470D01*
G02Y61658I0J-3502D01*
G37*
G36*
G01X757721Y68134D02*
X757724D01*
G02X758904Y67929I-1J-3502D01*
G03X759038I67J188D01*
G02X760221Y68134I1181J-3297D01*
G02X761115Y68018I0J-3502D01*
G03X761277Y68045I51J194D01*
G02X763221Y68634I1944J-2913D01*
G02X766724Y65132I1J-3502D01*
G02X766134Y63188I-3503J2D01*
G03X766107Y63026I167J-111D01*
G02X766224Y62132I-3386J-898D01*
G02X762721Y58630I-3503J1D01*
G01X762718D01*
G02X761538Y58835I1J3502D01*
G03X761404I-67J-188D01*
G02X760221Y58630I-1181J3297D01*
G02X759038Y58835I-2J3502D01*
G03X758904I-67J-188D01*
G02X757721Y58630I-1181J3297D01*
G02X754218Y62132I-1J3502D01*
G02X754424Y63314I3503J-2D01*
G03Y63450I-188J68D01*
G02X754218Y64632I3297J1184D01*
G02X757721Y68134I3503J-1D01*
G37*
G36*
G01X1770792Y60133D02*
G02X1771072Y61505I3502J0D01*
G03Y61661I-184J78D01*
G02X1770792Y63032I3222J1372D01*
G01Y63033D01*
G02X1777796I3502J0D01*
G01Y63032D01*
G02X1777516Y61661I-3502J1D01*
G03Y61505I184J-78D01*
G02X1777796Y60133I-3222J-1372D01*
G02X1777507Y58738I-3502J-2D01*
G03Y58579I183J-79D01*
G02X1777794Y57191I-3216J-1389D01*
G02X1770788I-3503J0D01*
G02X1771078Y58586I3503J-1D01*
G03X1771079Y58745I-183J81D01*
G02X1770792Y60133I3215J1388D01*
G37*
G36*
G01X1734590Y53103D02*
G02X1734796Y54285I3503J-2D01*
G03Y54421I-188J68D01*
G02X1734590Y55603I3297J1184D01*
G02X1741596I3503J0D01*
G02X1741390Y54421I-3503J2D01*
G03Y54285I188J-68D01*
G02X1741596Y53103I-3297J-1184D01*
G02X1734590I-3503J0D01*
G37*
G36*
G01X752118Y51602D02*
G02X755621Y55104I3503J-1D01*
G01X755623D01*
G02X757040Y54804I-1J-3502D01*
G03X757202I81J183D01*
G02X758621Y55104I1418J-3202D01*
G02X762124Y51602I1J-3502D01*
G02X760383Y48575I-3502J0D01*
G01X760382Y48574D01*
G03X760284Y48421I101J-173D01*
G01X760252Y48099D01*
G03X760319Y47929I199J-20D01*
G02X754928Y47567I-2516J-2851D01*
G01X754962Y47606D01*
X754984Y47707D01*
X754852Y48131D01*
X754778Y48202D01*
X754728Y48215D01*
G02X752118Y51602I893J3387D01*
G37*
G36*
G01X257516Y55068D02*
G02X259171Y54652I-1J-3503D01*
G03X259361I95J176D01*
G02X261016Y55068I1656J-3087D01*
G02X262198Y54862I-2J-3503D01*
G03X262334I68J188D01*
G02X263516Y55068I1184J-3297D01*
G02X266921Y52387I0J-3503D01*
G03X267021Y52257I195J46D01*
G02X268868Y49171I-1655J-3086D01*
G02X265365Y45668I-3503J0D01*
G02X263864Y46006I0J3503D01*
G03X263672Y45995I-86J-181D01*
G02X261816Y45462I-1857J2970D01*
G02X260634Y45668I2J3503D01*
G03X260498I-68J-188D01*
G02X259316Y45462I-1184J3297D01*
G02X257661Y45878I1J3503D01*
G03X257471I-95J-176D01*
G02X255816Y45462I-1656J3087D01*
G02X254161Y45878I1J3503D01*
G03X253971I-95J-176D01*
G02X252316Y45462I-1656J3087D01*
G02X250661Y45878I1J3503D01*
G03X250471I-95J-176D01*
G02X248816Y45462I-1656J3087D01*
G02X245314Y48965I1J3503D01*
G02X246959Y51935I3504J0D01*
G03X247051Y52075I-106J170D01*
G02X250516Y55068I3465J-509D01*
G02X252171Y54652I-1J-3503D01*
G03X252361I95J176D01*
G02X254016Y55068I1656J-3087D01*
G02X255671Y54652I-1J-3503D01*
G03X255861I95J176D01*
G02X257516Y55068I1656J-3087D01*
G37*
G36*
G01X365287Y197050D02*
X371587D01*
G02Y173422I0J-11814D01*
G01X365287D01*
G02Y197050I0J11814D01*
G37*
G36*
G01X280826Y52152D02*
X284226D01*
G02Y49146I0J-1503D01*
G01X280826D01*
G02Y52152I0J1503D01*
G37*
G36*
G01X280828Y27438D02*
X284228D01*
G02Y24432I0J-1503D01*
G01X280828D01*
G02Y27438I0J1503D01*
G37*
G36*
G01X247177Y197836D02*
X253476D01*
G02Y172636I0J-12600D01*
G01X247177D01*
G02Y197836I0J12600D01*
G37*
G36*
G01X225727Y52152D02*
X229127D01*
G02Y49146I0J-1503D01*
G01X225727D01*
G02Y52152I0J1503D01*
G37*
G36*
G01X69964Y110535D02*
X65662Y105934D01*
G02X47255Y123148I-9203J8607D01*
G01X51557Y127748D01*
G02X69964Y110535I9203J-8607D01*
G37*
G36*
G01X634794Y592006D02*
X638694D01*
G02Y589002I0J-1502D01*
G01X634794D01*
G02Y592006I0J1502D01*
G37*
G36*
G01X646358Y591818D02*
X650258D01*
G02Y588814I0J-1502D01*
G01X646358D01*
G02Y591818I0J1502D01*
G37*
G36*
G01X635567Y673276D02*
X638967D01*
G02Y670272I0J-1502D01*
G01X635567D01*
G02Y673276I0J1502D01*
G37*
G36*
G01X670613Y43966D02*
X674013D01*
G02Y40962I0J-1502D01*
G01X670613D01*
G02Y43966I0J1502D01*
G37*
G36*
G01X857187Y343712D02*
X860587D01*
G02Y340708I0J-1502D01*
G01X857187D01*
G02Y343712I0J1502D01*
G37*
G36*
G01X860942Y332360D02*
X864342D01*
G02Y329356I0J-1502D01*
G01X860942D01*
G02Y332360I0J1502D01*
G37*
G36*
G01X1700136Y52152D02*
X1703536D01*
G02Y49146I0J-1503D01*
G01X1700136D01*
G02Y52152I0J1503D01*
G37*
G36*
G01X1755238Y27980D02*
X1758638D01*
G02Y24974I0J-1503D01*
G01X1755238D01*
G02Y27980I0J1503D01*
G37*
G36*
G01X1755235Y52152D02*
X1758635D01*
G02Y49146I0J-1503D01*
G01X1755235D01*
G02Y52152I0J1503D01*
G37*
G36*
G01X873175Y748970D02*
X869275D01*
G02Y751974I0J1502D01*
G01X873175D01*
G02Y748970I0J-1502D01*
G37*
G36*
G01X1705561Y643052D02*
X1701661D01*
G02Y646056I0J1502D01*
G01X1705561D01*
G02Y643052I0J-1502D01*
G37*
G36*
G01X937341Y309612D02*
X920139D01*
G02X937341I8601J12042D01*
G37*
G36*
G01X425469Y1593930D02*
X422069D01*
G02Y1596936I0J1503D01*
G01X425469D01*
G02Y1593930I0J-1503D01*
G37*
G36*
G01X413396Y1593094D02*
G02X412333Y1593534I0J1504D01*
G01X409929Y1595939D01*
G02X412054Y1598064I1063J1062D01*
G01X414459Y1595660D01*
G02X414899Y1594597I-1064J-1063D01*
G02X413396Y1593094I-1503J0D01*
G37*
G36*
G01X1113847Y1606056D02*
X1117247D01*
G02Y1603052I0J-1502D01*
G01X1113847D01*
G02Y1606056I0J1502D01*
G37*
G36*
G01X1125784Y1664208D02*
X1129184D01*
G02Y1661202I0J-1503D01*
G01X1125784D01*
G02Y1664208I0J1503D01*
G37*
G36*
G01X417365Y1629198D02*
X420765D01*
G02Y1626192I0J-1503D01*
G01X417365D01*
G02Y1629198I0J1503D01*
G37*
G36*
G01X648314Y569666D02*
X644414D01*
G02Y572672I0J1503D01*
G01X648314D01*
G02Y569666I0J-1503D01*
G37*
G36*
G01X1628455Y106141D02*
G02X1628655Y106341I200J0D01*
G02X1628807Y106271I0J-200D01*
G01X1634322Y99803D01*
G02X1634370Y99673I-152J-130D01*
G02X1634300Y99521I-200J0D01*
G01X1632113Y97657D01*
G02X1631983Y97609I-130J152D01*
G02X1631831Y97679I0J200D01*
G01X1626316Y104147D01*
G02X1626268Y104277I152J130D01*
G02X1626468Y104477I200J0D01*
G02X1626620Y104407I0J-200D01*
G01X1631875Y98243D01*
G03X1632157Y98221I152J130D01*
G01X1633736Y99565D01*
G03X1633758Y99847I-130J152D01*
G01X1628503Y106011D01*
G02X1628455Y106141I152J130D01*
G37*
G36*
G01X816152Y1720920D02*
X901868D01*
G02X902752Y1720554I0J-1251D01*
G01X906384Y1716922D01*
G02X906750Y1716038I-885J-884D01*
G01Y1662730D01*
G03X906809Y1662588I200J0D01*
G01X925253Y1644144D01*
G03X925395Y1644085I142J141D01*
G01X1071615D01*
G02X1072499Y1643719I0J-1251D01*
G01X1104694Y1611524D01*
G02X1105060Y1610640I-885J-884D01*
G01Y1568556D01*
G02X1104694Y1567672I-1251J0D01*
G01X1100946Y1563924D01*
G02X1100062Y1563558I-884J885D01*
G01X942524D01*
G02X941640Y1563924I0J1251D01*
G01X939599Y1565965D01*
G02X939233Y1566849I885J884D01*
G01Y1598398D01*
G03X939174Y1598540I-200J0D01*
G01X923619Y1614095D01*
G03X923477Y1614154I-142J-141D01*
G01X903723D01*
G02X902839Y1614520I0J1251D01*
G01X892973Y1624386D01*
G03X892831Y1624445I-142J-141D01*
G01X770852D01*
G02X769968Y1624811I0J1251D01*
G01X766466Y1628313D01*
G02X766100Y1629197I885J884D01*
G01Y1656302D01*
G02X766893Y1658211I2700J-2D01*
G01X799393Y1690712D01*
G03X799410Y1690974I-142J141D01*
G01X799171Y1691289D01*
G03X798913Y1691342I-159J-121D01*
G02X791281Y1689340I-7632J13548D01*
G01X791280D01*
G02X806830Y1704890I0J15550D01*
G01Y1704889D01*
G02X804828Y1697257I-15550J0D01*
G01X804791Y1697191D01*
X804821Y1697045D01*
X805197Y1696760D01*
G03X805459Y1696778I121J160D01*
G01X808681Y1700000D01*
G03X808740Y1700142I-141J142D01*
G01Y1713508D01*
G02X809106Y1714392I1251J0D01*
G01X815268Y1720554D01*
G02X816152Y1720920I884J-885D01*
G37*
G36*
G01X1438232Y1664144D02*
G02X1438436Y1664348I204J0D01*
G01X1457722D01*
G02X1457926Y1664144I0J-204D01*
G01Y1658386D01*
Y1658186D01*
X1457740D01*
X1457330D01*
G03X1457154Y1658008I23J-199D01*
G01Y1656632D01*
G03X1457330Y1656454I199J21D01*
G01X1457726D01*
X1457926D01*
Y1656268D01*
Y1637396D01*
G02X1457722Y1637192I-204J0D01*
G01X1438436D01*
G02X1438232Y1637396I0J204D01*
G01Y1664144D01*
G37*
G36*
G01X791296Y1359655D02*
G02X790770Y1361500I2977J1846D01*
G02X791071Y1362919I3503J-2D01*
G03Y1363081I-183J81D01*
G02X790770Y1364500I3202J1421D01*
G02X797776I3503J0D01*
G02X797475Y1363081I-3503J2D01*
G03Y1362919I183J-81D01*
G02X797776Y1361500I-3202J-1421D01*
G02X797250Y1359655I-3503J1D01*
G03Y1359445I170J-105D01*
G02X797776Y1357600I-2977J-1846D01*
G02X797475Y1356181I-3503J2D01*
G03Y1356019I183J-81D01*
G02X797776Y1354600I-3202J-1421D01*
G02X790770I-3503J0D01*
G02X791071Y1356019I3503J-2D01*
G03Y1356181I-183J81D01*
G02X790770Y1357600I3202J1421D01*
G02X791296Y1359445I3503J-1D01*
G03Y1359655I-170J105D01*
G37*
G36*
G01X382478Y1657961D02*
G02X382681Y1658164I203J0D01*
G01X401967D01*
G02X402170Y1657961I0J-203D01*
G01Y1631213D01*
G02X401967Y1631010I-203J0D01*
G01X382681D01*
G02X382478Y1631213I0J203D01*
G01Y1657961D01*
G37*
G36*
G01X60921Y429304D02*
G02Y432308I0J1502D01*
G01X64821D01*
G02Y429304I0J-1502D01*
G01X60921D01*
G37*
G36*
G01X45960Y427304D02*
G02Y430308I0J1502D01*
G01X49360D01*
G02Y427304I0J-1502D01*
G01X45960D01*
G37*
G36*
G01X225731Y24974D02*
G02Y27980I0J1503D01*
G01X229131D01*
G02Y24974I0J-1503D01*
G01X225731D01*
G37*
G36*
G01X1700183Y25002D02*
G02Y28008I0J1503D01*
G01X1703583D01*
G02Y25002I0J-1503D01*
G01X1700183D01*
G37*
G36*
G01X551721Y80874D02*
G02Y77870I0J-1502D01*
G01X547821D01*
G02Y80874I0J1502D01*
G01X551721D01*
G37*
G36*
G01X512658Y45110D02*
G02Y48116I0J1503D01*
G01X516058D01*
G02Y45110I0J-1503D01*
G01X512658D01*
G37*
G36*
G01X541003Y69934D02*
G02Y72938I0J1502D01*
G01X544403D01*
G02Y69934I0J-1502D01*
G01X541003D01*
G37*
G36*
G01X509572Y863824D02*
G02Y866830I0J1503D01*
G01X513572D01*
G02Y863824I0J-1503D01*
G01X509572D01*
G37*
G36*
G01X1332812Y854880D02*
G02Y857886I0J1503D01*
G01X1336812D01*
G02Y854880I0J-1503D01*
G01X1332812D01*
G37*
G36*
G01X1659645Y1553264D02*
G02X1660705Y1553900I1060J-565D01*
G02X1661908Y1552698I1J-1202D01*
G02X1661747Y1552098I-1204J1D01*
G01X1660202Y1549425D01*
X1660200Y1549421D01*
G02X1659130Y1548768I-1070J550D01*
G02X1657928Y1549970I0J1202D01*
G01Y1549972D01*
G02X1658077Y1550551I1202J-1D01*
G01X1659643Y1553261D01*
X1659645Y1553264D01*
G37*
G36*
G01X1654920D02*
G02X1655980Y1553900I1060J-565D01*
G02X1657182Y1552698I0J-1202D01*
G02X1657022Y1552098I-1203J0D01*
G01X1655477Y1549425D01*
X1655475Y1549421D01*
G02X1654405Y1548768I-1070J550D01*
G02X1653202Y1549970I-1J1202D01*
G01Y1549972D01*
G02X1653352Y1550551I1203J-3D01*
G01X1654918Y1553261D01*
X1654920Y1553264D01*
G37*
G36*
G01X1645471D02*
G02X1646531Y1553900I1060J-565D01*
G02X1647734Y1552698I1J-1202D01*
G02X1647573Y1552098I-1204J1D01*
G01X1646028Y1549425D01*
X1646026Y1549421D01*
G02X1644956Y1548768I-1070J550D01*
G02X1643754Y1549970I0J1202D01*
G01Y1549972D01*
G02X1643903Y1550551I1202J-1D01*
G01X1645469Y1553261D01*
X1645471Y1553264D01*
G37*
G36*
G01X1650196D02*
G02X1651256Y1553900I1060J-565D01*
G02X1652458Y1552698I0J-1202D01*
G02X1652298Y1552098I-1203J0D01*
G01X1650753Y1549425D01*
X1650751Y1549421D01*
G02X1649681Y1548768I-1070J550D01*
G02X1648478Y1549970I-1J1202D01*
G01Y1549972D01*
G02X1648628Y1550551I1203J-3D01*
G01X1650194Y1553261D01*
X1650196Y1553264D01*
G37*
G36*
G01X1640747D02*
G02X1641807Y1553900I1060J-565D01*
G02X1643010Y1552698I1J-1202D01*
G02X1642849Y1552098I-1204J1D01*
G01X1641304Y1549425D01*
X1641302Y1549421D01*
G02X1640232Y1548768I-1070J550D01*
G02X1639030Y1549970I0J1202D01*
G01Y1549972D01*
G02X1639179Y1550551I1202J-1D01*
G01X1640745Y1553261D01*
X1640747Y1553264D01*
G37*
G36*
G01X1636023D02*
G02X1637083Y1553900I1060J-565D01*
G02X1638286Y1552698I1J-1202D01*
G02X1638125Y1552098I-1204J1D01*
G01X1636580Y1549425D01*
X1636578Y1549421D01*
G02X1635508Y1548768I-1070J550D01*
G02X1634306Y1549970I0J1202D01*
G01Y1549972D01*
G02X1634455Y1550551I1202J-1D01*
G01X1636021Y1553261D01*
X1636023Y1553264D01*
G37*
G36*
G01X1631298D02*
G02X1632358Y1553900I1060J-565D01*
G02X1633560Y1552698I0J-1202D01*
G02X1633400Y1552098I-1203J0D01*
G01X1631855Y1549425D01*
X1631853Y1549421D01*
G02X1630783Y1548768I-1070J550D01*
G02X1629580Y1549970I-1J1202D01*
G01Y1549972D01*
G02X1629730Y1550551I1203J-3D01*
G01X1631296Y1553261D01*
X1631298Y1553264D01*
G37*
G36*
G01X1626574D02*
G02X1627634Y1553900I1060J-565D01*
G02X1628836Y1552698I0J-1202D01*
G02X1628676Y1552098I-1203J0D01*
G01X1627131Y1549425D01*
X1627129Y1549421D01*
G02X1626059Y1548768I-1070J550D01*
G02X1624856Y1549970I-1J1202D01*
G01Y1549972D01*
G02X1625006Y1550551I1203J-3D01*
G01X1626572Y1553261D01*
X1626574Y1553264D01*
G37*
G36*
G01X1621849D02*
G02X1622909Y1553900I1060J-565D01*
G02X1624112Y1552698I1J-1202D01*
G02X1623951Y1552098I-1204J1D01*
G01X1622406Y1549425D01*
X1622404Y1549421D01*
G02X1621334Y1548768I-1070J550D01*
G02X1620132Y1549970I0J1202D01*
G01Y1549972D01*
G02X1620281Y1550551I1202J-1D01*
G01X1621847Y1553261D01*
X1621849Y1553264D01*
G37*
G36*
G01X1617125D02*
G02X1618185Y1553900I1060J-565D01*
G02X1619388Y1552698I1J-1202D01*
G02X1619227Y1552098I-1204J1D01*
G01X1617682Y1549425D01*
X1617680Y1549421D01*
G02X1616610Y1548768I-1070J550D01*
G02X1615408Y1549970I0J1202D01*
G01Y1549972D01*
G02X1615557Y1550551I1202J-1D01*
G01X1617123Y1553261D01*
X1617125Y1553264D01*
G37*
G36*
G01X1607676D02*
G02X1608736Y1553900I1060J-565D01*
G02X1609938Y1552698I0J-1202D01*
G02X1609778Y1552098I-1203J0D01*
G01X1608233Y1549425D01*
X1608231Y1549421D01*
G02X1607161Y1548768I-1070J550D01*
G02X1605958Y1549970I-1J1202D01*
G01Y1549972D01*
G02X1606108Y1550551I1203J-3D01*
G01X1607674Y1553261D01*
X1607676Y1553264D01*
G37*
G36*
G01X1612401D02*
G02X1613461Y1553900I1060J-565D01*
G02X1614664Y1552698I1J-1202D01*
G02X1614503Y1552098I-1204J1D01*
G01X1612958Y1549425D01*
X1612956Y1549421D01*
G02X1611886Y1548768I-1070J550D01*
G02X1610684Y1549970I0J1202D01*
G01Y1549972D01*
G02X1610833Y1550551I1202J-1D01*
G01X1612399Y1553261D01*
X1612401Y1553264D01*
G37*
G36*
G01X1598227D02*
G02X1599287Y1553900I1060J-565D01*
G02X1600490Y1552698I1J-1202D01*
G02X1600329Y1552098I-1204J1D01*
G01X1598784Y1549425D01*
X1598782Y1549421D01*
G02X1597712Y1548768I-1070J550D01*
G02X1596510Y1549970I0J1202D01*
G01Y1549972D01*
G02X1596659Y1550551I1202J-1D01*
G01X1598225Y1553261D01*
X1598227Y1553264D01*
G37*
G36*
G01X1602952D02*
G02X1604012Y1553900I1060J-565D01*
G02X1605214Y1552698I0J-1202D01*
G02X1605054Y1552098I-1203J0D01*
G01X1603509Y1549425D01*
X1603507Y1549421D01*
G02X1602437Y1548768I-1070J550D01*
G02X1601234Y1549970I-1J1202D01*
G01Y1549972D01*
G02X1601384Y1550551I1203J-3D01*
G01X1602950Y1553261D01*
X1602952Y1553264D01*
G37*
G36*
G01X1593503D02*
G02X1594563Y1553900I1060J-565D01*
G02X1595766Y1552698I1J-1202D01*
G02X1595605Y1552098I-1204J1D01*
G01X1594060Y1549425D01*
X1594058Y1549421D01*
G02X1592988Y1548768I-1070J550D01*
G02X1591786Y1549970I0J1202D01*
G01Y1549972D01*
G02X1591935Y1550551I1202J-1D01*
G01X1593501Y1553261D01*
X1593503Y1553264D01*
G37*
G36*
G01X1588779D02*
G02X1589839Y1553900I1060J-565D01*
G02X1591042Y1552698I1J-1202D01*
G02X1590881Y1552098I-1204J1D01*
G01X1589336Y1549425D01*
X1589334Y1549421D01*
G02X1588264Y1548768I-1070J550D01*
G02X1587062Y1549970I0J1202D01*
G01Y1549972D01*
G02X1587211Y1550551I1202J-1D01*
G01X1588777Y1553261D01*
X1588779Y1553264D01*
G37*
G36*
G01X1526858D02*
G02X1527918Y1553900I1060J-565D01*
G02X1529120Y1552698I0J-1202D01*
G02X1528960Y1552098I-1203J0D01*
G01X1527415Y1549425D01*
X1527413Y1549421D01*
G02X1526343Y1548768I-1070J550D01*
G02X1525140Y1549970I-1J1202D01*
G01Y1549972D01*
G02X1525290Y1550551I1203J-3D01*
G01X1526856Y1553261D01*
X1526858Y1553264D01*
G37*
G36*
G01X1531583D02*
G02X1532643Y1553900I1060J-565D01*
G02X1533846Y1552698I1J-1202D01*
G02X1533685Y1552098I-1204J1D01*
G01X1532140Y1549425D01*
X1532138Y1549421D01*
G02X1531068Y1548768I-1070J550D01*
G02X1529866Y1549970I0J1202D01*
G01Y1549972D01*
G02X1530015Y1550551I1202J-1D01*
G01X1531581Y1553261D01*
X1531583Y1553264D01*
G37*
G36*
G01X1517409D02*
G02X1518469Y1553900I1060J-565D01*
G02X1519672Y1552698I1J-1202D01*
G02X1519511Y1552098I-1204J1D01*
G01X1517966Y1549425D01*
X1517964Y1549421D01*
G02X1516894Y1548768I-1070J550D01*
G02X1515692Y1549970I0J1202D01*
G01Y1549972D01*
G02X1515841Y1550551I1202J-1D01*
G01X1517407Y1553261D01*
X1517409Y1553264D01*
G37*
G36*
G01X1512685D02*
G02X1513745Y1553900I1060J-565D01*
G02X1514948Y1552698I1J-1202D01*
G02X1514787Y1552098I-1204J1D01*
G01X1513242Y1549425D01*
X1513240Y1549421D01*
G02X1512170Y1548768I-1070J550D01*
G02X1510968Y1549970I0J1202D01*
G01Y1549972D01*
G02X1511117Y1550551I1202J-1D01*
G01X1512683Y1553261D01*
X1512685Y1553264D01*
G37*
G36*
G01X1522134D02*
G02X1523194Y1553900I1060J-565D01*
G02X1524396Y1552698I0J-1202D01*
G02X1524236Y1552098I-1203J0D01*
G01X1522691Y1549425D01*
X1522689Y1549421D01*
G02X1521619Y1548768I-1070J550D01*
G02X1520416Y1549970I-1J1202D01*
G01Y1549972D01*
G02X1520566Y1550551I1203J-3D01*
G01X1522132Y1553261D01*
X1522134Y1553264D01*
G37*
G36*
G01X1498512D02*
G02X1499572Y1553900I1060J-565D01*
G02X1500774Y1552698I0J-1202D01*
G02X1500614Y1552098I-1203J0D01*
G01X1499069Y1549425D01*
X1499067Y1549421D01*
G02X1497997Y1548768I-1070J550D01*
G02X1496794Y1549970I-1J1202D01*
G01Y1549972D01*
G02X1496944Y1550551I1203J-3D01*
G01X1498510Y1553261D01*
X1498512Y1553264D01*
G37*
G36*
G01X1507961D02*
G02X1509021Y1553900I1060J-565D01*
G02X1510224Y1552698I1J-1202D01*
G02X1510063Y1552098I-1204J1D01*
G01X1508518Y1549425D01*
X1508516Y1549421D01*
G02X1507446Y1548768I-1070J550D01*
G02X1506244Y1549970I0J1202D01*
G01Y1549972D01*
G02X1506393Y1550551I1202J-1D01*
G01X1507959Y1553261D01*
X1507961Y1553264D01*
G37*
G36*
G01X1503236D02*
G02X1504296Y1553900I1060J-565D01*
G02X1505498Y1552698I0J-1202D01*
G02X1505338Y1552098I-1203J0D01*
G01X1503793Y1549425D01*
X1503791Y1549421D01*
G02X1502721Y1548768I-1070J550D01*
G02X1501518Y1549970I-1J1202D01*
G01Y1549972D01*
G02X1501668Y1550551I1203J-3D01*
G01X1503234Y1553261D01*
X1503236Y1553264D01*
G37*
G36*
G01X1493787D02*
G02X1494847Y1553900I1060J-565D01*
G02X1496050Y1552698I1J-1202D01*
G02X1495889Y1552098I-1204J1D01*
G01X1494344Y1549425D01*
X1494342Y1549421D01*
G02X1493272Y1548768I-1070J550D01*
G02X1492070Y1549970I0J1202D01*
G01Y1549972D01*
G02X1492219Y1550551I1202J-1D01*
G01X1493785Y1553261D01*
X1493787Y1553264D01*
G37*
G36*
G01X1484339D02*
G02X1485399Y1553900I1060J-565D01*
G02X1486602Y1552698I1J-1202D01*
G02X1486441Y1552098I-1204J1D01*
G01X1484896Y1549425D01*
X1484894Y1549421D01*
G02X1483824Y1548768I-1070J550D01*
G02X1482622Y1549970I0J1202D01*
G01Y1549972D01*
G02X1482771Y1550551I1202J-1D01*
G01X1484337Y1553261D01*
X1484339Y1553264D01*
G37*
G36*
G01X1489063D02*
G02X1490123Y1553900I1060J-565D01*
G02X1491326Y1552698I1J-1202D01*
G02X1491165Y1552098I-1204J1D01*
G01X1489620Y1549425D01*
X1489618Y1549421D01*
G02X1488548Y1548768I-1070J550D01*
G02X1487346Y1549970I0J1202D01*
G01Y1549972D01*
G02X1487495Y1550551I1202J-1D01*
G01X1489061Y1553261D01*
X1489063Y1553264D01*
G37*
G36*
G01X1479614D02*
G02X1480674Y1553900I1060J-565D01*
G02X1481876Y1552698I0J-1202D01*
G02X1481716Y1552098I-1203J0D01*
G01X1480171Y1549425D01*
X1480169Y1549421D01*
G02X1479099Y1548768I-1070J550D01*
G02X1477896Y1549970I-1J1202D01*
G01Y1549972D01*
G02X1478046Y1550551I1203J-3D01*
G01X1479612Y1553261D01*
X1479614Y1553264D01*
G37*
G36*
G01X1470165D02*
G02X1471225Y1553900I1060J-565D01*
G02X1472428Y1552698I1J-1202D01*
G02X1472267Y1552098I-1204J1D01*
G01X1470722Y1549425D01*
X1470720Y1549421D01*
G02X1469650Y1548768I-1070J550D01*
G02X1468448Y1549970I0J1202D01*
G01Y1549972D01*
G02X1468597Y1550551I1202J-1D01*
G01X1470163Y1553261D01*
X1470165Y1553264D01*
G37*
G36*
G01X1474890D02*
G02X1475950Y1553900I1060J-565D01*
G02X1477152Y1552698I0J-1202D01*
G02X1476992Y1552098I-1203J0D01*
G01X1475447Y1549425D01*
X1475445Y1549421D01*
G02X1474375Y1548768I-1070J550D01*
G02X1473172Y1549970I-1J1202D01*
G01Y1549972D01*
G02X1473322Y1550551I1203J-3D01*
G01X1474888Y1553261D01*
X1474890Y1553264D01*
G37*
G36*
G01X1465441D02*
G02X1466501Y1553900I1060J-565D01*
G02X1467704Y1552698I1J-1202D01*
G02X1467543Y1552098I-1204J1D01*
G01X1465998Y1549425D01*
X1465996Y1549421D01*
G02X1464926Y1548768I-1070J550D01*
G02X1463724Y1549970I0J1202D01*
G01Y1549972D01*
G02X1463873Y1550551I1202J-1D01*
G01X1465439Y1553261D01*
X1465441Y1553264D01*
G37*
G36*
G01X1460717D02*
G02X1461777Y1553900I1060J-565D01*
G02X1462980Y1552698I1J-1202D01*
G02X1462819Y1552098I-1204J1D01*
G01X1461274Y1549425D01*
X1461272Y1549421D01*
G02X1460202Y1548768I-1070J550D01*
G02X1459000Y1549970I0J1202D01*
G01Y1549972D01*
G02X1459149Y1550551I1202J-1D01*
G01X1460715Y1553261D01*
X1460717Y1553264D01*
G37*
G36*
G01X372126Y1215958D02*
G02Y1212952I0J-1503D01*
G01X368726D01*
G02Y1215958I0J1503D01*
G01X372126D01*
G37*
G36*
G01X613975Y1520264D02*
G02X615035Y1520900I1060J-565D01*
G02X616238Y1519698I1J-1202D01*
G02X616077Y1519098I-1204J1D01*
G01X614532Y1516425D01*
X614530Y1516421D01*
G02X613460Y1515768I-1070J550D01*
G02X612258Y1516970I0J1202D01*
G01Y1516972D01*
G02X612407Y1517551I1202J-1D01*
G01X613973Y1520261D01*
X613975Y1520264D01*
G37*
G36*
G01X642322D02*
G02X643382Y1520900I1060J-565D01*
G02X644584Y1519698I0J-1202D01*
G02X644424Y1519098I-1203J0D01*
G01X642879Y1516425D01*
X642877Y1516421D01*
G02X641807Y1515768I-1070J550D01*
G02X640604Y1516970I-1J1202D01*
G01Y1516972D01*
G02X640754Y1517551I1203J-3D01*
G01X642320Y1520261D01*
X642322Y1520264D01*
G37*
G36*
G01X609251D02*
G02X610311Y1520900I1060J-565D01*
G02X611514Y1519698I1J-1202D01*
G02X611353Y1519098I-1204J1D01*
G01X609808Y1516425D01*
X609806Y1516421D01*
G02X608736Y1515768I-1070J550D01*
G02X607534Y1516970I0J1202D01*
G01Y1516972D01*
G02X607683Y1517551I1202J-1D01*
G01X609249Y1520261D01*
X609251Y1520264D01*
G37*
G36*
G01X637597D02*
G02X638657Y1520900I1060J-565D01*
G02X639860Y1519698I1J-1202D01*
G02X639699Y1519098I-1204J1D01*
G01X638154Y1516425D01*
X638152Y1516421D01*
G02X637082Y1515768I-1070J550D01*
G02X635880Y1516970I0J1202D01*
G01Y1516972D01*
G02X636029Y1517551I1202J-1D01*
G01X637595Y1520261D01*
X637597Y1520264D01*
G37*
G36*
G01X595078D02*
G02X596138Y1520900I1060J-565D01*
G02X597340Y1519698I0J-1202D01*
G02X597180Y1519098I-1203J0D01*
G01X595635Y1516425D01*
X595633Y1516421D01*
G02X594563Y1515768I-1070J550D01*
G02X593360Y1516970I-1J1202D01*
G01Y1516972D01*
G02X593510Y1517551I1203J-3D01*
G01X595076Y1520261D01*
X595078Y1520264D01*
G37*
G36*
G01X647046D02*
G02X648106Y1520900I1060J-565D01*
G02X649308Y1519698I0J-1202D01*
G02X649148Y1519098I-1203J0D01*
G01X647603Y1516425D01*
X647601Y1516421D01*
G02X646531Y1515768I-1070J550D01*
G02X645328Y1516970I-1J1202D01*
G01Y1516972D01*
G02X645478Y1517551I1203J-3D01*
G01X647044Y1520261D01*
X647046Y1520264D01*
G37*
G36*
G01X590353D02*
G02X591413Y1520900I1060J-565D01*
G02X592616Y1519698I1J-1202D01*
G02X592455Y1519098I-1204J1D01*
G01X590910Y1516425D01*
X590908Y1516421D01*
G02X589838Y1515768I-1070J550D01*
G02X588636Y1516970I0J1202D01*
G01Y1516972D01*
G02X588785Y1517551I1202J-1D01*
G01X590351Y1520261D01*
X590353Y1520264D01*
G37*
G36*
G01X604527D02*
G02X605587Y1520900I1060J-565D01*
G02X606790Y1519698I1J-1202D01*
G02X606629Y1519098I-1204J1D01*
G01X605084Y1516425D01*
X605082Y1516421D01*
G02X604012Y1515768I-1070J550D01*
G02X602810Y1516970I0J1202D01*
G01Y1516972D01*
G02X602959Y1517551I1202J-1D01*
G01X604525Y1520261D01*
X604527Y1520264D01*
G37*
G36*
G01X628149D02*
G02X629209Y1520900I1060J-565D01*
G02X630412Y1519698I1J-1202D01*
G02X630251Y1519098I-1204J1D01*
G01X628706Y1516425D01*
X628704Y1516421D01*
G02X627634Y1515768I-1070J550D01*
G02X626432Y1516970I0J1202D01*
G01Y1516972D01*
G02X626581Y1517551I1202J-1D01*
G01X628147Y1520261D01*
X628149Y1520264D01*
G37*
G36*
G01X618700D02*
G02X619760Y1520900I1060J-565D01*
G02X620962Y1519698I0J-1202D01*
G02X620802Y1519098I-1203J0D01*
G01X619257Y1516425D01*
X619255Y1516421D01*
G02X618185Y1515768I-1070J550D01*
G02X616982Y1516970I-1J1202D01*
G01Y1516972D01*
G02X617132Y1517551I1203J-3D01*
G01X618698Y1520261D01*
X618700Y1520264D01*
G37*
G36*
G01X599802D02*
G02X600862Y1520900I1060J-565D01*
G02X602064Y1519698I0J-1202D01*
G02X601904Y1519098I-1203J0D01*
G01X600359Y1516425D01*
X600357Y1516421D01*
G02X599287Y1515768I-1070J550D01*
G02X598084Y1516970I-1J1202D01*
G01Y1516972D01*
G02X598234Y1517551I1203J-3D01*
G01X599800Y1520261D01*
X599802Y1520264D01*
G37*
G36*
G01X623424D02*
G02X624484Y1520900I1060J-565D01*
G02X625686Y1519698I0J-1202D01*
G02X625526Y1519098I-1203J0D01*
G01X623981Y1516425D01*
X623979Y1516421D01*
G02X622909Y1515768I-1070J550D01*
G02X621706Y1516970I-1J1202D01*
G01Y1516972D01*
G02X621856Y1517551I1203J-3D01*
G01X623422Y1520261D01*
X623424Y1520264D01*
G37*
G36*
G01X580905D02*
G02X581965Y1520900I1060J-565D01*
G02X583168Y1519698I1J-1202D01*
G02X583007Y1519098I-1204J1D01*
G01X581462Y1516425D01*
X581460Y1516421D01*
G02X580390Y1515768I-1070J550D01*
G02X579188Y1516970I0J1202D01*
G01Y1516972D01*
G02X579337Y1517551I1202J-1D01*
G01X580903Y1520261D01*
X580905Y1520264D01*
G37*
G36*
G01X632873D02*
G02X633933Y1520900I1060J-565D01*
G02X635136Y1519698I1J-1202D01*
G02X634975Y1519098I-1204J1D01*
G01X633430Y1516425D01*
X633428Y1516421D01*
G02X632358Y1515768I-1070J550D01*
G02X631156Y1516970I0J1202D01*
G01Y1516972D01*
G02X631305Y1517551I1202J-1D01*
G01X632871Y1520261D01*
X632873Y1520264D01*
G37*
G36*
G01X585629D02*
G02X586689Y1520900I1060J-565D01*
G02X587892Y1519698I1J-1202D01*
G02X587731Y1519098I-1204J1D01*
G01X586186Y1516425D01*
X586184Y1516421D01*
G02X585114Y1515768I-1070J550D01*
G02X583912Y1516970I0J1202D01*
G01Y1516972D01*
G02X584061Y1517551I1202J-1D01*
G01X585627Y1520261D01*
X585629Y1520264D01*
G37*
G36*
G01X481189D02*
G02X482249Y1520900I1060J-565D01*
G02X483452Y1519698I1J-1202D01*
G02X483291Y1519098I-1204J1D01*
G01X481746Y1516425D01*
X481744Y1516421D01*
G02X480674Y1515768I-1070J550D01*
G02X479472Y1516970I0J1202D01*
G01Y1516972D01*
G02X479621Y1517551I1202J-1D01*
G01X481187Y1520261D01*
X481189Y1520264D01*
G37*
G36*
G01X518984D02*
G02X520044Y1520900I1060J-565D01*
G02X521246Y1519698I0J-1202D01*
G02X521086Y1519098I-1203J0D01*
G01X519541Y1516425D01*
X519539Y1516421D01*
G02X518469Y1515768I-1070J550D01*
G02X517266Y1516970I-1J1202D01*
G01Y1516972D01*
G02X517416Y1517551I1203J-3D01*
G01X518982Y1520261D01*
X518984Y1520264D01*
G37*
G36*
G01X471740D02*
G02X472800Y1520900I1060J-565D01*
G02X474002Y1519698I0J-1202D01*
G02X473842Y1519098I-1203J0D01*
G01X472297Y1516425D01*
X472295Y1516421D01*
G02X471225Y1515768I-1070J550D01*
G02X470022Y1516970I-1J1202D01*
G01Y1516972D01*
G02X470172Y1517551I1203J-3D01*
G01X471738Y1520261D01*
X471740Y1520264D01*
G37*
G36*
G01X514260D02*
G02X515320Y1520900I1060J-565D01*
G02X516522Y1519698I0J-1202D01*
G02X516362Y1519098I-1203J0D01*
G01X514817Y1516425D01*
X514815Y1516421D01*
G02X513745Y1515768I-1070J550D01*
G02X512542Y1516970I-1J1202D01*
G01Y1516972D01*
G02X512692Y1517551I1203J-3D01*
G01X514258Y1520261D01*
X514260Y1520264D01*
G37*
G36*
G01X476465D02*
G02X477525Y1520900I1060J-565D01*
G02X478728Y1519698I1J-1202D01*
G02X478567Y1519098I-1204J1D01*
G01X477022Y1516425D01*
X477020Y1516421D01*
G02X475950Y1515768I-1070J550D01*
G02X474748Y1516970I0J1202D01*
G01Y1516972D01*
G02X474897Y1517551I1202J-1D01*
G01X476463Y1520261D01*
X476465Y1520264D01*
G37*
G36*
G01X1395471Y1553264D02*
G02X1396531Y1553900I1060J-565D01*
G02X1397734Y1552698I1J-1202D01*
G02X1397573Y1552098I-1204J1D01*
G01X1396028Y1549425D01*
X1396026Y1549421D01*
G02X1394956Y1548768I-1070J550D01*
G02X1393754Y1549970I0J1202D01*
G01Y1549972D01*
G02X1393903Y1550551I1202J-1D01*
G01X1395469Y1553261D01*
X1395471Y1553264D01*
G37*
G36*
G01X1386022D02*
G02X1387082Y1553900I1060J-565D01*
G02X1388284Y1552698I0J-1202D01*
G02X1388124Y1552098I-1203J0D01*
G01X1386579Y1549425D01*
X1386577Y1549421D01*
G02X1385507Y1548768I-1070J550D01*
G02X1384304Y1549970I-1J1202D01*
G01Y1549972D01*
G02X1384454Y1550551I1203J-3D01*
G01X1386020Y1553261D01*
X1386022Y1553264D01*
G37*
G36*
G01X1376573D02*
G02X1377633Y1553900I1060J-565D01*
G02X1378836Y1552698I1J-1202D01*
G02X1378675Y1552098I-1204J1D01*
G01X1377130Y1549425D01*
X1377128Y1549421D01*
G02X1376058Y1548768I-1070J550D01*
G02X1374856Y1549970I0J1202D01*
G01Y1549972D01*
G02X1375005Y1550551I1202J-1D01*
G01X1376571Y1553261D01*
X1376573Y1553264D01*
G37*
G36*
G01X504811Y1520264D02*
G02X505871Y1520900I1060J-565D01*
G02X507074Y1519698I1J-1202D01*
G02X506913Y1519098I-1204J1D01*
G01X505368Y1516425D01*
X505366Y1516421D01*
G02X504296Y1515768I-1070J550D01*
G02X503094Y1516970I0J1202D01*
G01Y1516972D01*
G02X503243Y1517551I1202J-1D01*
G01X504809Y1520261D01*
X504811Y1520264D01*
G37*
G36*
G01X495362D02*
G02X496422Y1520900I1060J-565D01*
G02X497624Y1519698I0J-1202D01*
G02X497464Y1519098I-1203J0D01*
G01X495919Y1516425D01*
X495917Y1516421D01*
G02X494847Y1515768I-1070J550D01*
G02X493644Y1516970I-1J1202D01*
G01Y1516972D01*
G02X493794Y1517551I1203J-3D01*
G01X495360Y1520261D01*
X495362Y1520264D01*
G37*
G36*
G01X523709D02*
G02X524769Y1520900I1060J-565D01*
G02X525972Y1519698I1J-1202D01*
G02X525811Y1519098I-1204J1D01*
G01X524266Y1516425D01*
X524264Y1516421D01*
G02X523194Y1515768I-1070J550D01*
G02X521992Y1516970I0J1202D01*
G01Y1516972D01*
G02X522141Y1517551I1202J-1D01*
G01X523707Y1520261D01*
X523709Y1520264D01*
G37*
G36*
G01X452843D02*
G02X453903Y1520900I1060J-565D01*
G02X455106Y1519698I1J-1202D01*
G02X454945Y1519098I-1204J1D01*
G01X453400Y1516425D01*
X453398Y1516421D01*
G02X452328Y1515768I-1070J550D01*
G02X451126Y1516970I0J1202D01*
G01Y1516972D01*
G02X451275Y1517551I1202J-1D01*
G01X452841Y1520261D01*
X452843Y1520264D01*
G37*
G36*
G01X457567D02*
G02X458627Y1520900I1060J-565D01*
G02X459830Y1519698I1J-1202D01*
G02X459669Y1519098I-1204J1D01*
G01X458124Y1516425D01*
X458122Y1516421D01*
G02X457052Y1515768I-1070J550D01*
G02X455850Y1516970I0J1202D01*
G01Y1516972D01*
G02X455999Y1517551I1202J-1D01*
G01X457565Y1520261D01*
X457567Y1520264D01*
G37*
G36*
G01X691276Y1453610D02*
G02Y1456614I0J1502D01*
G01X694676D01*
G02Y1453610I0J-1502D01*
G01X691276D01*
G37*
G36*
G01X1338778Y1553264D02*
G02X1339838Y1553900I1060J-565D01*
G02X1341040Y1552698I0J-1202D01*
G02X1340880Y1552098I-1203J0D01*
G01X1339335Y1549425D01*
X1339333Y1549421D01*
G02X1338263Y1548768I-1070J550D01*
G02X1337060Y1549970I-1J1202D01*
G01Y1549972D01*
G02X1337210Y1550551I1203J-3D01*
G01X1338776Y1553261D01*
X1338778Y1553264D01*
G37*
G36*
G01X467016Y1520264D02*
G02X468076Y1520900I1060J-565D01*
G02X469278Y1519698I0J-1202D01*
G02X469118Y1519098I-1203J0D01*
G01X467573Y1516425D01*
X467571Y1516421D01*
G02X466501Y1515768I-1070J550D01*
G02X465298Y1516970I-1J1202D01*
G01Y1516972D01*
G02X465448Y1517551I1203J-3D01*
G01X467014Y1520261D01*
X467016Y1520264D01*
G37*
G36*
G01X485913D02*
G02X486973Y1520900I1060J-565D01*
G02X488176Y1519698I1J-1202D01*
G02X488015Y1519098I-1204J1D01*
G01X486470Y1516425D01*
X486468Y1516421D01*
G02X485398Y1515768I-1070J550D01*
G02X484196Y1516970I0J1202D01*
G01Y1516972D01*
G02X484345Y1517551I1202J-1D01*
G01X485911Y1520261D01*
X485913Y1520264D01*
G37*
G36*
G01X382873D02*
G02X383933Y1520900I1060J-565D01*
G02X385136Y1519698I1J-1202D01*
G02X384975Y1519098I-1204J1D01*
G01X383430Y1516425D01*
X383428Y1516421D01*
G02X382358Y1515768I-1070J550D01*
G02X381156Y1516970I0J1202D01*
G01Y1516972D01*
G02X381305Y1517551I1202J-1D01*
G01X382871Y1520261D01*
X382873Y1520264D01*
G37*
G36*
G01X340354D02*
G02X341414Y1520900I1060J-565D01*
G02X342616Y1519698I0J-1202D01*
G02X342456Y1519098I-1203J0D01*
G01X340911Y1516425D01*
X340909Y1516421D01*
G02X339839Y1515768I-1070J550D01*
G02X338636Y1516970I-1J1202D01*
G01Y1516972D01*
G02X338786Y1517551I1203J-3D01*
G01X340352Y1520261D01*
X340354Y1520264D01*
G37*
G36*
G01X387598D02*
G02X388658Y1520900I1060J-565D01*
G02X389860Y1519698I0J-1202D01*
G02X389700Y1519098I-1203J0D01*
G01X388155Y1516425D01*
X388153Y1516421D01*
G02X387083Y1515768I-1070J550D01*
G02X385880Y1516970I-1J1202D01*
G01Y1516972D01*
G02X386030Y1517551I1203J-3D01*
G01X387596Y1520261D01*
X387598Y1520264D01*
G37*
G36*
G01X462291D02*
G02X463351Y1520900I1060J-565D01*
G02X464554Y1519698I1J-1202D01*
G02X464393Y1519098I-1204J1D01*
G01X462848Y1516425D01*
X462846Y1516421D01*
G02X461776Y1515768I-1070J550D01*
G02X460574Y1516970I0J1202D01*
G01Y1516972D01*
G02X460723Y1517551I1202J-1D01*
G01X462289Y1520261D01*
X462291Y1520264D01*
G37*
G36*
G01X490638D02*
G02X491698Y1520900I1060J-565D01*
G02X492900Y1519698I0J-1202D01*
G02X492740Y1519098I-1203J0D01*
G01X491195Y1516425D01*
X491193Y1516421D01*
G02X490123Y1515768I-1070J550D01*
G02X488920Y1516970I-1J1202D01*
G01Y1516972D01*
G02X489070Y1517551I1203J-3D01*
G01X490636Y1520261D01*
X490638Y1520264D01*
G37*
G36*
G01X1371849Y1553264D02*
G02X1372909Y1553900I1060J-565D01*
G02X1374112Y1552698I1J-1202D01*
G02X1373951Y1552098I-1204J1D01*
G01X1372406Y1549425D01*
X1372404Y1549421D01*
G02X1371334Y1548768I-1070J550D01*
G02X1370132Y1549970I0J1202D01*
G01Y1549972D01*
G02X1370281Y1550551I1202J-1D01*
G01X1371847Y1553261D01*
X1371849Y1553264D01*
G37*
G36*
G01X1362400D02*
G02X1363460Y1553900I1060J-565D01*
G02X1364662Y1552698I0J-1202D01*
G02X1364502Y1552098I-1203J0D01*
G01X1362957Y1549425D01*
X1362955Y1549421D01*
G02X1361885Y1548768I-1070J550D01*
G02X1360682Y1549970I-1J1202D01*
G01Y1549972D01*
G02X1360832Y1550551I1203J-3D01*
G01X1362398Y1553261D01*
X1362400Y1553264D01*
G37*
G36*
G01X1367124D02*
G02X1368184Y1553900I1060J-565D01*
G02X1369386Y1552698I0J-1202D01*
G02X1369226Y1552098I-1203J0D01*
G01X1367681Y1549425D01*
X1367679Y1549421D01*
G02X1366609Y1548768I-1070J550D01*
G02X1365406Y1549970I-1J1202D01*
G01Y1549972D01*
G02X1365556Y1550551I1203J-3D01*
G01X1367122Y1553261D01*
X1367124Y1553264D01*
G37*
G36*
G01X1343502D02*
G02X1344562Y1553900I1060J-565D01*
G02X1345764Y1552698I0J-1202D01*
G02X1345604Y1552098I-1203J0D01*
G01X1344059Y1549425D01*
X1344057Y1549421D01*
G02X1342987Y1548768I-1070J550D01*
G02X1341784Y1549970I-1J1202D01*
G01Y1549972D01*
G02X1341934Y1550551I1203J-3D01*
G01X1343500Y1553261D01*
X1343502Y1553264D01*
G37*
G36*
G01X1348227D02*
G02X1349287Y1553900I1060J-565D01*
G02X1350490Y1552698I1J-1202D01*
G02X1350329Y1552098I-1204J1D01*
G01X1348784Y1549425D01*
X1348782Y1549421D01*
G02X1347712Y1548768I-1070J550D01*
G02X1346510Y1549970I0J1202D01*
G01Y1549972D01*
G02X1346659Y1550551I1202J-1D01*
G01X1348225Y1553261D01*
X1348227Y1553264D01*
G37*
G36*
G01X1352951D02*
G02X1354011Y1553900I1060J-565D01*
G02X1355214Y1552698I1J-1202D01*
G02X1355053Y1552098I-1204J1D01*
G01X1353508Y1549425D01*
X1353506Y1549421D01*
G02X1352436Y1548768I-1070J550D01*
G02X1351234Y1549970I0J1202D01*
G01Y1549972D01*
G02X1351383Y1550551I1202J-1D01*
G01X1352949Y1553261D01*
X1352951Y1553264D01*
G37*
G36*
G01X240638Y1520264D02*
G02X241698Y1520900I1060J-565D01*
G02X242900Y1519698I0J-1202D01*
G02X242740Y1519098I-1203J0D01*
G01X241195Y1516425D01*
X241193Y1516421D01*
G02X240123Y1515768I-1070J550D01*
G02X238920Y1516970I-1J1202D01*
G01Y1516972D01*
G02X239070Y1517551I1203J-3D01*
G01X240636Y1520261D01*
X240638Y1520264D01*
G37*
G36*
G01X188670D02*
G02X189730Y1520900I1060J-565D01*
G02X190932Y1519698I0J-1202D01*
G02X190772Y1519098I-1203J0D01*
G01X189227Y1516425D01*
X189225Y1516421D01*
G02X188155Y1515768I-1070J550D01*
G02X186952Y1516970I-1J1202D01*
G01Y1516972D01*
G02X187102Y1517551I1203J-3D01*
G01X188668Y1520261D01*
X188670Y1520264D01*
G37*
G36*
G01X245362D02*
G02X246422Y1520900I1060J-565D01*
G02X247624Y1519698I0J-1202D01*
G02X247464Y1519098I-1203J0D01*
G01X245919Y1516425D01*
X245917Y1516421D01*
G02X244847Y1515768I-1070J550D01*
G02X243644Y1516970I-1J1202D01*
G01Y1516972D01*
G02X243794Y1517551I1203J-3D01*
G01X245360Y1520261D01*
X245362Y1520264D01*
G37*
G36*
G01X217016D02*
G02X218076Y1520900I1060J-565D01*
G02X219278Y1519698I0J-1202D01*
G02X219118Y1519098I-1203J0D01*
G01X217573Y1516425D01*
X217571Y1516421D01*
G02X216501Y1515768I-1070J550D01*
G02X215298Y1516970I-1J1202D01*
G01Y1516972D01*
G02X215448Y1517551I1203J-3D01*
G01X217014Y1520261D01*
X217016Y1520264D01*
G37*
G36*
G01X193394D02*
G02X194454Y1520900I1060J-565D01*
G02X195656Y1519698I0J-1202D01*
G02X195496Y1519098I-1203J0D01*
G01X193951Y1516425D01*
X193949Y1516421D01*
G02X192879Y1515768I-1070J550D01*
G02X191676Y1516970I-1J1202D01*
G01Y1516972D01*
G02X191826Y1517551I1203J-3D01*
G01X193392Y1520261D01*
X193394Y1520264D01*
G37*
G36*
G01X1210716Y1553264D02*
G02X1211776Y1553900I1060J-565D01*
G02X1212978Y1552698I0J-1202D01*
G02X1212818Y1552098I-1203J0D01*
G01X1211273Y1549425D01*
X1211271Y1549421D01*
G02X1210201Y1548768I-1070J550D01*
G02X1208998Y1549970I-1J1202D01*
G01Y1549972D01*
G02X1209148Y1550551I1203J-3D01*
G01X1210714Y1553261D01*
X1210716Y1553264D01*
G37*
G36*
G01X1196543D02*
G02X1197603Y1553900I1060J-565D01*
G02X1198806Y1552698I1J-1202D01*
G02X1198645Y1552098I-1204J1D01*
G01X1197100Y1549425D01*
X1197098Y1549421D01*
G02X1196028Y1548768I-1070J550D01*
G02X1194826Y1549970I0J1202D01*
G01Y1549972D01*
G02X1194975Y1550551I1202J-1D01*
G01X1196541Y1553261D01*
X1196543Y1553264D01*
G37*
G36*
G01X198118Y1520264D02*
G02X199178Y1520900I1060J-565D01*
G02X200380Y1519698I0J-1202D01*
G02X200220Y1519098I-1203J0D01*
G01X198675Y1516425D01*
X198673Y1516421D01*
G02X197603Y1515768I-1070J550D01*
G02X196400Y1516970I-1J1202D01*
G01Y1516972D01*
G02X196550Y1517551I1203J-3D01*
G01X198116Y1520261D01*
X198118Y1520264D01*
G37*
G36*
G01X1201267Y1553264D02*
G02X1202327Y1553900I1060J-565D01*
G02X1203530Y1552698I1J-1202D01*
G02X1203369Y1552098I-1204J1D01*
G01X1201824Y1549425D01*
X1201822Y1549421D01*
G02X1200752Y1548768I-1070J550D01*
G02X1199550Y1549970I0J1202D01*
G01Y1549972D01*
G02X1199699Y1550551I1202J-1D01*
G01X1201265Y1553261D01*
X1201267Y1553264D01*
G37*
G36*
G01X651771Y1520264D02*
G02X652831Y1520900I1060J-565D01*
G02X654034Y1519698I1J-1202D01*
G02X653873Y1519098I-1204J1D01*
G01X652328Y1516425D01*
X652326Y1516421D01*
G02X651256Y1515768I-1070J550D01*
G02X650054Y1516970I0J1202D01*
G01Y1516972D01*
G02X650203Y1517551I1202J-1D01*
G01X651769Y1520261D01*
X651771Y1520264D01*
G37*
G36*
G01X226465D02*
G02X227525Y1520900I1060J-565D01*
G02X228728Y1519698I1J-1202D01*
G02X228567Y1519098I-1204J1D01*
G01X227022Y1516425D01*
X227020Y1516421D01*
G02X225950Y1515768I-1070J550D01*
G02X224748Y1516970I0J1202D01*
G01Y1516972D01*
G02X224897Y1517551I1202J-1D01*
G01X226463Y1520261D01*
X226465Y1520264D01*
G37*
G36*
G01X509535D02*
G02X510595Y1520900I1060J-565D01*
G02X511798Y1519698I1J-1202D01*
G02X511637Y1519098I-1204J1D01*
G01X510092Y1516425D01*
X510090Y1516421D01*
G02X509020Y1515768I-1070J550D01*
G02X507818Y1516970I0J1202D01*
G01Y1516972D01*
G02X507967Y1517551I1202J-1D01*
G01X509533Y1520261D01*
X509535Y1520264D01*
G37*
G36*
G01X1385686Y1494092D02*
G02Y1497098I0J1503D01*
G01X1389086D01*
G02Y1494092I0J-1503D01*
G01X1385686D01*
G37*
G36*
G01X269851Y1451392D02*
G02Y1454398I0J1503D01*
G01X273251D01*
G02Y1451392I0J-1503D01*
G01X269851D01*
G37*
G36*
G01X256451D02*
G02Y1454398I0J1503D01*
G01X259851D01*
G02Y1451392I0J-1503D01*
G01X256451D01*
G37*
G36*
G01X249751Y1461092D02*
G02Y1464098I0J1503D01*
G01X253151D01*
G02Y1461092I0J-1503D01*
G01X249751D01*
G37*
G36*
G01X243051Y1470792D02*
G02Y1473798I0J1503D01*
G01X246451D01*
G02Y1470792I0J-1503D01*
G01X243051D01*
G37*
G36*
G01X229651Y1451392D02*
G02Y1454398I0J1503D01*
G01X233051D01*
G02Y1451392I0J-1503D01*
G01X229651D01*
G37*
G36*
G01X222951Y1461092D02*
G02Y1464098I0J1503D01*
G01X226351D01*
G02Y1461092I0J-1503D01*
G01X222951D01*
G37*
G36*
G01X216251Y1470792D02*
G02Y1473798I0J1503D01*
G01X219651D01*
G02Y1470792I0J-1503D01*
G01X216251D01*
G37*
G36*
G01X202851Y1451392D02*
G02Y1454398I0J1503D01*
G01X206251D01*
G02Y1451392I0J-1503D01*
G01X202851D01*
G37*
G36*
G01X196151Y1461092D02*
G02Y1464098I0J1503D01*
G01X199551D01*
G02Y1461092I0J-1503D01*
G01X196151D01*
G37*
G36*
G01X189451Y1470792D02*
G02Y1473798I0J1503D01*
G01X192851D01*
G02Y1470792I0J-1503D01*
G01X189451D01*
G37*
G36*
G01X176051Y1451392D02*
G02Y1454398I0J1503D01*
G01X179451D01*
G02Y1451392I0J-1503D01*
G01X176051D01*
G37*
G36*
G01X212286Y1590878D02*
G02Y1593882I0J1502D01*
G01X215686D01*
G02Y1590878I0J-1502D01*
G01X212286D01*
G37*
G36*
G01X200226D02*
G02Y1593882I0J1502D01*
G01X203626D01*
G02Y1590878I0J-1502D01*
G01X200226D01*
G37*
G36*
G01X1310609Y1633878D02*
G02Y1636882I0J1502D01*
G01X1314009D01*
G02Y1633878I0J-1502D01*
G01X1310609D01*
G37*
G36*
G01X1490363D02*
G02Y1636882I0J1502D01*
G01X1493763D01*
G02Y1633878I0J-1502D01*
G01X1490363D01*
G37*
G36*
G01X491919Y1593882D02*
G02Y1590878I0J-1502D01*
G01X488519D01*
G02Y1593882I0J1502D01*
G01X491919D01*
G37*
G36*
G01X500579Y1590878D02*
G02Y1593882I0J1502D01*
G01X503979D01*
G02Y1590878I0J-1502D01*
G01X500579D01*
G37*
G36*
G01X194196Y1600878D02*
G02Y1603882I0J1502D01*
G01X197596D01*
G02Y1600878I0J-1502D01*
G01X194196D01*
G37*
G36*
G01X350976D02*
G02Y1603882I0J1502D01*
G01X354376D01*
G02Y1600878I0J-1502D01*
G01X350976D01*
G37*
G36*
G01X194196Y1612790D02*
G02Y1615794I0J1502D01*
G01X197596D01*
G02Y1612790I0J-1502D01*
G01X194196D01*
G37*
G36*
G01X330913Y1451392D02*
G02Y1454398I0J1503D01*
G01X334313D01*
G02Y1451392I0J-1503D01*
G01X330913D01*
G37*
G36*
G01X1376939Y1655790D02*
G02Y1658794I0J1502D01*
G01X1380339D01*
G02Y1655790I0J-1502D01*
G01X1376939D01*
G37*
G36*
G01Y1623878D02*
G02Y1626882I0J1502D01*
G01X1380339D01*
G02Y1623878I0J-1502D01*
G01X1376939D01*
G37*
G36*
G01X1220159D02*
G02Y1626882I0J1502D01*
G01X1223559D01*
G02Y1623878I0J-1502D01*
G01X1220159D01*
G37*
G36*
G01X572939Y1590878D02*
G02Y1593882I0J1502D01*
G01X576339D01*
G02Y1590878I0J-1502D01*
G01X572939D01*
G37*
G36*
G01X536759D02*
G02Y1593882I0J1502D01*
G01X540159D01*
G02Y1590878I0J-1502D01*
G01X536759D01*
G37*
G36*
G01X344946D02*
G02Y1593882I0J1502D01*
G01X348346D01*
G02Y1590878I0J-1502D01*
G01X344946D01*
G37*
G36*
G01X248466D02*
G02Y1593882I0J1502D01*
G01X251866D01*
G02Y1590878I0J-1502D01*
G01X248466D01*
G37*
G36*
G01X230376Y1600878D02*
G02Y1603882I0J1502D01*
G01X233776D01*
G02Y1600878I0J-1502D01*
G01X230376D01*
G37*
G36*
G01X206256D02*
G02Y1603882I0J1502D01*
G01X209656D01*
G02Y1600878I0J-1502D01*
G01X206256D01*
G37*
G36*
G01X236406Y1590878D02*
G02Y1593882I0J1502D01*
G01X239806D01*
G02Y1590878I0J-1502D01*
G01X236406D01*
G37*
G36*
G01X554849Y1600878D02*
G02Y1603882I0J1502D01*
G01X558249D01*
G02Y1600878I0J-1502D01*
G01X554849D01*
G37*
G36*
G01X470429D02*
G02Y1603882I0J1502D01*
G01X473829D01*
G02Y1600878I0J-1502D01*
G01X470429D01*
G37*
G36*
G01X482489D02*
G02Y1603882I0J1502D01*
G01X485889D01*
G02Y1600878I0J-1502D01*
G01X482489D01*
G37*
G36*
G01X1370909Y1633878D02*
G02Y1636882I0J1502D01*
G01X1374309D01*
G02Y1633878I0J-1502D01*
G01X1370909D01*
G37*
G36*
G01X1358849D02*
G02Y1636882I0J1502D01*
G01X1362249D01*
G02Y1633878I0J-1502D01*
G01X1358849D01*
G37*
G36*
G01X1346789D02*
G02Y1636882I0J1502D01*
G01X1350189D01*
G02Y1633878I0J-1502D01*
G01X1346789D01*
G37*
G36*
G01X1528498Y1484392D02*
G02Y1487398I0J1503D01*
G01X1531898D01*
G02Y1484392I0J-1503D01*
G01X1528498D01*
G37*
G36*
G01X1468198Y1494092D02*
G02Y1497098I0J1503D01*
G01X1471598D01*
G02Y1494092I0J-1503D01*
G01X1468198D01*
G37*
G36*
G01X615186Y1461092D02*
G02Y1464098I0J1503D01*
G01X618586D01*
G02Y1461092I0J-1503D01*
G01X615186D01*
G37*
G36*
G01X453624Y1470792D02*
G02Y1473798I0J1503D01*
G01X457024D01*
G02Y1470792I0J-1503D01*
G01X453624D01*
G37*
G36*
G01X1673360Y1487398D02*
G02Y1484392I0J-1503D01*
G01X1669960D01*
G02Y1487398I0J1503D01*
G01X1673360D01*
G37*
G36*
G01X1629760Y1484392D02*
G02Y1487398I0J1503D01*
G01X1633160D01*
G02Y1484392I0J-1503D01*
G01X1629760D01*
G37*
G36*
G01X1541898D02*
G02Y1487398I0J1503D01*
G01X1545298D01*
G02Y1484392I0J-1503D01*
G01X1541898D01*
G37*
G36*
G01X1501698D02*
G02Y1487398I0J1503D01*
G01X1505098D01*
G02Y1484392I0J-1503D01*
G01X1501698D01*
G37*
G36*
G01X1405786D02*
G02Y1487398I0J1503D01*
G01X1409186D01*
G02Y1484392I0J-1503D01*
G01X1405786D01*
G37*
G36*
G01X1365586D02*
G02Y1487398I0J1503D01*
G01X1368986D01*
G02Y1484392I0J-1503D01*
G01X1365586D01*
G37*
G36*
G01X1305286Y1494092D02*
G02Y1497098I0J1503D01*
G01X1308686D01*
G02Y1494092I0J-1503D01*
G01X1305286D01*
G37*
G36*
G01X1277724Y1484392D02*
G02Y1487398I0J1503D01*
G01X1281124D01*
G02Y1484392I0J-1503D01*
G01X1277724D01*
G37*
G36*
G01X1264324D02*
G02Y1487398I0J1503D01*
G01X1267724D01*
G02Y1484392I0J-1503D01*
G01X1264324D01*
G37*
G36*
G01X662086Y1451392D02*
G02Y1454398I0J1503D01*
G01X665486D01*
G02Y1451392I0J-1503D01*
G01X662086D01*
G37*
G36*
G01X621886D02*
G02Y1454398I0J1503D01*
G01X625286D01*
G02Y1451392I0J-1503D01*
G01X621886D01*
G37*
G36*
G01X534024D02*
G02Y1454398I0J1503D01*
G01X537424D01*
G02Y1451392I0J-1503D01*
G01X534024D01*
G37*
G36*
G01X520624D02*
G02Y1454398I0J1503D01*
G01X524024D01*
G02Y1451392I0J-1503D01*
G01X520624D01*
G37*
G36*
G01X397913D02*
G02Y1454398I0J1503D01*
G01X401313D01*
G02Y1451392I0J-1503D01*
G01X397913D01*
G37*
G36*
G01X371113Y1470792D02*
G02Y1473798I0J1503D01*
G01X374513D01*
G02Y1470792I0J-1503D01*
G01X371113D01*
G37*
G36*
G01X317513D02*
G02Y1473798I0J1503D01*
G01X320913D01*
G02Y1470792I0J-1503D01*
G01X317513D01*
G37*
G36*
G01X250087Y1520264D02*
G02X251147Y1520900I1060J-565D01*
G02X252350Y1519698I1J-1202D01*
G02X252189Y1519098I-1204J1D01*
G01X250644Y1516425D01*
X250642Y1516421D01*
G02X249572Y1515768I-1070J550D01*
G02X248370Y1516970I0J1202D01*
G01Y1516972D01*
G02X248519Y1517551I1202J-1D01*
G01X250085Y1520261D01*
X250087Y1520264D01*
G37*
G36*
G01X357713Y1451392D02*
G02Y1454398I0J1503D01*
G01X361113D01*
G02Y1451392I0J-1503D01*
G01X357713D01*
G37*
G36*
G01X1496393Y1623878D02*
G02Y1626882I0J1502D01*
G01X1499793D01*
G02Y1623878I0J-1502D01*
G01X1496393D01*
G37*
G36*
G01X1508453D02*
G02Y1626882I0J1502D01*
G01X1511853D01*
G02Y1623878I0J-1502D01*
G01X1508453D01*
G37*
G36*
G01X1322669Y1633878D02*
G02Y1636882I0J1502D01*
G01X1326069D01*
G02Y1633878I0J-1502D01*
G01X1322669D01*
G37*
G36*
G01X597059Y1590878D02*
G02Y1593882I0J1502D01*
G01X600459D01*
G02Y1590878I0J-1502D01*
G01X597059D01*
G37*
G36*
G01X476459Y1622790D02*
G02Y1625794I0J1502D01*
G01X479859D01*
G02Y1622790I0J-1502D01*
G01X476459D01*
G37*
G36*
G01X1215440Y1553264D02*
G02X1216500Y1553900I1060J-565D01*
G02X1217702Y1552698I0J-1202D01*
G02X1217542Y1552098I-1203J0D01*
G01X1215997Y1549425D01*
X1215995Y1549421D01*
G02X1214925Y1548768I-1070J550D01*
G02X1213722Y1549970I-1J1202D01*
G01Y1549972D01*
G02X1213872Y1550551I1203J-3D01*
G01X1215438Y1553261D01*
X1215440Y1553264D01*
G37*
G36*
G01X1220165D02*
G02X1221225Y1553900I1060J-565D01*
G02X1222428Y1552698I1J-1202D01*
G02X1222267Y1552098I-1204J1D01*
G01X1220722Y1549425D01*
X1220720Y1549421D01*
G02X1219650Y1548768I-1070J550D01*
G02X1218448Y1549970I0J1202D01*
G01Y1549972D01*
G02X1218597Y1550551I1202J-1D01*
G01X1220163Y1553261D01*
X1220165Y1553264D01*
G37*
G36*
G01X1224889D02*
G02X1225949Y1553900I1060J-565D01*
G02X1227152Y1552698I1J-1202D01*
G02X1226991Y1552098I-1204J1D01*
G01X1225446Y1549425D01*
X1225444Y1549421D01*
G02X1224374Y1548768I-1070J550D01*
G02X1223172Y1549970I0J1202D01*
G01Y1549972D01*
G02X1223321Y1550551I1202J-1D01*
G01X1224887Y1553261D01*
X1224889Y1553264D01*
G37*
G36*
G01X1234338D02*
G02X1235398Y1553900I1060J-565D01*
G02X1236600Y1552698I0J-1202D01*
G02X1236440Y1552098I-1203J0D01*
G01X1234895Y1549425D01*
X1234893Y1549421D01*
G02X1233823Y1548768I-1070J550D01*
G02X1232620Y1549970I-1J1202D01*
G01Y1549972D01*
G02X1232770Y1550551I1203J-3D01*
G01X1234336Y1553261D01*
X1234338Y1553264D01*
G37*
G36*
G01X1243787D02*
G02X1244847Y1553900I1060J-565D01*
G02X1246050Y1552698I1J-1202D01*
G02X1245889Y1552098I-1204J1D01*
G01X1244344Y1549425D01*
X1244342Y1549421D01*
G02X1243272Y1548768I-1070J550D01*
G02X1242070Y1549970I0J1202D01*
G01Y1549972D01*
G02X1242219Y1550551I1202J-1D01*
G01X1243785Y1553261D01*
X1243787Y1553264D01*
G37*
G36*
G01X1253236D02*
G02X1254296Y1553900I1060J-565D01*
G02X1255498Y1552698I0J-1202D01*
G02X1255338Y1552098I-1203J0D01*
G01X1253793Y1549425D01*
X1253791Y1549421D01*
G02X1252721Y1548768I-1070J550D01*
G02X1251518Y1549970I-1J1202D01*
G01Y1549972D01*
G02X1251668Y1550551I1203J-3D01*
G01X1253234Y1553261D01*
X1253236Y1553264D01*
G37*
G36*
G01X1267409D02*
G02X1268469Y1553900I1060J-565D01*
G02X1269672Y1552698I1J-1202D01*
G02X1269511Y1552098I-1204J1D01*
G01X1267966Y1549425D01*
X1267964Y1549421D01*
G02X1266894Y1548768I-1070J550D01*
G02X1265692Y1549970I0J1202D01*
G01Y1549972D01*
G02X1265841Y1550551I1202J-1D01*
G01X1267407Y1553261D01*
X1267409Y1553264D01*
G37*
G36*
G01X1262685D02*
G02X1263745Y1553900I1060J-565D01*
G02X1264948Y1552698I1J-1202D01*
G02X1264787Y1552098I-1204J1D01*
G01X1263242Y1549425D01*
X1263240Y1549421D01*
G02X1262170Y1548768I-1070J550D01*
G02X1260968Y1549970I0J1202D01*
G01Y1549972D01*
G02X1261117Y1550551I1202J-1D01*
G01X1262683Y1553261D01*
X1262685Y1553264D01*
G37*
G36*
G01X1329329D02*
G02X1330389Y1553900I1060J-565D01*
G02X1331592Y1552698I1J-1202D01*
G02X1331431Y1552098I-1204J1D01*
G01X1329886Y1549425D01*
X1329884Y1549421D01*
G02X1328814Y1548768I-1070J550D01*
G02X1327612Y1549970I0J1202D01*
G01Y1549972D01*
G02X1327761Y1550551I1202J-1D01*
G01X1329327Y1553261D01*
X1329329Y1553264D01*
G37*
G36*
G01X1324605D02*
G02X1325665Y1553900I1060J-565D01*
G02X1326868Y1552698I1J-1202D01*
G02X1326707Y1552098I-1204J1D01*
G01X1325162Y1549425D01*
X1325160Y1549421D01*
G02X1324090Y1548768I-1070J550D01*
G02X1322888Y1549970I0J1202D01*
G01Y1549972D01*
G02X1323037Y1550551I1202J-1D01*
G01X1324603Y1553261D01*
X1324605Y1553264D01*
G37*
G36*
G01X1610963Y1633878D02*
G02Y1636882I0J1502D01*
G01X1614363D01*
G02Y1633878I0J-1502D01*
G01X1610963D01*
G37*
G36*
G01X1598903D02*
G02Y1636882I0J1502D01*
G01X1602303D01*
G02Y1633878I0J-1502D01*
G01X1598903D01*
G37*
G36*
G01X1586843D02*
G02Y1636882I0J1502D01*
G01X1590243D01*
G02Y1633878I0J-1502D01*
G01X1586843D01*
G37*
G36*
G01X1641113Y1655790D02*
G02Y1658794I0J1502D01*
G01X1644513D01*
G02Y1655790I0J-1502D01*
G01X1641113D01*
G37*
G36*
G01X1574783Y1633878D02*
G02Y1636882I0J1502D01*
G01X1578183D01*
G02Y1633878I0J-1502D01*
G01X1574783D01*
G37*
G36*
G01X1562723D02*
G02Y1636882I0J1502D01*
G01X1566123D01*
G02Y1633878I0J-1502D01*
G01X1562723D01*
G37*
G36*
G01X1592873Y1623878D02*
G02Y1626882I0J1502D01*
G01X1596273D01*
G02Y1623878I0J-1502D01*
G01X1592873D01*
G37*
G36*
G01X1550663Y1633878D02*
G02Y1636882I0J1502D01*
G01X1554063D01*
G02Y1633878I0J-1502D01*
G01X1550663D01*
G37*
G36*
G01X1580813Y1623878D02*
G02Y1626882I0J1502D01*
G01X1584213D01*
G02Y1623878I0J-1502D01*
G01X1580813D01*
G37*
G36*
G01X1538603Y1633878D02*
G02Y1636882I0J1502D01*
G01X1542003D01*
G02Y1633878I0J-1502D01*
G01X1538603D01*
G37*
G36*
G01X1568753Y1623878D02*
G02Y1626882I0J1502D01*
G01X1572153D01*
G02Y1623878I0J-1502D01*
G01X1568753D01*
G37*
G36*
G01X1526543Y1633878D02*
G02Y1636882I0J1502D01*
G01X1529943D01*
G02Y1633878I0J-1502D01*
G01X1526543D01*
G37*
G36*
G01X1514483D02*
G02Y1636882I0J1502D01*
G01X1517883D01*
G02Y1633878I0J-1502D01*
G01X1514483D01*
G37*
G36*
G01X1478303D02*
G02Y1636882I0J1502D01*
G01X1481703D01*
G02Y1633878I0J-1502D01*
G01X1478303D01*
G37*
G36*
G01X1466243D02*
G02Y1636882I0J1502D01*
G01X1469643D01*
G02Y1633878I0J-1502D01*
G01X1466243D01*
G37*
G36*
G01X1370909Y1645790D02*
G02Y1648794I0J1502D01*
G01X1374309D01*
G02Y1645790I0J-1502D01*
G01X1370909D01*
G37*
G36*
G01X1352819Y1655790D02*
G02Y1658794I0J1502D01*
G01X1356219D01*
G02Y1655790I0J-1502D01*
G01X1352819D01*
G37*
G36*
G01X1298549Y1633878D02*
G02Y1636882I0J1502D01*
G01X1301949D01*
G02Y1633878I0J-1502D01*
G01X1298549D01*
G37*
G36*
G01X1286489D02*
G02Y1636882I0J1502D01*
G01X1289889D01*
G02Y1633878I0J-1502D01*
G01X1286489D01*
G37*
G36*
G01X1238249D02*
G02Y1636882I0J1502D01*
G01X1241649D01*
G02Y1633878I0J-1502D01*
G01X1238249D01*
G37*
G36*
G01X1250309D02*
G02Y1636882I0J1502D01*
G01X1253709D01*
G02Y1633878I0J-1502D01*
G01X1250309D01*
G37*
G36*
G01X1280459Y1655790D02*
G02Y1658794I0J1502D01*
G01X1283859D01*
G02Y1655790I0J-1502D01*
G01X1280459D01*
G37*
G36*
G01X1214129Y1633878D02*
G02Y1636882I0J1502D01*
G01X1217529D01*
G02Y1633878I0J-1502D01*
G01X1214129D01*
G37*
G36*
G01X1226189Y1645790D02*
G02Y1648794I0J1502D01*
G01X1229589D01*
G02Y1645790I0J-1502D01*
G01X1226189D01*
G37*
G36*
G01Y1633878D02*
G02Y1636882I0J1502D01*
G01X1229589D01*
G02Y1633878I0J-1502D01*
G01X1226189D01*
G37*
G36*
G01X1202069Y1645790D02*
G02Y1648794I0J1502D01*
G01X1205469D01*
G02Y1645790I0J-1502D01*
G01X1202069D01*
G37*
G36*
G01X1220159Y1655790D02*
G02Y1658794I0J1502D01*
G01X1223559D01*
G02Y1655790I0J-1502D01*
G01X1220159D01*
G37*
G36*
G01X1208099D02*
G02Y1658794I0J1502D01*
G01X1211499D01*
G02Y1655790I0J-1502D01*
G01X1208099D01*
G37*
G36*
G01Y1623878D02*
G02Y1626882I0J1502D01*
G01X1211499D01*
G02Y1623878I0J-1502D01*
G01X1208099D01*
G37*
G36*
G01X1256339D02*
G02Y1626882I0J1502D01*
G01X1259739D01*
G02Y1623878I0J-1502D01*
G01X1256339D01*
G37*
G36*
G01X591029Y1600878D02*
G02Y1603882I0J1502D01*
G01X594429D01*
G02Y1600878I0J-1502D01*
G01X591029D01*
G37*
G36*
G01X1196039Y1623878D02*
G02Y1626882I0J1502D01*
G01X1199439D01*
G02Y1623878I0J-1502D01*
G01X1196039D01*
G37*
G36*
G01X554849Y1612790D02*
G02Y1615794I0J1502D01*
G01X558249D01*
G02Y1612790I0J-1502D01*
G01X554849D01*
G37*
G36*
G01X584999Y1622790D02*
G02Y1625794I0J1502D01*
G01X588399D01*
G02Y1622790I0J-1502D01*
G01X584999D01*
G37*
G36*
G01X542789Y1600878D02*
G02Y1603882I0J1502D01*
G01X546189D01*
G02Y1600878I0J-1502D01*
G01X542789D01*
G37*
G36*
G01X494549D02*
G02Y1603882I0J1502D01*
G01X497949D01*
G02Y1600878I0J-1502D01*
G01X494549D01*
G37*
G36*
G01Y1612790D02*
G02Y1615794I0J1502D01*
G01X497949D01*
G02Y1612790I0J-1502D01*
G01X494549D01*
G37*
G36*
G01X482489D02*
G02Y1615794I0J1502D01*
G01X485889D01*
G02Y1612790I0J-1502D01*
G01X482489D01*
G37*
G36*
G01X461769Y1603882D02*
G02Y1600878I0J-1502D01*
G01X458369D01*
G02Y1603882I0J1502D01*
G01X461769D01*
G37*
G36*
G01X476459Y1590878D02*
G02Y1593882I0J1502D01*
G01X479859D01*
G02Y1590878I0J-1502D01*
G01X476459D01*
G37*
G36*
G01X464399Y1622790D02*
G02Y1625794I0J1502D01*
G01X467799D01*
G02Y1622790I0J-1502D01*
G01X464399D01*
G37*
G36*
G01X452339Y1590878D02*
G02Y1593882I0J1502D01*
G01X455739D01*
G02Y1590878I0J-1502D01*
G01X452339D01*
G37*
G36*
G01X375096Y1600878D02*
G02Y1603882I0J1502D01*
G01X378496D01*
G02Y1600878I0J-1502D01*
G01X375096D01*
G37*
G36*
G01X357006Y1590878D02*
G02Y1593882I0J1502D01*
G01X360406D01*
G02Y1590878I0J-1502D01*
G01X357006D01*
G37*
G36*
G01X314796Y1612790D02*
G02Y1615794I0J1502D01*
G01X318196D01*
G02Y1612790I0J-1502D01*
G01X314796D01*
G37*
G36*
G01X302736Y1600878D02*
G02Y1603882I0J1502D01*
G01X306136D01*
G02Y1600878I0J-1502D01*
G01X302736D01*
G37*
G36*
G01X272586Y1590878D02*
G02Y1593882I0J1502D01*
G01X275986D01*
G02Y1590878I0J-1502D01*
G01X272586D01*
G37*
G36*
G01X266556Y1612790D02*
G02Y1615794I0J1502D01*
G01X269956D01*
G02Y1612790I0J-1502D01*
G01X266556D01*
G37*
G36*
G01X254496D02*
G02Y1615794I0J1502D01*
G01X257896D01*
G02Y1612790I0J-1502D01*
G01X254496D01*
G37*
G36*
G01X218316D02*
G02Y1615794I0J1502D01*
G01X221716D01*
G02Y1612790I0J-1502D01*
G01X218316D01*
G37*
G36*
G01X212286Y1622790D02*
G02Y1625794I0J1502D01*
G01X215686D01*
G02Y1622790I0J-1502D01*
G01X212286D01*
G37*
G36*
G01X578969Y1612790D02*
G02Y1615794I0J1502D01*
G01X582369D01*
G02Y1612790I0J-1502D01*
G01X578969D01*
G37*
G36*
G01X1340759Y1655790D02*
G02Y1658794I0J1502D01*
G01X1344159D01*
G02Y1655790I0J-1502D01*
G01X1340759D01*
G37*
G36*
G01X1328699D02*
G02Y1658794I0J1502D01*
G01X1332099D01*
G02Y1655790I0J-1502D01*
G01X1328699D01*
G37*
G36*
G01X304113Y1451392D02*
G02Y1454398I0J1503D01*
G01X307513D01*
G02Y1451392I0J-1503D01*
G01X304113D01*
G37*
G36*
G01X324213Y1461092D02*
G02Y1464098I0J1503D01*
G01X327613D01*
G02Y1461092I0J-1503D01*
G01X324213D01*
G37*
G36*
G01X338916Y1612790D02*
G02Y1615794I0J1502D01*
G01X342316D01*
G02Y1612790I0J-1502D01*
G01X338916D01*
G37*
G36*
G01X169351Y1461092D02*
G02Y1464098I0J1503D01*
G01X172751D01*
G02Y1461092I0J-1503D01*
G01X169351D01*
G37*
G36*
G01X350976Y1612790D02*
G02Y1615794I0J1502D01*
G01X354376D01*
G02Y1612790I0J-1502D01*
G01X350976D01*
G37*
G36*
G01X641986Y1461092D02*
G02Y1464098I0J1503D01*
G01X645386D01*
G02Y1461092I0J-1503D01*
G01X641986D01*
G37*
G36*
G01X230376Y1612790D02*
G02Y1615794I0J1502D01*
G01X233776D01*
G02Y1612790I0J-1502D01*
G01X230376D01*
G37*
G36*
G01X344313Y1470792D02*
G02Y1473798I0J1503D01*
G01X347713D01*
G02Y1470792I0J-1503D01*
G01X344313D01*
G37*
G36*
G01X1232219Y1623878D02*
G02Y1626882I0J1502D01*
G01X1235619D01*
G02Y1623878I0J-1502D01*
G01X1232219D01*
G37*
G36*
G01X1629053D02*
G02Y1626882I0J1502D01*
G01X1632453D01*
G02Y1623878I0J-1502D01*
G01X1629053D01*
G37*
G36*
G01X1364879D02*
G02Y1626882I0J1502D01*
G01X1368279D01*
G02Y1623878I0J-1502D01*
G01X1364879D01*
G37*
G36*
G01X363036Y1612790D02*
G02Y1615794I0J1502D01*
G01X366436D01*
G02Y1612790I0J-1502D01*
G01X363036D01*
G37*
G36*
G01X648686Y1451392D02*
G02Y1454398I0J1503D01*
G01X652086D01*
G02Y1451392I0J-1503D01*
G01X648686D01*
G37*
G36*
G01X221740Y1520264D02*
G02X222800Y1520900I1060J-565D01*
G02X224002Y1519698I0J-1202D01*
G02X223842Y1519098I-1203J0D01*
G01X222297Y1516425D01*
X222295Y1516421D01*
G02X221225Y1515768I-1070J550D01*
G02X220022Y1516970I-1J1202D01*
G01Y1516972D01*
G02X220172Y1517551I1203J-3D01*
G01X221738Y1520261D01*
X221740Y1520264D01*
G37*
G36*
G01X1392386Y1484392D02*
G02Y1487398I0J1503D01*
G01X1395786D01*
G02Y1484392I0J-1503D01*
G01X1392386D01*
G37*
G36*
G01X480424Y1470792D02*
G02Y1473798I0J1503D01*
G01X483824D01*
G02Y1470792I0J-1503D01*
G01X480424D01*
G37*
G36*
G01X1334729Y1645790D02*
G02Y1648794I0J1502D01*
G01X1338129D01*
G02Y1645790I0J-1502D01*
G01X1334729D01*
G37*
G36*
G01X1322669D02*
G02Y1648794I0J1502D01*
G01X1326069D01*
G02Y1645790I0J-1502D01*
G01X1322669D01*
G37*
G36*
G01X1310609D02*
G02Y1648794I0J1502D01*
G01X1314009D01*
G02Y1645790I0J-1502D01*
G01X1310609D01*
G37*
G36*
G01X1316639Y1655790D02*
G02Y1658794I0J1502D01*
G01X1320039D01*
G02Y1655790I0J-1502D01*
G01X1316639D01*
G37*
G36*
G01X1304579D02*
G02Y1658794I0J1502D01*
G01X1307979D01*
G02Y1655790I0J-1502D01*
G01X1304579D01*
G37*
G36*
G01X470845Y1144846D02*
G02Y1147250I0J1202D01*
G01X474546D01*
G02Y1144846I0J-1202D01*
G01X470845D01*
G37*
G36*
G01X1292519Y1623878D02*
G02Y1626882I0J1502D01*
G01X1295919D01*
G02Y1623878I0J-1502D01*
G01X1292519D01*
G37*
G36*
G01X1280459D02*
G02Y1626882I0J1502D01*
G01X1283859D01*
G02Y1623878I0J-1502D01*
G01X1280459D01*
G37*
G36*
G01X1268399Y1655790D02*
G02Y1658794I0J1502D01*
G01X1271799D01*
G02Y1655790I0J-1502D01*
G01X1268399D01*
G37*
G36*
G01X1256339D02*
G02Y1658794I0J1502D01*
G01X1259739D01*
G02Y1655790I0J-1502D01*
G01X1256339D01*
G37*
G36*
G01X1244279D02*
G02Y1658794I0J1502D01*
G01X1247679D01*
G02Y1655790I0J-1502D01*
G01X1244279D01*
G37*
G36*
G01X1232219D02*
G02Y1658794I0J1502D01*
G01X1235619D01*
G02Y1655790I0J-1502D01*
G01X1232219D01*
G37*
G36*
G01X493050Y1144846D02*
G02Y1147250I0J1202D01*
G01X496751D01*
G02Y1144846I0J-1202D01*
G01X493050D01*
G37*
G36*
G01X485649Y1128118D02*
G02Y1125712I0J-1203D01*
G01X481948D01*
G02Y1128118I0J1203D01*
G01X485649D01*
G37*
G36*
G01X493050Y1125712D02*
G02Y1128118I0J1203D01*
G01X496751D01*
G02Y1125712I0J-1203D01*
G01X493050D01*
G37*
G36*
G01X485649Y1147250D02*
G02Y1144846I0J-1202D01*
G01X481948D01*
G02Y1147250I0J1202D01*
G01X485649D01*
G37*
G36*
G01X459743Y1144846D02*
G02Y1147250I0J1202D01*
G01X463444D01*
G02Y1144846I0J-1202D01*
G01X459743D01*
G37*
G36*
G01X259536Y1520264D02*
G02X260596Y1520900I1060J-565D01*
G02X261798Y1519698I0J-1202D01*
G02X261638Y1519098I-1203J0D01*
G01X260093Y1516425D01*
X260091Y1516421D01*
G02X259021Y1515768I-1070J550D01*
G02X257818Y1516970I-1J1202D01*
G01Y1516972D01*
G02X257968Y1517551I1203J-3D01*
G01X259534Y1520261D01*
X259536Y1520264D01*
G37*
G36*
G01X1460213Y1655790D02*
G02Y1658794I0J1502D01*
G01X1463613D01*
G02Y1655790I0J-1502D01*
G01X1460213D01*
G37*
G36*
G01X357006Y1622790D02*
G02Y1625794I0J1502D01*
G01X360406D01*
G02Y1622790I0J-1502D01*
G01X357006D01*
G37*
G36*
G01X1616993Y1623878D02*
G02Y1626882I0J1502D01*
G01X1620393D01*
G02Y1623878I0J-1502D01*
G01X1616993D01*
G37*
G36*
G01X1515098Y1503792D02*
G02Y1506798I0J1503D01*
G01X1518498D01*
G02Y1503792I0J-1503D01*
G01X1515098D01*
G37*
G36*
G01X588386Y1461092D02*
G02Y1464098I0J1503D01*
G01X591786D01*
G02Y1461092I0J-1503D01*
G01X588386D01*
G37*
G36*
G01X561586D02*
G02Y1464098I0J1503D01*
G01X564986D01*
G02Y1461092I0J-1503D01*
G01X561586D01*
G37*
G36*
G01X1340759Y1623878D02*
G02Y1626882I0J1502D01*
G01X1344159D01*
G02Y1623878I0J-1502D01*
G01X1340759D01*
G37*
G36*
G01X1659960Y1487398D02*
G02Y1484392I0J-1503D01*
G01X1656560D01*
G02Y1487398I0J1503D01*
G01X1659960D01*
G37*
G36*
G01X1488298Y1503792D02*
G02Y1506798I0J1503D01*
G01X1491698D01*
G02Y1503792I0J-1503D01*
G01X1488298D01*
G37*
G36*
G01X635286Y1470792D02*
G02Y1473798I0J1503D01*
G01X638686D01*
G02Y1470792I0J-1503D01*
G01X635286D01*
G37*
G36*
G01X1647143Y1633878D02*
G02Y1636882I0J1502D01*
G01X1650543D01*
G02Y1633878I0J-1502D01*
G01X1647143D01*
G37*
G36*
G01X1352819Y1623878D02*
G02Y1626882I0J1502D01*
G01X1356219D01*
G02Y1623878I0J-1502D01*
G01X1352819D01*
G37*
G36*
G01X536759Y1622790D02*
G02Y1625794I0J1502D01*
G01X540159D01*
G02Y1622790I0J-1502D01*
G01X536759D01*
G37*
G36*
G01X332886Y1590878D02*
G02Y1593882I0J1502D01*
G01X336286D01*
G02Y1590878I0J-1502D01*
G01X332886D01*
G37*
G36*
G01X512639D02*
G02Y1593882I0J1502D01*
G01X516039D01*
G02Y1590878I0J-1502D01*
G01X512639D01*
G37*
G36*
G01X522069Y1603882D02*
G02Y1600878I0J-1502D01*
G01X518669D01*
G02Y1603882I0J1502D01*
G01X522069D01*
G37*
G36*
G01X603089Y1600878D02*
G02Y1603882I0J1502D01*
G01X606489D01*
G02Y1600878I0J-1502D01*
G01X603089D01*
G37*
G36*
G01X1472273Y1623878D02*
G02Y1626882I0J1502D01*
G01X1475673D01*
G02Y1623878I0J-1502D01*
G01X1472273D01*
G37*
G36*
G01X1304579D02*
G02Y1626882I0J1502D01*
G01X1307979D01*
G02Y1623878I0J-1502D01*
G01X1304579D01*
G37*
G36*
G01X297413Y1461092D02*
G02Y1464098I0J1503D01*
G01X300813D01*
G02Y1461092I0J-1503D01*
G01X297413D01*
G37*
G36*
G01X493824Y1451392D02*
G02Y1454398I0J1503D01*
G01X497224D01*
G02Y1451392I0J-1503D01*
G01X493824D01*
G37*
G36*
G01X1544633Y1623878D02*
G02Y1626882I0J1502D01*
G01X1548033D01*
G02Y1623878I0J-1502D01*
G01X1544633D01*
G37*
G36*
G01X530729Y1600878D02*
G02Y1603882I0J1502D01*
G01X534129D01*
G02Y1600878I0J-1502D01*
G01X530729D01*
G37*
G36*
G01X1177224Y1494092D02*
G02Y1497098I0J1503D01*
G01X1180624D01*
G02Y1494092I0J-1503D01*
G01X1177224D01*
G37*
G36*
G01X440224Y1451392D02*
G02Y1454398I0J1503D01*
G01X443624D01*
G02Y1451392I0J-1503D01*
G01X440224D01*
G37*
G36*
G01X1520513Y1623878D02*
G02Y1626882I0J1502D01*
G01X1523913D01*
G02Y1623878I0J-1502D01*
G01X1520513D01*
G37*
G36*
G01X1316639D02*
G02Y1626882I0J1502D01*
G01X1320039D01*
G02Y1623878I0J-1502D01*
G01X1316639D01*
G37*
G36*
G01X595086Y1451392D02*
G02Y1454398I0J1503D01*
G01X598486D01*
G02Y1451392I0J-1503D01*
G01X595086D01*
G37*
G36*
G01X568286D02*
G02Y1454398I0J1503D01*
G01X571686D01*
G02Y1451392I0J-1503D01*
G01X568286D01*
G37*
G36*
G01X581686Y1470792D02*
G02Y1473798I0J1503D01*
G01X585086D01*
G02Y1470792I0J-1503D01*
G01X581686D01*
G37*
G36*
G01X1604933Y1623878D02*
G02Y1626882I0J1502D01*
G01X1608333D01*
G02Y1623878I0J-1502D01*
G01X1604933D01*
G37*
G36*
G01X296706Y1590878D02*
G02Y1593882I0J1502D01*
G01X300106D01*
G02Y1590878I0J-1502D01*
G01X296706D01*
G37*
G36*
G01X218316Y1600878D02*
G02Y1603882I0J1502D01*
G01X221716D01*
G02Y1600878I0J-1502D01*
G01X218316D01*
G37*
G36*
G01X278616D02*
G02Y1603882I0J1502D01*
G01X282016D01*
G02Y1600878I0J-1502D01*
G01X278616D01*
G37*
G36*
G01X326856D02*
G02Y1603882I0J1502D01*
G01X330256D01*
G02Y1600878I0J-1502D01*
G01X326856D01*
G37*
G36*
G01X338916D02*
G02Y1603882I0J1502D01*
G01X342316D01*
G02Y1600878I0J-1502D01*
G01X338916D01*
G37*
G36*
G01X363036D02*
G02Y1603882I0J1502D01*
G01X366436D01*
G02Y1600878I0J-1502D01*
G01X363036D01*
G37*
G36*
G01X578969D02*
G02Y1603882I0J1502D01*
G01X582369D01*
G02Y1600878I0J-1502D01*
G01X578969D01*
G37*
G36*
G01X1382969Y1633878D02*
G02Y1636882I0J1502D01*
G01X1386369D01*
G02Y1633878I0J-1502D01*
G01X1382969D01*
G37*
G36*
G01X1224124Y1503792D02*
G02Y1506798I0J1503D01*
G01X1227524D01*
G02Y1503792I0J-1503D01*
G01X1224124D01*
G37*
G36*
G01X460324Y1461092D02*
G02Y1464098I0J1503D01*
G01X463724D01*
G02Y1461092I0J-1503D01*
G01X460324D01*
G37*
G36*
G01X1484333Y1623878D02*
G02Y1626882I0J1502D01*
G01X1487733D01*
G02Y1623878I0J-1502D01*
G01X1484333D01*
G37*
G36*
G01X560879Y1590878D02*
G02Y1593882I0J1502D01*
G01X564279D01*
G02Y1590878I0J-1502D01*
G01X560879D01*
G37*
G36*
G01X1325386Y1503792D02*
G02Y1506798I0J1503D01*
G01X1328786D01*
G02Y1503792I0J-1503D01*
G01X1325386D01*
G37*
G36*
G01X1257624Y1494092D02*
G02Y1497098I0J1503D01*
G01X1261024D01*
G02Y1494092I0J-1503D01*
G01X1257624D01*
G37*
G36*
G01X1596260D02*
G02Y1497098I0J1503D01*
G01X1599660D01*
G02Y1494092I0J-1503D01*
G01X1596260D01*
G37*
G36*
G01X1328699Y1623878D02*
G02Y1626882I0J1502D01*
G01X1332099D01*
G02Y1623878I0J-1502D01*
G01X1328699D01*
G37*
G36*
G01X1202069Y1633878D02*
G02Y1636882I0J1502D01*
G01X1205469D01*
G02Y1633878I0J-1502D01*
G01X1202069D01*
G37*
G36*
G01X464399Y1590878D02*
G02Y1593882I0J1502D01*
G01X467799D01*
G02Y1590878I0J-1502D01*
G01X464399D01*
G37*
G36*
G01X1441398Y1494092D02*
G02Y1497098I0J1503D01*
G01X1444798D01*
G02Y1494092I0J-1503D01*
G01X1441398D01*
G37*
G36*
G01X1623060D02*
G02Y1497098I0J1503D01*
G01X1626460D01*
G02Y1494092I0J-1503D01*
G01X1623060D01*
G37*
G36*
G01X1646560Y1506798D02*
G02Y1503792I0J-1503D01*
G01X1643160D01*
G02Y1506798I0J1503D01*
G01X1646560D01*
G37*
G36*
G01X1576160Y1484392D02*
G02Y1487398I0J1503D01*
G01X1579560D01*
G02Y1484392I0J-1503D01*
G01X1576160D01*
G37*
G36*
G01X1268399Y1623878D02*
G02Y1626882I0J1502D01*
G01X1271799D01*
G02Y1623878I0J-1502D01*
G01X1268399D01*
G37*
G36*
G01X1292519Y1655790D02*
G02Y1658794I0J1502D01*
G01X1295919D01*
G02Y1655790I0J-1502D01*
G01X1292519D01*
G37*
G36*
G01X513924Y1461092D02*
G02Y1464098I0J1503D01*
G01X517324D01*
G02Y1461092I0J-1503D01*
G01X513924D01*
G37*
G36*
G01X1197324Y1503792D02*
G02Y1506798I0J1503D01*
G01X1200724D01*
G02Y1503792I0J-1503D01*
G01X1197324D01*
G37*
G36*
G01X608486Y1470792D02*
G02Y1473798I0J1503D01*
G01X611886D01*
G02Y1470792I0J-1503D01*
G01X608486D01*
G37*
G36*
G01X1358886Y1494092D02*
G02Y1497098I0J1503D01*
G01X1362286D01*
G02Y1494092I0J-1503D01*
G01X1358886D01*
G37*
G36*
G01X1448098Y1484392D02*
G02Y1487398I0J1503D01*
G01X1451498D01*
G02Y1484392I0J-1503D01*
G01X1448098D01*
G37*
G36*
G01X1244279Y1623878D02*
G02Y1626882I0J1502D01*
G01X1247679D01*
G02Y1623878I0J-1502D01*
G01X1244279D01*
G37*
G36*
G01X1250924Y1503792D02*
G02Y1506798I0J1503D01*
G01X1254324D01*
G02Y1503792I0J-1503D01*
G01X1250924D01*
G37*
G36*
G01X500087Y1520264D02*
G02X501147Y1520900I1060J-565D01*
G02X502350Y1519698I1J-1202D01*
G02X502189Y1519098I-1204J1D01*
G01X500644Y1516425D01*
X500642Y1516421D01*
G02X499572Y1515768I-1070J550D01*
G02X498370Y1516970I0J1202D01*
G01Y1516972D01*
G02X498519Y1517551I1202J-1D01*
G01X500085Y1520261D01*
X500087Y1520264D01*
G37*
G36*
G01X1653260Y1497098D02*
G02Y1494092I0J-1503D01*
G01X1649860D01*
G02Y1497098I0J1503D01*
G01X1653260D01*
G37*
G36*
G01X1230824Y1494092D02*
G02Y1497098I0J1503D01*
G01X1234224D01*
G02Y1494092I0J-1503D01*
G01X1230824D01*
G37*
G36*
G01X202843Y1520264D02*
G02X203903Y1520900I1060J-565D01*
G02X205106Y1519698I1J-1202D01*
G02X204945Y1519098I-1204J1D01*
G01X203400Y1516425D01*
X203398Y1516421D01*
G02X202328Y1515768I-1070J550D01*
G02X201126Y1516970I0J1202D01*
G01Y1516972D01*
G02X201275Y1517551I1202J-1D01*
G01X202841Y1520261D01*
X202843Y1520264D01*
G37*
G36*
G01X467024Y1451392D02*
G02Y1454398I0J1503D01*
G01X470424D01*
G02Y1451392I0J-1503D01*
G01X467024D01*
G37*
G36*
G01X1589560Y1503792D02*
G02Y1506798I0J1503D01*
G01X1592960D01*
G02Y1503792I0J-1503D01*
G01X1589560D01*
G37*
G36*
G01X1616360D02*
G02Y1506798I0J1503D01*
G01X1619760D01*
G02Y1503792I0J-1503D01*
G01X1616360D01*
G37*
G36*
G01X1460213Y1623878D02*
G02Y1626882I0J1502D01*
G01X1463613D01*
G02Y1623878I0J-1502D01*
G01X1460213D01*
G37*
G36*
G01X1521798Y1494092D02*
G02Y1497098I0J1503D01*
G01X1525198D01*
G02Y1494092I0J-1503D01*
G01X1521798D01*
G37*
G36*
G01X487124Y1461092D02*
G02Y1464098I0J1503D01*
G01X490524D01*
G02Y1461092I0J-1503D01*
G01X487124D01*
G37*
G36*
G01X1352186Y1503792D02*
G02Y1506798I0J1503D01*
G01X1355586D01*
G02Y1503792I0J-1503D01*
G01X1352186D01*
G37*
G36*
G01X254811Y1520264D02*
G02X255871Y1520900I1060J-565D01*
G02X257074Y1519698I1J-1202D01*
G02X256913Y1519098I-1204J1D01*
G01X255368Y1516425D01*
X255366Y1516421D01*
G02X254296Y1515768I-1070J550D01*
G02X253094Y1516970I0J1202D01*
G01Y1516972D01*
G02X253243Y1517551I1202J-1D01*
G01X254809Y1520261D01*
X254811Y1520264D01*
G37*
G36*
G01X231189D02*
G02X232249Y1520900I1060J-565D01*
G02X233452Y1519698I1J-1202D01*
G02X233291Y1519098I-1204J1D01*
G01X231746Y1516425D01*
X231744Y1516421D01*
G02X230674Y1515768I-1070J550D01*
G02X229472Y1516970I0J1202D01*
G01Y1516972D01*
G02X229621Y1517551I1202J-1D01*
G01X231187Y1520261D01*
X231189Y1520264D01*
G37*
G36*
G01X375096Y1612790D02*
G02Y1615794I0J1502D01*
G01X378496D01*
G02Y1612790I0J-1502D01*
G01X375096D01*
G37*
G36*
G01X1332086Y1494092D02*
G02Y1497098I0J1503D01*
G01X1335486D01*
G02Y1494092I0J-1503D01*
G01X1332086D01*
G37*
G36*
G01X207567Y1520264D02*
G02X208627Y1520900I1060J-565D01*
G02X209830Y1519698I1J-1202D01*
G02X209669Y1519098I-1204J1D01*
G01X208124Y1516425D01*
X208122Y1516421D01*
G02X207052Y1515768I-1070J550D01*
G02X205850Y1516970I0J1202D01*
G01Y1516972D01*
G02X205999Y1517551I1202J-1D01*
G01X207565Y1520261D01*
X207567Y1520264D01*
G37*
G36*
G01X235914D02*
G02X236974Y1520900I1060J-565D01*
G02X238176Y1519698I0J-1202D01*
G02X238016Y1519098I-1203J0D01*
G01X236471Y1516425D01*
X236469Y1516421D01*
G02X235399Y1515768I-1070J550D01*
G02X234196Y1516970I-1J1202D01*
G01Y1516972D01*
G02X234346Y1517551I1203J-3D01*
G01X235912Y1520261D01*
X235914Y1520264D01*
G37*
G36*
G01X212292D02*
G02X213352Y1520900I1060J-565D01*
G02X214554Y1519698I0J-1202D01*
G02X214394Y1519098I-1203J0D01*
G01X212849Y1516425D01*
X212847Y1516421D01*
G02X211777Y1515768I-1070J550D01*
G02X210574Y1516970I-1J1202D01*
G01Y1516972D01*
G02X210724Y1517551I1203J-3D01*
G01X212290Y1520261D01*
X212292Y1520264D01*
G37*
G36*
G01X1338786Y1484392D02*
G02Y1487398I0J1503D01*
G01X1342186D01*
G02Y1484392I0J-1503D01*
G01X1338786D01*
G37*
G36*
G01X345078Y1520264D02*
G02X346138Y1520900I1060J-565D01*
G02X347340Y1519698I0J-1202D01*
G02X347180Y1519098I-1203J0D01*
G01X345635Y1516425D01*
X345633Y1516421D01*
G02X344563Y1515768I-1070J550D01*
G02X343360Y1516970I-1J1202D01*
G01Y1516972D01*
G02X343510Y1517551I1203J-3D01*
G01X345076Y1520261D01*
X345078Y1520264D01*
G37*
G36*
G01X368700D02*
G02X369760Y1520900I1060J-565D01*
G02X370962Y1519698I0J-1202D01*
G02X370802Y1519098I-1203J0D01*
G01X369257Y1516425D01*
X369255Y1516421D01*
G02X368185Y1515768I-1070J550D01*
G02X366982Y1516970I-1J1202D01*
G01Y1516972D01*
G02X367132Y1517551I1203J-3D01*
G01X368698Y1520261D01*
X368700Y1520264D01*
G37*
G36*
G01X326180D02*
G02X327240Y1520900I1060J-565D01*
G02X328442Y1519698I0J-1202D01*
G02X328282Y1519098I-1203J0D01*
G01X326737Y1516425D01*
X326735Y1516421D01*
G02X325665Y1515768I-1070J550D01*
G02X324462Y1516970I-1J1202D01*
G01Y1516972D01*
G02X324612Y1517551I1203J-3D01*
G01X326178Y1520261D01*
X326180Y1520264D01*
G37*
G36*
G01X378149D02*
G02X379209Y1520900I1060J-565D01*
G02X380412Y1519698I1J-1202D01*
G02X380251Y1519098I-1204J1D01*
G01X378706Y1516425D01*
X378704Y1516421D01*
G02X377634Y1515768I-1070J550D01*
G02X376432Y1516970I0J1202D01*
G01Y1516972D01*
G02X376581Y1517551I1202J-1D01*
G01X378147Y1520261D01*
X378149Y1520264D01*
G37*
G36*
G01X112473Y1661738D02*
G02Y1658732I0J-1503D01*
G01X109073D01*
G02Y1661738I0J1503D01*
G01X112473D01*
G37*
G36*
G01X157410Y1678314D02*
G02Y1675308I0J-1503D01*
G01X154010D01*
G02Y1678314I0J1503D01*
G01X157410D01*
G37*
G36*
G01X157511Y1665436D02*
G02Y1662430I0J-1503D01*
G01X154111D01*
G02Y1665436I0J1503D01*
G01X157511D01*
G37*
G36*
G01X110969Y1687266D02*
G02Y1684260I0J-1503D01*
G01X107569D01*
G02Y1687266I0J1503D01*
G01X110969D01*
G37*
G36*
G01X384571Y916688D02*
G02Y919094I0J1203D01*
G01X388272D01*
G02Y916688I0J-1203D01*
G01X384571D01*
G37*
G36*
G01Y929444D02*
G02Y931850I0J1203D01*
G01X388272D01*
G02Y929444I0J-1203D01*
G01X384571D01*
G37*
G36*
G01Y923066D02*
G02Y925472I0J1203D01*
G01X388272D01*
G02Y923066I0J-1203D01*
G01X384571D01*
G37*
G36*
G01X388272Y970118D02*
G02Y967712I0J-1203D01*
G01X384571D01*
G02Y970118I0J1203D01*
G01X388272D01*
G37*
G36*
G01Y963740D02*
G02Y961334I0J-1203D01*
G01X384571D01*
G02Y963740I0J1203D01*
G01X388272D01*
G37*
G36*
G01Y976496D02*
G02Y974090I0J-1203D01*
G01X384571D01*
G02Y976496I0J1203D01*
G01X388272D01*
G37*
G36*
G01X389453Y1115362D02*
G02Y1112956I0J-1203D01*
G01X385752D01*
G02Y1115362I0J1203D01*
G01X389453D01*
G37*
G36*
G01Y1108984D02*
G02Y1106578I0J-1203D01*
G01X385752D01*
G02Y1108984I0J1203D01*
G01X389453D01*
G37*
G36*
G01X385752Y1132090D02*
G02Y1134496I0J1203D01*
G01X389453D01*
G02Y1132090I0J-1203D01*
G01X385752D01*
G37*
G36*
G01X389453Y1121740D02*
G02Y1119334I0J-1203D01*
G01X385752D01*
G02Y1121740I0J1203D01*
G01X389453D01*
G37*
G36*
G01X385752Y1125712D02*
G02Y1128118I0J1203D01*
G01X389453D01*
G02Y1125712I0J-1203D01*
G01X385752D01*
G37*
G36*
G01Y1144846D02*
G02Y1147250I0J1202D01*
G01X389453D01*
G02Y1144846I0J-1202D01*
G01X385752D01*
G37*
G36*
G01Y1138468D02*
G02Y1140872I0J1202D01*
G01X389453D01*
G02Y1138468I0J-1202D01*
G01X385752D01*
G37*
G36*
G01X395673Y910310D02*
G02Y912716I0J1203D01*
G01X399374D01*
G02Y910310I0J-1203D01*
G01X395673D01*
G37*
G36*
G01X406776D02*
G02Y912716I0J1203D01*
G01X410477D01*
G02Y910310I0J-1203D01*
G01X406776D01*
G37*
G36*
G01X395673Y929444D02*
G02Y931850I0J1203D01*
G01X399374D01*
G02Y929444I0J-1203D01*
G01X395673D01*
G37*
G36*
G01Y923066D02*
G02Y925472I0J1203D01*
G01X399374D01*
G02Y923066I0J-1203D01*
G01X395673D01*
G37*
G36*
G01X406776D02*
G02Y925472I0J1203D01*
G01X410477D01*
G02Y923066I0J-1203D01*
G01X406776D01*
G37*
G36*
G01X395673Y916688D02*
G02Y919094I0J1203D01*
G01X399374D01*
G02Y916688I0J-1203D01*
G01X395673D01*
G37*
G36*
G01X406776D02*
G02Y919094I0J1203D01*
G01X410477D01*
G02Y916688I0J-1203D01*
G01X406776D01*
G37*
G36*
G01X399374Y970118D02*
G02Y967712I0J-1203D01*
G01X395673D01*
G02Y970118I0J1203D01*
G01X399374D01*
G37*
G36*
G01X406776Y967712D02*
G02Y970118I0J1203D01*
G01X410477D01*
G02Y967712I0J-1203D01*
G01X406776D01*
G37*
G36*
G01X399374Y963740D02*
G02Y961334I0J-1203D01*
G01X395673D01*
G02Y963740I0J1203D01*
G01X399374D01*
G37*
G36*
G01X410477D02*
G02Y961334I0J-1203D01*
G01X406776D01*
G02Y963740I0J1203D01*
G01X410477D01*
G37*
G36*
G01X399374Y976496D02*
G02Y974090I0J-1203D01*
G01X395673D01*
G02Y976496I0J1203D01*
G01X399374D01*
G37*
G36*
G01X406776Y974090D02*
G02Y976496I0J1203D01*
G01X410477D01*
G02Y974090I0J-1203D01*
G01X406776D01*
G37*
G36*
G01X400556Y1115362D02*
G02Y1112956I0J-1203D01*
G01X396855D01*
G02Y1115362I0J1203D01*
G01X400556D01*
G37*
G36*
G01Y1108984D02*
G02Y1106578I0J-1203D01*
G01X396855D01*
G02Y1108984I0J1203D01*
G01X400556D01*
G37*
G36*
G01X396855Y1132090D02*
G02Y1134496I0J1203D01*
G01X400556D01*
G02Y1132090I0J-1203D01*
G01X396855D01*
G37*
G36*
G01X400556Y1128118D02*
G02Y1125712I0J-1203D01*
G01X396855D01*
G02Y1128118I0J1203D01*
G01X400556D01*
G37*
G36*
G01Y1121740D02*
G02Y1119334I0J-1203D01*
G01X396855D01*
G02Y1121740I0J1203D01*
G01X400556D01*
G37*
G36*
G01X396855Y1144846D02*
G02Y1147250I0J1202D01*
G01X400556D01*
G02Y1144846I0J-1202D01*
G01X396855D01*
G37*
G36*
G01Y1138468D02*
G02Y1140872I0J1202D01*
G01X400556D01*
G02Y1138468I0J-1202D01*
G01X396855D01*
G37*
G36*
G01X417878Y910310D02*
G02Y912716I0J1203D01*
G01X421579D01*
G02Y910310I0J-1203D01*
G01X417878D01*
G37*
G36*
G01Y923066D02*
G02Y925472I0J1203D01*
G01X421579D01*
G02Y923066I0J-1203D01*
G01X417878D01*
G37*
G36*
G01Y916688D02*
G02Y919094I0J1203D01*
G01X421579D01*
G02Y916688I0J-1203D01*
G01X417878D01*
G37*
G36*
G01X421579Y976496D02*
G02Y974090I0J-1203D01*
G01X417878D01*
G02Y976496I0J1203D01*
G01X421579D01*
G37*
G36*
G01Y970118D02*
G02Y967712I0J-1203D01*
G01X417878D01*
G02Y970118I0J1203D01*
G01X421579D01*
G37*
G36*
G01Y963740D02*
G02Y961334I0J-1203D01*
G01X417878D01*
G02Y963740I0J1203D01*
G01X421579D01*
G37*
G36*
G01X419059Y1112956D02*
G02Y1115362I0J1203D01*
G01X422760D01*
G02Y1112956I0J-1203D01*
G01X419059D01*
G37*
G36*
G01X411658Y1115362D02*
G02Y1112956I0J-1203D01*
G01X407957D01*
G02Y1115362I0J1203D01*
G01X411658D01*
G37*
G36*
G01X419059Y1132090D02*
G02Y1134496I0J1203D01*
G01X422760D01*
G02Y1132090I0J-1203D01*
G01X419059D01*
G37*
G36*
G01Y1125712D02*
G02Y1128118I0J1203D01*
G01X422760D01*
G02Y1125712I0J-1203D01*
G01X419059D01*
G37*
G36*
G01Y1119334D02*
G02Y1121740I0J1203D01*
G01X422760D01*
G02Y1119334I0J-1203D01*
G01X419059D01*
G37*
G36*
G01X407957Y1132090D02*
G02Y1134496I0J1203D01*
G01X411658D01*
G02Y1132090I0J-1203D01*
G01X407957D01*
G37*
G36*
G01X411658Y1128118D02*
G02Y1125712I0J-1203D01*
G01X407957D01*
G02Y1128118I0J1203D01*
G01X411658D01*
G37*
G36*
G01Y1121740D02*
G02Y1119334I0J-1203D01*
G01X407957D01*
G02Y1121740I0J1203D01*
G01X411658D01*
G37*
G36*
G01X419059Y1144846D02*
G02Y1147250I0J1202D01*
G01X422760D01*
G02Y1144846I0J-1202D01*
G01X419059D01*
G37*
G36*
G01Y1138468D02*
G02Y1140872I0J1202D01*
G01X422760D01*
G02Y1138468I0J-1202D01*
G01X419059D01*
G37*
G36*
G01X407957Y1144846D02*
G02Y1147250I0J1202D01*
G01X411658D01*
G02Y1144846I0J-1202D01*
G01X407957D01*
G37*
G36*
G01Y1138468D02*
G02Y1140872I0J1202D01*
G01X411658D01*
G02Y1138468I0J-1202D01*
G01X407957D01*
G37*
G36*
G01X427130Y913500D02*
G02Y915904I0J1202D01*
G01X430831D01*
G02Y913500I0J-1202D01*
G01X427130D01*
G37*
G36*
G01Y958146D02*
G02Y960550I0J1202D01*
G01X430831D01*
G02Y958146I0J-1202D01*
G01X427130D01*
G37*
G36*
G01Y926256D02*
G02Y928660I0J1202D01*
G01X430831D01*
G02Y926256I0J-1202D01*
G01X427130D01*
G37*
G36*
G01Y919878D02*
G02Y922282I0J1202D01*
G01X430831D01*
G02Y919878I0J-1202D01*
G01X427130D01*
G37*
G36*
G01X430831Y973306D02*
G02Y970902I0J-1202D01*
G01X427130D01*
G02Y973306I0J1202D01*
G01X430831D01*
G37*
G36*
G01X427130Y977280D02*
G02Y979684I0J1202D01*
G01X430831D01*
G02Y977280I0J-1202D01*
G01X427130D01*
G37*
G36*
G01Y964524D02*
G02Y966928I0J1202D01*
G01X430831D01*
G02Y964524I0J-1202D01*
G01X427130D01*
G37*
G36*
G01X432012Y1118550D02*
G02Y1116146I0J-1202D01*
G01X428311D01*
G02Y1118550I0J1202D01*
G01X432012D01*
G37*
G36*
G01Y1112172D02*
G02Y1109768I0J-1202D01*
G01X428311D01*
G02Y1112172I0J1202D01*
G01X432012D01*
G37*
G36*
G01Y1144062D02*
G02Y1141656I0J-1203D01*
G01X428311D01*
G02Y1144062I0J1203D01*
G01X432012D01*
G37*
G36*
G01Y1137684D02*
G02Y1135278I0J-1203D01*
G01X428311D01*
G02Y1137684I0J1203D01*
G01X432012D01*
G37*
G36*
G01Y1131306D02*
G02Y1128900I0J-1203D01*
G01X428311D01*
G02Y1131306I0J1203D01*
G01X432012D01*
G37*
G36*
G01Y1124928D02*
G02Y1122524I0J-1202D01*
G01X428311D01*
G02Y1124928I0J1202D01*
G01X432012D01*
G37*
G36*
G01X459743Y1132090D02*
G02Y1134496I0J1203D01*
G01X463444D01*
G02Y1132090I0J-1203D01*
G01X459743D01*
G37*
G36*
G01X493050Y1138468D02*
G02Y1140872I0J1202D01*
G01X496751D01*
G02Y1138468I0J-1202D01*
G01X493050D01*
G37*
G36*
G01Y1119334D02*
G02Y1121740I0J1203D01*
G01X496751D01*
G02Y1119334I0J-1203D01*
G01X493050D01*
G37*
G36*
G01X485649Y1121740D02*
G02Y1119334I0J-1203D01*
G01X481948D01*
G02Y1121740I0J1203D01*
G01X485649D01*
G37*
G36*
G01X470845Y1119334D02*
G02Y1121740I0J1203D01*
G01X474546D01*
G02Y1119334I0J-1203D01*
G01X470845D01*
G37*
G36*
G01X450491Y1128900D02*
G02Y1131306I0J1203D01*
G01X454192D01*
G02Y1128900I0J-1203D01*
G01X450491D01*
G37*
G36*
G01X459743Y1125712D02*
G02Y1128118I0J1203D01*
G01X463444D01*
G02Y1125712I0J-1203D01*
G01X459743D01*
G37*
G36*
G01Y1119334D02*
G02Y1121740I0J1203D01*
G01X463444D01*
G02Y1119334I0J-1203D01*
G01X459743D01*
G37*
G36*
G01X450491Y1141656D02*
G02Y1144062I0J1203D01*
G01X454192D01*
G02Y1141656I0J-1203D01*
G01X450491D01*
G37*
G36*
G01Y1122524D02*
G02Y1124928I0J1202D01*
G01X454192D01*
G02Y1122524I0J-1202D01*
G01X450491D01*
G37*
G36*
G01X485649Y1140872D02*
G02Y1138468I0J-1202D01*
G01X481948D01*
G02Y1140872I0J1202D01*
G01X485649D01*
G37*
G36*
G01X493050Y1112956D02*
G02Y1115362I0J1203D01*
G01X496751D01*
G02Y1112956I0J-1203D01*
G01X493050D01*
G37*
G36*
G01X450491Y1116146D02*
G02Y1118550I0J1202D01*
G01X454192D01*
G02Y1116146I0J-1202D01*
G01X450491D01*
G37*
G36*
G01X493050Y1132090D02*
G02Y1134496I0J1203D01*
G01X496751D01*
G02Y1132090I0J-1203D01*
G01X493050D01*
G37*
G36*
G01X485649Y1134496D02*
G02Y1132090I0J-1203D01*
G01X481948D01*
G02Y1134496I0J1203D01*
G01X485649D01*
G37*
G36*
G01X450491Y1135278D02*
G02Y1137684I0J1203D01*
G01X454192D01*
G02Y1135278I0J-1203D01*
G01X450491D01*
G37*
G36*
G01X470845Y1132090D02*
G02Y1134496I0J1203D01*
G01X474546D01*
G02Y1132090I0J-1203D01*
G01X470845D01*
G37*
G36*
G01X493050Y1106578D02*
G02Y1108984I0J1203D01*
G01X496751D01*
G02Y1106578I0J-1203D01*
G01X493050D01*
G37*
G36*
G01X485649Y1115362D02*
G02Y1112956I0J-1203D01*
G01X481948D01*
G02Y1115362I0J1203D01*
G01X485649D01*
G37*
G36*
G01X470845Y1112956D02*
G02Y1115362I0J1203D01*
G01X474546D01*
G02Y1112956I0J-1203D01*
G01X470845D01*
G37*
G36*
G01X485649Y1108984D02*
G02Y1106578I0J-1203D01*
G01X481948D01*
G02Y1108984I0J1203D01*
G01X485649D01*
G37*
G36*
G01X470845Y1138468D02*
G02Y1140872I0J1202D01*
G01X474546D01*
G02Y1138468I0J-1202D01*
G01X470845D01*
G37*
G36*
G01X459743D02*
G02Y1140872I0J1202D01*
G01X463444D01*
G02Y1138468I0J-1202D01*
G01X459743D01*
G37*
G36*
G01X1361894Y1132090D02*
G02Y1134494I0J1202D01*
G01X1365595D01*
G02Y1132090I0J-1202D01*
G01X1361894D01*
G37*
G36*
G01X1365595Y1121738D02*
G02Y1119334I0J-1202D01*
G01X1361894D01*
G02Y1121738I0J1202D01*
G01X1365595D01*
G37*
G36*
G01X1361894Y1125712D02*
G02Y1128116I0J1202D01*
G01X1365595D01*
G02Y1125712I0J-1202D01*
G01X1361894D01*
G37*
G36*
G01X1376698Y1121738D02*
G02Y1119334I0J-1202D01*
G01X1372997D01*
G02Y1121738I0J1202D01*
G01X1376698D01*
G37*
G36*
G01Y1128116D02*
G02Y1125712I0J-1202D01*
G01X1372997D01*
G02Y1128116I0J1202D01*
G01X1376698D01*
G37*
G36*
G01Y1115360D02*
G02Y1112956I0J-1202D01*
G01X1372997D01*
G02Y1115360I0J1202D01*
G01X1376698D01*
G37*
G36*
G01X1365595D02*
G02Y1112956I0J-1202D01*
G01X1361894D01*
G02Y1115360I0J1202D01*
G01X1365595D01*
G37*
G36*
G01Y1108982D02*
G02Y1106578I0J-1202D01*
G01X1361894D01*
G02Y1108982I0J1202D01*
G01X1365595D01*
G37*
G36*
G01X1376698D02*
G02Y1106578I0J-1202D01*
G01X1372997D01*
G02Y1108982I0J1202D01*
G01X1376698D01*
G37*
G36*
G01X1372997Y1144844D02*
G02Y1147250I0J1203D01*
G01X1376698D01*
G02Y1144844I0J-1203D01*
G01X1372997D01*
G37*
G36*
G01Y1138466D02*
G02Y1140872I0J1203D01*
G01X1376698D01*
G02Y1138466I0J-1203D01*
G01X1372997D01*
G37*
G36*
G01X1361894Y1144844D02*
G02Y1147250I0J1203D01*
G01X1365595D01*
G02Y1144844I0J-1203D01*
G01X1361894D01*
G37*
G36*
G01Y1138466D02*
G02Y1140872I0J1203D01*
G01X1365595D01*
G02Y1138466I0J-1203D01*
G01X1361894D01*
G37*
G36*
G01X1372997Y1132090D02*
G02Y1134494I0J1202D01*
G01X1376698D01*
G02Y1132090I0J-1202D01*
G01X1372997D01*
G37*
G36*
G01X1384099D02*
G02Y1134494I0J1202D01*
G01X1387800D01*
G02Y1132090I0J-1202D01*
G01X1384099D01*
G37*
G36*
G01X1387800Y1121738D02*
G02Y1119334I0J-1202D01*
G01X1384099D01*
G02Y1121738I0J1202D01*
G01X1387800D01*
G37*
G36*
G01Y1128116D02*
G02Y1125712I0J-1202D01*
G01X1384099D01*
G02Y1128116I0J1202D01*
G01X1387800D01*
G37*
G36*
G01Y1115360D02*
G02Y1112956I0J-1202D01*
G01X1384099D01*
G02Y1115360I0J1202D01*
G01X1387800D01*
G37*
G36*
G01X1384099Y1144844D02*
G02Y1147250I0J1203D01*
G01X1387800D01*
G02Y1144844I0J-1203D01*
G01X1384099D01*
G37*
G36*
G01Y1138466D02*
G02Y1140872I0J1203D01*
G01X1387800D01*
G02Y1138466I0J-1203D01*
G01X1384099D01*
G37*
G36*
G01X1408154Y1118550D02*
G02Y1116144I0J-1203D01*
G01X1404453D01*
G02Y1118550I0J1203D01*
G01X1408154D01*
G37*
G36*
G01Y1112172D02*
G02Y1109766I0J-1203D01*
G01X1404453D01*
G02Y1112172I0J1203D01*
G01X1408154D01*
G37*
G36*
G01X1404453Y1128900D02*
G02Y1131304I0J1202D01*
G01X1408154D01*
G02Y1128900I0J-1202D01*
G01X1404453D01*
G37*
G36*
G01X1395201Y1132090D02*
G02Y1134494I0J1202D01*
G01X1398902D01*
G02Y1132090I0J-1202D01*
G01X1395201D01*
G37*
G36*
G01X1398902Y1128116D02*
G02Y1125712I0J-1202D01*
G01X1395201D01*
G02Y1128116I0J1202D01*
G01X1398902D01*
G37*
G36*
G01X1408154Y1124928D02*
G02Y1122522I0J-1203D01*
G01X1404453D01*
G02Y1124928I0J1203D01*
G01X1408154D01*
G37*
G36*
G01X1398902Y1121738D02*
G02Y1119334I0J-1202D01*
G01X1395201D01*
G02Y1121738I0J1202D01*
G01X1398902D01*
G37*
G36*
G01Y1115360D02*
G02Y1112956I0J-1202D01*
G01X1395201D01*
G02Y1115360I0J1202D01*
G01X1398902D01*
G37*
G36*
G01X1404453Y1135278D02*
G02Y1137682I0J1202D01*
G01X1408154D01*
G02Y1135278I0J-1202D01*
G01X1404453D01*
G37*
G36*
G01X1395201Y1144844D02*
G02Y1147250I0J1203D01*
G01X1398902D01*
G02Y1144844I0J-1203D01*
G01X1395201D01*
G37*
G36*
G01Y1138466D02*
G02Y1140872I0J1203D01*
G01X1398902D01*
G02Y1138466I0J-1203D01*
G01X1395201D01*
G37*
G36*
G01X1404453Y1141656D02*
G02Y1144060I0J1202D01*
G01X1408154D01*
G02Y1141656I0J-1202D01*
G01X1404453D01*
G37*
G36*
G01X1425452Y919876D02*
G02Y922282I0J1203D01*
G01X1429153D01*
G02Y919876I0J-1203D01*
G01X1425452D01*
G37*
G36*
G01Y913498D02*
G02Y915904I0J1203D01*
G01X1429153D01*
G02Y913498I0J-1203D01*
G01X1425452D01*
G37*
G36*
G01X1434704Y910310D02*
G02Y912714I0J1202D01*
G01X1438405D01*
G02Y910310I0J-1202D01*
G01X1434704D01*
G37*
G36*
G01X1425452Y926254D02*
G02Y928660I0J1203D01*
G01X1429153D01*
G02Y926254I0J-1203D01*
G01X1425452D01*
G37*
G36*
G01X1434704Y916688D02*
G02Y919092I0J1202D01*
G01X1438405D01*
G02Y916688I0J-1202D01*
G01X1434704D01*
G37*
G36*
G01Y923066D02*
G02Y925470I0J1202D01*
G01X1438405D01*
G02Y923066I0J-1202D01*
G01X1434704D01*
G37*
G36*
G01X1429153Y960550D02*
G02Y958144I0J-1203D01*
G01X1425452D01*
G02Y960550I0J1203D01*
G01X1429153D01*
G37*
G36*
G01X1438405Y970116D02*
G02Y967712I0J-1202D01*
G01X1434704D01*
G02Y970116I0J1202D01*
G01X1438405D01*
G37*
G36*
G01X1429153Y966928D02*
G02Y964522I0J-1203D01*
G01X1425452D01*
G02Y966928I0J1203D01*
G01X1429153D01*
G37*
G36*
G01X1438405Y963738D02*
G02Y961334I0J-1202D01*
G01X1434704D01*
G02Y963738I0J1202D01*
G01X1438405D01*
G37*
G36*
G01X1429153Y979684D02*
G02Y977278I0J-1203D01*
G01X1425452D01*
G02Y979684I0J1203D01*
G01X1429153D01*
G37*
G36*
G01X1438405Y976494D02*
G02Y974090I0J-1202D01*
G01X1434704D01*
G02Y976494I0J1202D01*
G01X1438405D01*
G37*
G36*
G01X1429153Y973306D02*
G02Y970900I0J-1203D01*
G01X1425452D01*
G02Y973306I0J1203D01*
G01X1429153D01*
G37*
G36*
G01X1426633Y1128900D02*
G02Y1131304I0J1202D01*
G01X1430334D01*
G02Y1128900I0J-1202D01*
G01X1426633D01*
G37*
G36*
G01Y1122522D02*
G02Y1124928I0J1203D01*
G01X1430334D01*
G02Y1122522I0J-1203D01*
G01X1426633D01*
G37*
G36*
G01Y1116144D02*
G02Y1118550I0J1203D01*
G01X1430334D01*
G02Y1116144I0J-1203D01*
G01X1426633D01*
G37*
G36*
G01Y1109766D02*
G02Y1112172I0J1203D01*
G01X1430334D01*
G02Y1109766I0J-1203D01*
G01X1426633D01*
G37*
G36*
G01Y1141656D02*
G02Y1144060I0J1202D01*
G01X1430334D01*
G02Y1141656I0J-1202D01*
G01X1426633D01*
G37*
G36*
G01Y1135278D02*
G02Y1137682I0J1202D01*
G01X1430334D01*
G02Y1135278I0J-1202D01*
G01X1426633D01*
G37*
G36*
G01X1445806Y916688D02*
G02Y919092I0J1202D01*
G01X1449507D01*
G02Y916688I0J-1202D01*
G01X1445806D01*
G37*
G36*
G01Y910310D02*
G02Y912714I0J1202D01*
G01X1449507D01*
G02Y910310I0J-1202D01*
G01X1445806D01*
G37*
G36*
G01Y923066D02*
G02Y925470I0J1202D01*
G01X1449507D01*
G02Y923066I0J-1202D01*
G01X1445806D01*
G37*
G36*
G01X1449507Y976494D02*
G02Y974090I0J-1202D01*
G01X1445806D01*
G02Y976494I0J1202D01*
G01X1449507D01*
G37*
G36*
G01Y970116D02*
G02Y967712I0J-1202D01*
G01X1445806D01*
G02Y970116I0J1202D01*
G01X1449507D01*
G37*
G36*
G01Y963738D02*
G02Y961334I0J-1202D01*
G01X1445806D01*
G02Y963738I0J1202D01*
G01X1449507D01*
G37*
G36*
G01X1435885Y1125712D02*
G02Y1128116I0J1202D01*
G01X1439586D01*
G02Y1125712I0J-1202D01*
G01X1435885D01*
G37*
G36*
G01Y1119334D02*
G02Y1121738I0J1202D01*
G01X1439586D01*
G02Y1119334I0J-1202D01*
G01X1435885D01*
G37*
G36*
G01X1446987Y1125712D02*
G02Y1128116I0J1202D01*
G01X1450688D01*
G02Y1125712I0J-1202D01*
G01X1446987D01*
G37*
G36*
G01Y1119334D02*
G02Y1121738I0J1202D01*
G01X1450688D01*
G02Y1119334I0J-1202D01*
G01X1446987D01*
G37*
G36*
G01X1435885Y1112956D02*
G02Y1115360I0J1202D01*
G01X1439586D01*
G02Y1112956I0J-1202D01*
G01X1435885D01*
G37*
G36*
G01X1446987D02*
G02Y1115360I0J1202D01*
G01X1450688D01*
G02Y1112956I0J-1202D01*
G01X1446987D01*
G37*
G36*
G01X1435885Y1144844D02*
G02Y1147250I0J1203D01*
G01X1439586D01*
G02Y1144844I0J-1203D01*
G01X1435885D01*
G37*
G36*
G01X1446987D02*
G02Y1147250I0J1203D01*
G01X1450688D01*
G02Y1144844I0J-1203D01*
G01X1446987D01*
G37*
G36*
G01Y1138466D02*
G02Y1140872I0J1203D01*
G01X1450688D01*
G02Y1138466I0J-1203D01*
G01X1446987D01*
G37*
G36*
G01X1435885D02*
G02Y1140872I0J1203D01*
G01X1439586D01*
G02Y1138466I0J-1203D01*
G01X1435885D01*
G37*
G36*
G01X1446987Y1132090D02*
G02Y1134494I0J1202D01*
G01X1450688D01*
G02Y1132090I0J-1202D01*
G01X1446987D01*
G37*
G36*
G01X1435885D02*
G02Y1134494I0J1202D01*
G01X1439586D01*
G02Y1132090I0J-1202D01*
G01X1435885D01*
G37*
G36*
G01X1456909Y910310D02*
G02Y912714I0J1202D01*
G01X1460610D01*
G02Y910310I0J-1202D01*
G01X1456909D01*
G37*
G36*
G01Y923066D02*
G02Y925470I0J1202D01*
G01X1460610D01*
G02Y923066I0J-1202D01*
G01X1456909D01*
G37*
G36*
G01Y916688D02*
G02Y919092I0J1202D01*
G01X1460610D01*
G02Y916688I0J-1202D01*
G01X1456909D01*
G37*
G36*
G01Y929444D02*
G02Y931848I0J1202D01*
G01X1460610D01*
G02Y929444I0J-1202D01*
G01X1456909D01*
G37*
G36*
G01X1460610Y970116D02*
G02Y967712I0J-1202D01*
G01X1456909D01*
G02Y970116I0J1202D01*
G01X1460610D01*
G37*
G36*
G01Y963738D02*
G02Y961334I0J-1202D01*
G01X1456909D01*
G02Y963738I0J1202D01*
G01X1460610D01*
G37*
G36*
G01Y976494D02*
G02Y974090I0J-1202D01*
G01X1456909D01*
G02Y976494I0J1202D01*
G01X1460610D01*
G37*
G36*
G01X1458090Y1132090D02*
G02Y1134494I0J1202D01*
G01X1461791D01*
G02Y1132090I0J-1202D01*
G01X1458090D01*
G37*
G36*
G01Y1125712D02*
G02Y1128116I0J1202D01*
G01X1461791D01*
G02Y1125712I0J-1202D01*
G01X1458090D01*
G37*
G36*
G01Y1119334D02*
G02Y1121738I0J1202D01*
G01X1461791D01*
G02Y1119334I0J-1202D01*
G01X1458090D01*
G37*
G36*
G01Y1112956D02*
G02Y1115360I0J1202D01*
G01X1461791D01*
G02Y1112956I0J-1202D01*
G01X1458090D01*
G37*
G36*
G01Y1106578D02*
G02Y1108982I0J1202D01*
G01X1461791D01*
G02Y1106578I0J-1202D01*
G01X1458090D01*
G37*
G36*
G01Y1144844D02*
G02Y1147250I0J1203D01*
G01X1461791D01*
G02Y1144844I0J-1203D01*
G01X1458090D01*
G37*
G36*
G01Y1138466D02*
G02Y1140872I0J1203D01*
G01X1461791D01*
G02Y1138466I0J-1203D01*
G01X1458090D01*
G37*
G36*
G01X1468011Y929444D02*
G02Y931848I0J1202D01*
G01X1471712D01*
G02Y929444I0J-1202D01*
G01X1468011D01*
G37*
G36*
G01Y923066D02*
G02Y925470I0J1202D01*
G01X1471712D01*
G02Y923066I0J-1202D01*
G01X1468011D01*
G37*
G36*
G01Y916688D02*
G02Y919092I0J1202D01*
G01X1471712D01*
G02Y916688I0J-1202D01*
G01X1468011D01*
G37*
G36*
G01X1471712Y970116D02*
G02Y967712I0J-1202D01*
G01X1468011D01*
G02Y970116I0J1202D01*
G01X1471712D01*
G37*
G36*
G01Y963738D02*
G02Y961334I0J-1202D01*
G01X1468011D01*
G02Y963738I0J1202D01*
G01X1471712D01*
G37*
G36*
G01Y976494D02*
G02Y974090I0J-1202D01*
G01X1468011D01*
G02Y976494I0J1202D01*
G01X1471712D01*
G37*
G36*
G01X1469192Y1106578D02*
G02Y1108982I0J1202D01*
G01X1472893D01*
G02Y1106578I0J-1202D01*
G01X1469192D01*
G37*
G36*
G01Y1119334D02*
G02Y1121738I0J1202D01*
G01X1472893D01*
G02Y1119334I0J-1202D01*
G01X1469192D01*
G37*
G36*
G01Y1125712D02*
G02Y1128116I0J1202D01*
G01X1472893D01*
G02Y1125712I0J-1202D01*
G01X1469192D01*
G37*
G36*
G01Y1112956D02*
G02Y1115360I0J1202D01*
G01X1472893D01*
G02Y1112956I0J-1202D01*
G01X1469192D01*
G37*
G36*
G01Y1144844D02*
G02Y1147250I0J1203D01*
G01X1472893D01*
G02Y1144844I0J-1203D01*
G01X1469192D01*
G37*
G36*
G01Y1138466D02*
G02Y1140872I0J1203D01*
G01X1472893D01*
G02Y1138466I0J-1203D01*
G01X1469192D01*
G37*
G36*
G01Y1132090D02*
G02Y1134494I0J1202D01*
G01X1472893D01*
G02Y1132090I0J-1202D01*
G01X1469192D01*
G37*
G36*
G01X359251Y1520264D02*
G02X360311Y1520900I1060J-565D01*
G02X361514Y1519698I1J-1202D01*
G02X361353Y1519098I-1204J1D01*
G01X359808Y1516425D01*
X359806Y1516421D01*
G02X358736Y1515768I-1070J550D01*
G02X357534Y1516970I0J1202D01*
G01Y1516972D01*
G02X357683Y1517551I1202J-1D01*
G01X359249Y1520261D01*
X359251Y1520264D01*
G37*
G36*
G01X1592873Y1655790D02*
G02Y1658794I0J1502D01*
G01X1596273D01*
G02Y1655790I0J-1502D01*
G01X1592873D01*
G37*
G36*
G01X1616993D02*
G02Y1658794I0J1502D01*
G01X1620393D01*
G02Y1655790I0J-1502D01*
G01X1616993D01*
G37*
G36*
G01X1274429Y1645790D02*
G02Y1648794I0J1502D01*
G01X1277829D01*
G02Y1645790I0J-1502D01*
G01X1274429D01*
G37*
G36*
G01X1286489D02*
G02Y1648794I0J1502D01*
G01X1289889D01*
G02Y1645790I0J-1502D01*
G01X1286489D01*
G37*
G36*
G01X459743Y1112956D02*
G02Y1115362I0J1203D01*
G01X463444D01*
G02Y1112956I0J-1203D01*
G01X459743D01*
G37*
G36*
G01X470845Y1125712D02*
G02Y1128118I0J1203D01*
G01X474546D01*
G02Y1125712I0J-1203D01*
G01X470845D01*
G37*
G36*
G01X450491Y1109768D02*
G02Y1112172I0J1202D01*
G01X454192D01*
G02Y1109768I0J-1202D01*
G01X450491D01*
G37*
G36*
G01X1494998Y1494092D02*
G02Y1497098I0J1503D01*
G01X1498398D01*
G02Y1494092I0J-1503D01*
G01X1494998D01*
G37*
G36*
G01X507224Y1470792D02*
G02Y1473798I0J1503D01*
G01X510624D01*
G02Y1470792I0J-1503D01*
G01X507224D01*
G37*
G36*
G01X335629Y1520264D02*
G02X336689Y1520900I1060J-565D01*
G02X337892Y1519698I1J-1202D01*
G02X337731Y1519098I-1204J1D01*
G01X336186Y1516425D01*
X336184Y1516421D01*
G02X335114Y1515768I-1070J550D01*
G02X333912Y1516970I0J1202D01*
G01Y1516972D01*
G02X334061Y1517551I1202J-1D01*
G01X335627Y1520261D01*
X335629Y1520264D01*
G37*
G36*
G01X433524Y1461092D02*
G02Y1464098I0J1503D01*
G01X436924D01*
G02Y1461092I0J-1503D01*
G01X433524D01*
G37*
G36*
G01X384513Y1451392D02*
G02Y1454398I0J1503D01*
G01X387913D01*
G02Y1451392I0J-1503D01*
G01X384513D01*
G37*
G36*
G01X1204024Y1494092D02*
G02Y1497098I0J1503D01*
G01X1207424D01*
G02Y1494092I0J-1503D01*
G01X1204024D01*
G37*
G36*
G01X242436Y1600878D02*
G02Y1603882I0J1502D01*
G01X245836D01*
G02Y1600878I0J-1502D01*
G01X242436D01*
G37*
G36*
G01Y1612790D02*
G02Y1615794I0J1502D01*
G01X245836D01*
G02Y1612790I0J-1502D01*
G01X242436D01*
G37*
G36*
G01X266556Y1600878D02*
G02Y1603882I0J1502D01*
G01X269956D01*
G02Y1600878I0J-1502D01*
G01X266556D01*
G37*
G36*
G01X254496D02*
G02Y1603882I0J1502D01*
G01X257896D01*
G02Y1600878I0J-1502D01*
G01X254496D01*
G37*
G36*
G01X278616Y1612790D02*
G02Y1615794I0J1502D01*
G01X282016D01*
G02Y1612790I0J-1502D01*
G01X278616D01*
G37*
G36*
G01X290676Y1600878D02*
G02Y1603882I0J1502D01*
G01X294076D01*
G02Y1600878I0J-1502D01*
G01X290676D01*
G37*
G36*
G01Y1612790D02*
G02Y1615794I0J1502D01*
G01X294076D01*
G02Y1612790I0J-1502D01*
G01X290676D01*
G37*
G36*
G01X302736D02*
G02Y1615794I0J1502D01*
G01X306136D01*
G02Y1612790I0J-1502D01*
G01X302736D01*
G37*
G36*
G01X314796Y1600878D02*
G02Y1603882I0J1502D01*
G01X318196D01*
G02Y1600878I0J-1502D01*
G01X314796D01*
G37*
G36*
G01X584999Y1590878D02*
G02Y1593882I0J1502D01*
G01X588399D01*
G02Y1590878I0J-1502D01*
G01X584999D01*
G37*
G36*
G01X597059Y1622790D02*
G02Y1625794I0J1502D01*
G01X600459D01*
G02Y1622790I0J-1502D01*
G01X597059D01*
G37*
G36*
G01X1196039Y1655790D02*
G02Y1658794I0J1502D01*
G01X1199439D01*
G02Y1655790I0J-1502D01*
G01X1196039D01*
G37*
G36*
G01X491919Y1625794D02*
G02Y1622790I0J-1502D01*
G01X488519D01*
G02Y1625794I0J1502D01*
G01X491919D01*
G37*
G36*
G01X500579Y1622790D02*
G02Y1625794I0J1502D01*
G01X503979D01*
G02Y1622790I0J-1502D01*
G01X500579D01*
G37*
G36*
G01X512639D02*
G02Y1625794I0J1502D01*
G01X516039D01*
G02Y1622790I0J-1502D01*
G01X512639D01*
G37*
G36*
G01X524699Y1590878D02*
G02Y1593882I0J1502D01*
G01X528099D01*
G02Y1590878I0J-1502D01*
G01X524699D01*
G37*
G36*
G01Y1622790D02*
G02Y1625794I0J1502D01*
G01X528099D01*
G02Y1622790I0J-1502D01*
G01X524699D01*
G37*
G36*
G01X548819Y1590878D02*
G02Y1593882I0J1502D01*
G01X552219D01*
G02Y1590878I0J-1502D01*
G01X548819D01*
G37*
G36*
G01Y1622790D02*
G02Y1625794I0J1502D01*
G01X552219D01*
G02Y1622790I0J-1502D01*
G01X548819D01*
G37*
G36*
G01X560879D02*
G02Y1625794I0J1502D01*
G01X564279D01*
G02Y1622790I0J-1502D01*
G01X560879D01*
G37*
G36*
G01X572939D02*
G02Y1625794I0J1502D01*
G01X576339D01*
G02Y1622790I0J-1502D01*
G01X572939D01*
G37*
G36*
G01X566909Y1600878D02*
G02Y1603882I0J1502D01*
G01X570309D01*
G02Y1600878I0J-1502D01*
G01X566909D01*
G37*
G36*
G01Y1612790D02*
G02Y1615794I0J1502D01*
G01X570309D01*
G02Y1612790I0J-1502D01*
G01X566909D01*
G37*
G36*
G01X591029D02*
G02Y1615794I0J1502D01*
G01X594429D01*
G02Y1612790I0J-1502D01*
G01X591029D01*
G37*
G36*
G01X603089D02*
G02Y1615794I0J1502D01*
G01X606489D01*
G02Y1612790I0J-1502D01*
G01X603089D01*
G37*
G36*
G01X461769Y1615794D02*
G02Y1612790I0J-1502D01*
G01X458369D01*
G02Y1615794I0J1502D01*
G01X461769D01*
G37*
G36*
G01X470429Y1612790D02*
G02Y1615794I0J1502D01*
G01X473829D01*
G02Y1612790I0J-1502D01*
G01X470429D01*
G37*
G36*
G01X506609Y1600878D02*
G02Y1603882I0J1502D01*
G01X510009D01*
G02Y1600878I0J-1502D01*
G01X506609D01*
G37*
G36*
G01Y1612790D02*
G02Y1615794I0J1502D01*
G01X510009D01*
G02Y1612790I0J-1502D01*
G01X506609D01*
G37*
G36*
G01X522069Y1615794D02*
G02Y1612790I0J-1502D01*
G01X518669D01*
G02Y1615794I0J1502D01*
G01X522069D01*
G37*
G36*
G01X530729Y1612790D02*
G02Y1615794I0J1502D01*
G01X534129D01*
G02Y1612790I0J-1502D01*
G01X530729D01*
G37*
G36*
G01X542789D02*
G02Y1615794I0J1502D01*
G01X546189D01*
G02Y1612790I0J-1502D01*
G01X542789D01*
G37*
G36*
G01X188166Y1622790D02*
G02Y1625794I0J1502D01*
G01X191566D01*
G02Y1622790I0J-1502D01*
G01X188166D01*
G37*
G36*
G01Y1590878D02*
G02Y1593882I0J1502D01*
G01X191566D01*
G02Y1590878I0J-1502D01*
G01X188166D01*
G37*
G36*
G01X326856Y1612790D02*
G02Y1615794I0J1502D01*
G01X330256D01*
G02Y1612790I0J-1502D01*
G01X326856D01*
G37*
G36*
G01X377813Y1461092D02*
G02Y1464098I0J1503D01*
G01X381213D01*
G02Y1461092I0J-1503D01*
G01X377813D01*
G37*
G36*
G01X206256Y1612790D02*
G02Y1615794I0J1502D01*
G01X209656D01*
G02Y1612790I0J-1502D01*
G01X206256D01*
G37*
G36*
G01X308766Y1622790D02*
G02Y1625794I0J1502D01*
G01X312166D01*
G02Y1622790I0J-1502D01*
G01X308766D01*
G37*
G36*
G01Y1590878D02*
G02Y1593882I0J1502D01*
G01X312166D01*
G02Y1590878I0J-1502D01*
G01X308766D01*
G37*
G36*
G01X296706Y1622790D02*
G02Y1625794I0J1502D01*
G01X300106D01*
G02Y1622790I0J-1502D01*
G01X296706D01*
G37*
G36*
G01X284646Y1590878D02*
G02Y1593882I0J1502D01*
G01X288046D01*
G02Y1590878I0J-1502D01*
G01X284646D01*
G37*
G36*
G01Y1622790D02*
G02Y1625794I0J1502D01*
G01X288046D01*
G02Y1622790I0J-1502D01*
G01X284646D01*
G37*
G36*
G01X272586D02*
G02Y1625794I0J1502D01*
G01X275986D01*
G02Y1622790I0J-1502D01*
G01X272586D01*
G37*
G36*
G01X1183924Y1484392D02*
G02Y1487398I0J1503D01*
G01X1187324D01*
G02Y1484392I0J-1503D01*
G01X1183924D01*
G37*
G36*
G01X260526Y1590878D02*
G02Y1593882I0J1502D01*
G01X263926D01*
G02Y1590878I0J-1502D01*
G01X260526D01*
G37*
G36*
G01Y1622790D02*
G02Y1625794I0J1502D01*
G01X263926D01*
G02Y1622790I0J-1502D01*
G01X260526D01*
G37*
G36*
G01X248466D02*
G02Y1625794I0J1502D01*
G01X251866D01*
G02Y1622790I0J-1502D01*
G01X248466D01*
G37*
G36*
G01X236406D02*
G02Y1625794I0J1502D01*
G01X239806D01*
G02Y1622790I0J-1502D01*
G01X236406D01*
G37*
G36*
G01X224346D02*
G02Y1625794I0J1502D01*
G01X227746D01*
G02Y1622790I0J-1502D01*
G01X224346D01*
G37*
G36*
G01Y1590878D02*
G02Y1593882I0J1502D01*
G01X227746D01*
G02Y1590878I0J-1502D01*
G01X224346D01*
G37*
G36*
G01X1237524Y1484392D02*
G02Y1487398I0J1503D01*
G01X1240924D01*
G02Y1484392I0J-1503D01*
G01X1237524D01*
G37*
G36*
G01X1210724D02*
G02Y1487398I0J1503D01*
G01X1214124D01*
G02Y1484392I0J-1503D01*
G01X1210724D01*
G37*
G36*
G01X351013Y1461092D02*
G02Y1464098I0J1503D01*
G01X354413D01*
G02Y1461092I0J-1503D01*
G01X351013D01*
G37*
G36*
G01X1378986Y1503792D02*
G02Y1506798I0J1503D01*
G01X1382386D01*
G02Y1503792I0J-1503D01*
G01X1378986D01*
G37*
G36*
G01X320826Y1622790D02*
G02Y1625794I0J1502D01*
G01X324226D01*
G02Y1622790I0J-1502D01*
G01X320826D01*
G37*
G36*
G01X332886D02*
G02Y1625794I0J1502D01*
G01X336286D01*
G02Y1622790I0J-1502D01*
G01X332886D01*
G37*
G36*
G01X344946D02*
G02Y1625794I0J1502D01*
G01X348346D01*
G02Y1622790I0J-1502D01*
G01X344946D01*
G37*
G36*
G01X369066Y1590878D02*
G02Y1593882I0J1502D01*
G01X372466D01*
G02Y1590878I0J-1502D01*
G01X369066D01*
G37*
G36*
G01X452339Y1622790D02*
G02Y1625794I0J1502D01*
G01X455739D01*
G02Y1622790I0J-1502D01*
G01X452339D01*
G37*
G36*
G01X369066D02*
G02Y1625794I0J1502D01*
G01X372466D01*
G02Y1622790I0J-1502D01*
G01X369066D01*
G37*
G36*
G01X1538603Y1645790D02*
G02Y1648794I0J1502D01*
G01X1542003D01*
G02Y1645790I0J-1502D01*
G01X1538603D01*
G37*
G36*
G01X1550663D02*
G02Y1648794I0J1502D01*
G01X1554063D01*
G02Y1645790I0J-1502D01*
G01X1550663D01*
G37*
G36*
G01X1562723D02*
G02Y1648794I0J1502D01*
G01X1566123D01*
G02Y1645790I0J-1502D01*
G01X1562723D01*
G37*
G36*
G01X200226Y1622790D02*
G02Y1625794I0J1502D01*
G01X203626D01*
G02Y1622790I0J-1502D01*
G01X200226D01*
G37*
G36*
G01X320826Y1590878D02*
G02Y1593882I0J1502D01*
G01X324226D01*
G02Y1590878I0J-1502D01*
G01X320826D01*
G37*
G36*
G01X1568753Y1655790D02*
G02Y1658794I0J1502D01*
G01X1572153D01*
G02Y1655790I0J-1502D01*
G01X1568753D01*
G37*
G36*
G01X1580813D02*
G02Y1658794I0J1502D01*
G01X1584213D01*
G02Y1655790I0J-1502D01*
G01X1580813D01*
G37*
G36*
G01X1382969Y1645790D02*
G02Y1648794I0J1502D01*
G01X1386369D01*
G02Y1645790I0J-1502D01*
G01X1382969D01*
G37*
G36*
G01X1586843D02*
G02Y1648794I0J1502D01*
G01X1590243D01*
G02Y1645790I0J-1502D01*
G01X1586843D01*
G37*
G36*
G01X1610963D02*
G02Y1648794I0J1502D01*
G01X1614363D01*
G02Y1645790I0J-1502D01*
G01X1610963D01*
G37*
G36*
G01X1623023Y1633878D02*
G02Y1636882I0J1502D01*
G01X1626423D01*
G02Y1633878I0J-1502D01*
G01X1623023D01*
G37*
G36*
G01Y1645790D02*
G02Y1648794I0J1502D01*
G01X1626423D01*
G02Y1645790I0J-1502D01*
G01X1623023D01*
G37*
G36*
G01X1635083D02*
G02Y1648794I0J1502D01*
G01X1638483D01*
G02Y1645790I0J-1502D01*
G01X1635083D01*
G37*
G36*
G01X1466243D02*
G02Y1648794I0J1502D01*
G01X1469643D01*
G02Y1645790I0J-1502D01*
G01X1466243D01*
G37*
G36*
G01X1478303D02*
G02Y1648794I0J1502D01*
G01X1481703D01*
G02Y1645790I0J-1502D01*
G01X1478303D01*
G37*
G36*
G01X1490363D02*
G02Y1648794I0J1502D01*
G01X1493763D01*
G02Y1645790I0J-1502D01*
G01X1490363D01*
G37*
G36*
G01X1502423Y1633878D02*
G02Y1636882I0J1502D01*
G01X1505823D01*
G02Y1633878I0J-1502D01*
G01X1502423D01*
G37*
G36*
G01Y1645790D02*
G02Y1648794I0J1502D01*
G01X1505823D01*
G02Y1645790I0J-1502D01*
G01X1502423D01*
G37*
G36*
G01X1514483D02*
G02Y1648794I0J1502D01*
G01X1517883D01*
G02Y1645790I0J-1502D01*
G01X1514483D01*
G37*
G36*
G01X1526543D02*
G02Y1648794I0J1502D01*
G01X1529943D01*
G02Y1645790I0J-1502D01*
G01X1526543D01*
G37*
G36*
G01X1461498Y1503792D02*
G02Y1506798I0J1503D01*
G01X1464898D01*
G02Y1503792I0J-1503D01*
G01X1461498D01*
G37*
G36*
G01X1569460Y1494092D02*
G02Y1497098I0J1503D01*
G01X1572860D01*
G02Y1494092I0J-1503D01*
G01X1569460D01*
G37*
G36*
G01X1602960Y1484392D02*
G02Y1487398I0J1503D01*
G01X1606360D01*
G02Y1484392I0J-1503D01*
G01X1602960D01*
G37*
G36*
G01X1474898D02*
G02Y1487398I0J1503D01*
G01X1478298D01*
G02Y1484392I0J-1503D01*
G01X1474898D01*
G37*
G36*
G01X1556693Y1623878D02*
G02Y1626882I0J1502D01*
G01X1560093D01*
G02Y1623878I0J-1502D01*
G01X1556693D01*
G37*
G36*
G01Y1655790D02*
G02Y1658794I0J1502D01*
G01X1560093D01*
G02Y1655790I0J-1502D01*
G01X1556693D01*
G37*
G36*
G01X1496393D02*
G02Y1658794I0J1502D01*
G01X1499793D01*
G02Y1655790I0J-1502D01*
G01X1496393D01*
G37*
G36*
G01X1508453D02*
G02Y1658794I0J1502D01*
G01X1511853D01*
G02Y1655790I0J-1502D01*
G01X1508453D01*
G37*
G36*
G01X1532573Y1623878D02*
G02Y1626882I0J1502D01*
G01X1535973D01*
G02Y1623878I0J-1502D01*
G01X1532573D01*
G37*
G36*
G01X1520513Y1655790D02*
G02Y1658794I0J1502D01*
G01X1523913D01*
G02Y1655790I0J-1502D01*
G01X1520513D01*
G37*
G36*
G01X1532573D02*
G02Y1658794I0J1502D01*
G01X1535973D01*
G02Y1655790I0J-1502D01*
G01X1532573D01*
G37*
G36*
G01X1544633D02*
G02Y1658794I0J1502D01*
G01X1548033D01*
G02Y1655790I0J-1502D01*
G01X1544633D01*
G37*
G36*
G01X1484333D02*
G02Y1658794I0J1502D01*
G01X1487733D01*
G02Y1655790I0J-1502D01*
G01X1484333D01*
G37*
G36*
G01X1262369Y1645790D02*
G02Y1648794I0J1502D01*
G01X1265769D01*
G02Y1645790I0J-1502D01*
G01X1262369D01*
G37*
G36*
G01Y1633878D02*
G02Y1636882I0J1502D01*
G01X1265769D01*
G02Y1633878I0J-1502D01*
G01X1262369D01*
G37*
G36*
G01X1274429D02*
G02Y1636882I0J1502D01*
G01X1277829D01*
G02Y1633878I0J-1502D01*
G01X1274429D01*
G37*
G36*
G01X1214129Y1645790D02*
G02Y1648794I0J1502D01*
G01X1217529D01*
G02Y1645790I0J-1502D01*
G01X1214129D01*
G37*
G36*
G01X1238249D02*
G02Y1648794I0J1502D01*
G01X1241649D01*
G02Y1645790I0J-1502D01*
G01X1238249D01*
G37*
G36*
G01X1250309D02*
G02Y1648794I0J1502D01*
G01X1253709D01*
G02Y1645790I0J-1502D01*
G01X1250309D01*
G37*
G36*
G01X1364879Y1655790D02*
G02Y1658794I0J1502D01*
G01X1368279D01*
G02Y1655790I0J-1502D01*
G01X1364879D01*
G37*
G36*
G01X354527Y1520264D02*
G02X355587Y1520900I1060J-565D01*
G02X356790Y1519698I1J-1202D01*
G02X356629Y1519098I-1204J1D01*
G01X355084Y1516425D01*
X355082Y1516421D01*
G02X354012Y1515768I-1070J550D01*
G02X352810Y1516970I0J1202D01*
G01Y1516972D01*
G02X352959Y1517551I1202J-1D01*
G01X354525Y1520261D01*
X354527Y1520264D01*
G37*
G36*
G01X482380Y140440D02*
G02Y143444I0J1502D01*
G01X485780D01*
G02Y140440I0J-1502D01*
G01X482380D01*
G37*
G36*
G01X537148Y89555D02*
G02X539273Y91680I1062J1062D01*
G01X541678Y89276D01*
G02X542118Y88214I-1063J-1063D01*
G01Y88213D01*
G02X540615Y86710I-1503J0D01*
G01X540614D01*
G02X539552Y87150I1J1503D01*
G01X537148Y89555D01*
G37*
G36*
G01X472895Y128518D02*
G02Y131522I0J1502D01*
G01X476295D01*
G02Y128518I0J-1502D01*
G01X472895D01*
G37*
G36*
G01X445014Y93182D02*
G02Y96186I0J1502D01*
G01X448414D01*
G02Y93182I0J-1502D01*
G01X445014D01*
G37*
G36*
G01X514240Y95644D02*
G02Y98648I0J1502D01*
G01X517640D01*
G02Y95644I0J-1502D01*
G01X514240D01*
G37*
G36*
G01X552105Y110700D02*
G02Y113706I0J1503D01*
G01X555505D01*
G02Y110700I0J-1503D01*
G01X552105D01*
G37*
G36*
G01X330905Y1520264D02*
G02X331965Y1520900I1060J-565D01*
G02X333168Y1519698I1J-1202D01*
G02X333007Y1519098I-1204J1D01*
G01X331462Y1516425D01*
X331460Y1516421D01*
G02X330390Y1515768I-1070J550D01*
G02X329188Y1516970I0J1202D01*
G01Y1516972D01*
G02X329337Y1517551I1202J-1D01*
G01X330903Y1520261D01*
X330905Y1520264D01*
G37*
G36*
G01X452102Y87208D02*
G02Y90214I0J1503D01*
G01X455502D01*
G02Y87208I0J-1503D01*
G01X452102D01*
G37*
G36*
G01X321456Y1520264D02*
G02X322516Y1520900I1060J-565D01*
G02X323718Y1519698I0J-1202D01*
G02X323558Y1519098I-1203J0D01*
G01X322013Y1516425D01*
X322011Y1516421D01*
G02X320941Y1515768I-1070J550D01*
G02X319738Y1516970I-1J1202D01*
G01Y1516972D01*
G02X319888Y1517551I1203J-3D01*
G01X321454Y1520261D01*
X321456Y1520264D01*
G37*
G36*
G01X316732D02*
G02X317792Y1520900I1060J-565D01*
G02X318994Y1519698I0J-1202D01*
G02X318834Y1519098I-1203J0D01*
G01X317289Y1516425D01*
X317287Y1516421D01*
G02X316217Y1515768I-1070J550D01*
G02X315014Y1516970I-1J1202D01*
G01Y1516972D01*
G02X315164Y1517551I1203J-3D01*
G01X316730Y1520261D01*
X316732Y1520264D01*
G37*
G36*
G01X459056Y93598D02*
G02Y96604I0J1503D01*
G01X462456D01*
G02Y93598I0J-1503D01*
G01X459056D01*
G37*
G36*
G01X363976Y1520264D02*
G02X365036Y1520900I1060J-565D01*
G02X366238Y1519698I0J-1202D01*
G02X366078Y1519098I-1203J0D01*
G01X364533Y1516425D01*
X364531Y1516421D01*
G02X363461Y1515768I-1070J550D01*
G02X362258Y1516970I-1J1202D01*
G01Y1516972D01*
G02X362408Y1517551I1203J-3D01*
G01X363974Y1520261D01*
X363976Y1520264D01*
G37*
G36*
G01X490380Y129940D02*
G02Y132944I0J1502D01*
G01X493780D01*
G02Y129940I0J-1502D01*
G01X490380D01*
G37*
G36*
G01X349802Y1520264D02*
G02X350862Y1520900I1060J-565D01*
G02X352064Y1519698I0J-1202D01*
G02X351904Y1519098I-1203J0D01*
G01X350359Y1516425D01*
X350357Y1516421D01*
G02X349287Y1515768I-1070J550D01*
G02X348084Y1516970I-1J1202D01*
G01Y1516972D01*
G02X348234Y1517551I1203J-3D01*
G01X349800Y1520261D01*
X349802Y1520264D01*
G37*
G36*
G01X533918Y45564D02*
G02Y48570I0J1503D01*
G01X537318D01*
G02Y45564I0J-1503D01*
G01X533918D01*
G37*
G36*
G01X1549274Y24974D02*
G02Y27980I0J1503D01*
G01X1552674D01*
G02Y24974I0J-1503D01*
G01X1549274D01*
G37*
G36*
G01X1685967D02*
G02Y27980I0J1503D01*
G01X1689367D01*
G02Y24974I0J-1503D01*
G01X1685967D01*
G37*
G36*
G01X1612566Y73838D02*
G02Y76842I0J1502D01*
G01X1615966D01*
G02Y73838I0J-1502D01*
G01X1612566D01*
G37*
G36*
G01X1623562Y67840D02*
G02Y70846I0J1503D01*
G01X1626962D01*
G02Y67840I0J-1503D01*
G01X1623562D01*
G37*
G36*
G01X1563447Y24974D02*
G02Y27980I0J1503D01*
G01X1566847D01*
G02Y24974I0J-1503D01*
G01X1563447D01*
G37*
G36*
G01X1627660D02*
G02Y27980I0J1503D01*
G01X1631060D01*
G02Y24974I0J-1503D01*
G01X1627660D01*
G37*
G36*
G01X1598899Y18038D02*
G02Y21044I0J1503D01*
G01X1602299D01*
G02Y18038I0J-1503D01*
G01X1598899D01*
G37*
G36*
G01X1570552D02*
G02Y21044I0J1503D01*
G01X1573952D01*
G02Y18038I0J-1503D01*
G01X1570552D01*
G37*
G36*
G01X1591794Y24974D02*
G02Y27980I0J1503D01*
G01X1595194D01*
G02Y24974I0J-1503D01*
G01X1591794D01*
G37*
G36*
G01X1648938Y18038D02*
G02Y21044I0J1503D01*
G01X1652338D01*
G02Y18038I0J-1503D01*
G01X1648938D01*
G37*
G36*
G01X1601562Y67840D02*
G02Y70846I0J1503D01*
G01X1604962D01*
G02Y67840I0J-1503D01*
G01X1601562D01*
G37*
G36*
G01X1701904Y73838D02*
G02Y76842I0J1502D01*
G01X1705304D01*
G02Y73838I0J-1502D01*
G01X1701904D01*
G37*
G36*
G01X1679904D02*
G02Y76842I0J1502D01*
G01X1683304D01*
G02Y73838I0J-1502D01*
G01X1679904D01*
G37*
G36*
G01X1668770Y67838D02*
G02Y70842I0J1502D01*
G01X1672170D01*
G02Y67838I0J-1502D01*
G01X1668770D01*
G37*
G36*
G01X1657766Y73840D02*
G02Y76846I0J1503D01*
G01X1661166D01*
G02Y73840I0J-1503D01*
G01X1657766D01*
G37*
G36*
G01X1646770Y67838D02*
G02Y70842I0J1502D01*
G01X1650170D01*
G02Y67838I0J-1502D01*
G01X1646770D01*
G37*
G36*
G01X1635770Y73838D02*
G02Y76842I0J1502D01*
G01X1639170D01*
G02Y73838I0J-1502D01*
G01X1635770D01*
G37*
G36*
G01X1584725Y18038D02*
G02Y21044I0J1503D01*
G01X1588125D01*
G02Y18038I0J-1503D01*
G01X1584725D01*
G37*
G36*
G01X1671794Y24974D02*
G02Y27980I0J1503D01*
G01X1675194D01*
G02Y24974I0J-1503D01*
G01X1671794D01*
G37*
G36*
G01X1590566Y73838D02*
G02Y76842I0J1502D01*
G01X1593966D01*
G02Y73838I0J-1502D01*
G01X1590566D01*
G37*
G36*
G01X1546562Y73840D02*
G02Y76846I0J1503D01*
G01X1549962D01*
G02Y73840I0J-1503D01*
G01X1546562D01*
G37*
G36*
G01X1579566Y67838D02*
G02Y70842I0J1502D01*
G01X1582966D01*
G02Y67838I0J-1502D01*
G01X1579566D01*
G37*
G36*
G01X1557566D02*
G02Y70842I0J1502D01*
G01X1560966D01*
G02Y67838I0J-1502D01*
G01X1557566D01*
G37*
G36*
G01X1535566D02*
G02Y70842I0J1502D01*
G01X1538966D01*
G02Y67838I0J-1502D01*
G01X1535566D01*
G37*
G36*
G01X1568566Y73838D02*
G02Y76842I0J1502D01*
G01X1571966D01*
G02Y73838I0J-1502D01*
G01X1568566D01*
G37*
G36*
G01X218663Y18038D02*
G02Y21044I0J1503D01*
G01X222063D01*
G02Y18038I0J-1503D01*
G01X218663D01*
G37*
G36*
G01X211558Y24974D02*
G02Y27980I0J1503D01*
G01X214958D01*
G02Y24974I0J-1503D01*
G01X211558D01*
G37*
G36*
G01X204490Y18038D02*
G02Y21044I0J1503D01*
G01X207890D01*
G02Y18038I0J-1503D01*
G01X204490D01*
G37*
G36*
G01X197385Y24974D02*
G02Y27980I0J1503D01*
G01X200785D01*
G02Y24974I0J-1503D01*
G01X197385D01*
G37*
G36*
G01X174529Y18038D02*
G02Y21044I0J1503D01*
G01X177929D01*
G02Y18038I0J-1503D01*
G01X174529D01*
G37*
G36*
G01X160356D02*
G02Y21044I0J1503D01*
G01X163756D01*
G02Y18038I0J-1503D01*
G01X160356D01*
G37*
G36*
G01X167424Y24974D02*
G02Y27980I0J1503D01*
G01X170824D01*
G02Y24974I0J-1503D01*
G01X167424D01*
G37*
G36*
G01X153251D02*
G02Y27980I0J1503D01*
G01X156651D01*
G02Y24974I0J-1503D01*
G01X153251D01*
G37*
G36*
G01X124490Y18038D02*
G02Y21044I0J1503D01*
G01X127890D01*
G02Y18038I0J-1503D01*
G01X124490D01*
G37*
G36*
G01X117385Y24974D02*
G02Y27980I0J1503D01*
G01X120785D01*
G02Y24974I0J-1503D01*
G01X117385D01*
G37*
G36*
G01X110316Y18038D02*
G02Y21044I0J1503D01*
G01X113716D01*
G02Y18038I0J-1503D01*
G01X110316D01*
G37*
G36*
G01X103211Y24974D02*
G02Y27980I0J1503D01*
G01X106611D01*
G02Y24974I0J-1503D01*
G01X103211D01*
G37*
G36*
G01X96143Y18038D02*
G02Y21044I0J1503D01*
G01X99543D01*
G02Y18038I0J-1503D01*
G01X96143D01*
G37*
G36*
G01X89038Y24974D02*
G02Y27980I0J1503D01*
G01X92438D01*
G02Y24974I0J-1503D01*
G01X89038D01*
G37*
G36*
G01X74865D02*
G02Y27980I0J1503D01*
G01X78265D01*
G02Y24974I0J-1503D01*
G01X74865D01*
G37*
G36*
G01X81970Y18038D02*
G02Y21044I0J1503D01*
G01X85370D01*
G02Y18038I0J-1503D01*
G01X81970D01*
G37*
G36*
G01X227495Y73838D02*
G02Y76842I0J1502D01*
G01X230895D01*
G02Y73838I0J-1502D01*
G01X227495D01*
G37*
G36*
G01X216491Y67840D02*
G02Y70846I0J1503D01*
G01X219891D01*
G02Y67840I0J-1503D01*
G01X216491D01*
G37*
G36*
G01X205495Y73838D02*
G02Y76842I0J1502D01*
G01X208895D01*
G02Y73838I0J-1502D01*
G01X205495D01*
G37*
G36*
G01X194361Y67838D02*
G02Y70842I0J1502D01*
G01X197761D01*
G02Y67838I0J-1502D01*
G01X194361D01*
G37*
G36*
G01X172361D02*
G02Y70842I0J1502D01*
G01X175761D01*
G02Y67838I0J-1502D01*
G01X172361D01*
G37*
G36*
G01X183357Y73840D02*
G02Y76846I0J1503D01*
G01X186757D01*
G02Y73840I0J-1503D01*
G01X183357D01*
G37*
G36*
G01X161361Y73838D02*
G02Y76842I0J1502D01*
G01X164761D01*
G02Y73838I0J-1502D01*
G01X161361D01*
G37*
G36*
G01X149153Y67840D02*
G02Y70846I0J1503D01*
G01X152553D01*
G02Y67840I0J-1503D01*
G01X149153D01*
G37*
G36*
G01X138157Y73838D02*
G02Y76842I0J1502D01*
G01X141557D01*
G02Y73838I0J-1502D01*
G01X138157D01*
G37*
G36*
G01X127153Y67840D02*
G02Y70846I0J1503D01*
G01X130553D01*
G02Y67840I0J-1503D01*
G01X127153D01*
G37*
G36*
G01X116157Y73838D02*
G02Y76842I0J1502D01*
G01X119557D01*
G02Y73838I0J-1502D01*
G01X116157D01*
G37*
G36*
G01X105157Y67838D02*
G02Y70842I0J1502D01*
G01X108557D01*
G02Y67838I0J-1502D01*
G01X105157D01*
G37*
G36*
G01X83157D02*
G02Y70842I0J1502D01*
G01X86557D01*
G02Y67838I0J-1502D01*
G01X83157D01*
G37*
G36*
G01X94157Y73838D02*
G02Y76842I0J1502D01*
G01X97557D01*
G02Y73838I0J-1502D01*
G01X94157D01*
G37*
G36*
G01X72153Y73840D02*
G02Y76846I0J1503D01*
G01X75553D01*
G02Y73840I0J-1503D01*
G01X72153D01*
G37*
G36*
G01X61157Y67838D02*
G02Y70842I0J1502D01*
G01X64557D01*
G02Y67838I0J-1502D01*
G01X61157D01*
G37*
G36*
G01X1690900Y67840D02*
G02Y70846I0J1503D01*
G01X1694300D01*
G02Y67840I0J-1503D01*
G01X1690900D01*
G37*
G36*
G01X1693072Y18038D02*
G02Y21044I0J1503D01*
G01X1696472D01*
G02Y18038I0J-1503D01*
G01X1693072D01*
G37*
G36*
G01X1641833Y24974D02*
G02Y27980I0J1503D01*
G01X1645233D01*
G02Y24974I0J-1503D01*
G01X1641833D01*
G37*
G36*
G01X1634765Y18038D02*
G02Y21044I0J1503D01*
G01X1638165D01*
G02Y18038I0J-1503D01*
G01X1634765D01*
G37*
G36*
G01X1678899D02*
G02Y21044I0J1503D01*
G01X1682299D01*
G02Y18038I0J-1503D01*
G01X1678899D01*
G37*
G36*
G01X1577620Y24974D02*
G02Y27980I0J1503D01*
G01X1581020D01*
G02Y24974I0J-1503D01*
G01X1577620D01*
G37*
G36*
G01X1556379Y18038D02*
G02Y21044I0J1503D01*
G01X1559779D01*
G02Y18038I0J-1503D01*
G01X1556379D01*
G37*
G36*
G01X373424Y1520264D02*
G02X374484Y1520900I1060J-565D01*
G02X375686Y1519698I0J-1202D01*
G02X375526Y1519098I-1203J0D01*
G01X373981Y1516425D01*
X373979Y1516421D01*
G02X372909Y1515768I-1070J550D01*
G02X371706Y1516970I-1J1202D01*
G01Y1516972D01*
G02X371856Y1517551I1203J-3D01*
G01X373422Y1520261D01*
X373424Y1520264D01*
G37*
G36*
G01X555176Y69934D02*
G02Y72938I0J1502D01*
G01X558576D01*
G02Y69934I0J-1502D01*
G01X555176D01*
G37*
G36*
G01X45812Y450100D02*
G02Y453104I0J1502D01*
G01X49212D01*
G02Y450100I0J-1502D01*
G01X45812D01*
G37*
G36*
G01X519765Y38826D02*
G02Y41830I0J1502D01*
G01X523165D01*
G02Y38826I0J-1502D01*
G01X519765D01*
G37*
G36*
G01X519743Y69934D02*
G02Y72938I0J1502D01*
G01X523143D01*
G02Y69934I0J-1502D01*
G01X519743D01*
G37*
G36*
G01X1311986Y1484392D02*
G02Y1487398I0J1503D01*
G01X1315386D01*
G02Y1484392I0J-1503D01*
G01X1311986D01*
G37*
G36*
G01X1358849Y1645790D02*
G02Y1648794I0J1502D01*
G01X1362249D01*
G02Y1645790I0J-1502D01*
G01X1358849D01*
G37*
G36*
G01X1334729Y1633878D02*
G02Y1636882I0J1502D01*
G01X1338129D01*
G02Y1633878I0J-1502D01*
G01X1334729D01*
G37*
G36*
G01X1298549Y1645790D02*
G02Y1648794I0J1502D01*
G01X1301949D01*
G02Y1645790I0J-1502D01*
G01X1298549D01*
G37*
G36*
G01X1472273Y1655790D02*
G02Y1658794I0J1502D01*
G01X1475673D01*
G02Y1655790I0J-1502D01*
G01X1472273D01*
G37*
G36*
G01X1604933D02*
G02Y1658794I0J1502D01*
G01X1608333D01*
G02Y1655790I0J-1502D01*
G01X1604933D01*
G37*
G36*
G01X1635083Y1633878D02*
G02Y1636882I0J1502D01*
G01X1638483D01*
G02Y1633878I0J-1502D01*
G01X1635083D01*
G37*
G36*
G01X1629053Y1655790D02*
G02Y1658794I0J1502D01*
G01X1632453D01*
G02Y1655790I0J-1502D01*
G01X1629053D01*
G37*
G36*
G01X1647143Y1645790D02*
G02Y1648794I0J1502D01*
G01X1650543D01*
G02Y1645790I0J-1502D01*
G01X1647143D01*
G37*
G36*
G01X1598903D02*
G02Y1648794I0J1502D01*
G01X1602303D01*
G02Y1645790I0J-1502D01*
G01X1598903D01*
G37*
G36*
G01X1574783D02*
G02Y1648794I0J1502D01*
G01X1578183D01*
G02Y1645790I0J-1502D01*
G01X1574783D01*
G37*
G36*
G01X1346789D02*
G02Y1648794I0J1502D01*
G01X1350189D01*
G02Y1645790I0J-1502D01*
G01X1346789D01*
G37*
G36*
G01X1641113Y1623878D02*
G02Y1626882I0J1502D01*
G01X1644513D01*
G02Y1623878I0J-1502D01*
G01X1641113D01*
G37*
G36*
G01X1607248Y1731340D02*
G02X1607551Y1731642I303J-1D01*
G01X1611251D01*
G02X1611554Y1731340I1J-302D01*
G01Y1721334D01*
G02X1611251Y1721032I-303J1D01*
G01X1607551D01*
G02X1607248Y1721334I-1J302D01*
G01Y1731340D01*
G37*
G36*
G01X1622996D02*
G02X1623299Y1731642I303J-1D01*
G01X1626999D01*
G02X1627302Y1731340I1J-302D01*
G01Y1721334D01*
G02X1626999Y1721032I-303J1D01*
G01X1623299D01*
G02X1622996Y1721334I-1J302D01*
G01Y1731340D01*
G37*
G36*
G01X1599374Y1727403D02*
G02X1599677Y1727706I303J0D01*
G01X1603377D01*
G02X1603680Y1727403I0J-303D01*
G01Y1717397D01*
G02X1603377Y1717094I-303J0D01*
G01X1599677D01*
G02X1599374Y1717397I0J303D01*
G01Y1727403D01*
G37*
G36*
G01X1615122D02*
G02X1615425Y1727706I303J0D01*
G01X1619125D01*
G02X1619428Y1727403I0J-303D01*
G01Y1717397D01*
G02X1619125Y1717094I-303J0D01*
G01X1615425D01*
G02X1615122Y1717397I0J303D01*
G01Y1727403D01*
G37*
G36*
G01X1607248Y1717167D02*
G02X1607551Y1717470I303J0D01*
G01X1611251D01*
G02X1611554Y1717167I0J-303D01*
G01Y1707161D01*
G02X1611251Y1706858I-303J0D01*
G01X1607551D01*
G02X1607248Y1707161I0J303D01*
G01Y1717167D01*
G37*
G36*
G01X1622996D02*
G02X1623299Y1717470I303J0D01*
G01X1626999D01*
G02X1627302Y1717167I0J-303D01*
G01Y1707161D01*
G02X1626999Y1706858I-303J0D01*
G01X1623299D01*
G02X1622996Y1707161I0J303D01*
G01Y1717167D01*
G37*
G36*
G01X1599374Y1713230D02*
G02X1599677Y1713532I303J-1D01*
G01X1603377D01*
G02X1603680Y1713230I1J-302D01*
G01Y1703224D01*
G02X1603377Y1702922I-303J1D01*
G01X1599677D01*
G02X1599374Y1703224I-1J302D01*
G01Y1713230D01*
G37*
G36*
G01X1615122D02*
G02X1615425Y1713532I303J-1D01*
G01X1619125D01*
G02X1619428Y1713230I1J-302D01*
G01Y1703224D01*
G02X1619125Y1702922I-303J1D01*
G01X1615425D01*
G02X1615122Y1703224I-1J302D01*
G01Y1713230D01*
G37*
G36*
G01X1607248Y1702994D02*
G02X1607551Y1703296I303J-1D01*
G01X1611251D01*
G02X1611554Y1702994I1J-302D01*
G01Y1692988D01*
G02X1611251Y1692686I-303J1D01*
G01X1607551D01*
G02X1607248Y1692988I-1J302D01*
G01Y1702994D01*
G37*
G36*
G01X1622996D02*
G02X1623299Y1703296I303J-1D01*
G01X1626999D01*
G02X1627302Y1702994I1J-302D01*
G01Y1692988D01*
G02X1626999Y1692686I-303J1D01*
G01X1623299D01*
G02X1622996Y1692988I-1J302D01*
G01Y1702994D01*
G37*
G36*
G01X1599374Y1699057D02*
G02X1599677Y1699360I303J0D01*
G01X1603377D01*
G02X1603680Y1699057I0J-303D01*
G01Y1689051D01*
G02X1603377Y1688748I-303J0D01*
G01X1599677D01*
G02X1599374Y1689051I0J303D01*
G01Y1699057D01*
G37*
G36*
G01X1615122D02*
G02X1615425Y1699360I303J0D01*
G01X1619125D01*
G02X1619428Y1699057I0J-303D01*
G01Y1689051D01*
G02X1619125Y1688748I-303J0D01*
G01X1615425D01*
G02X1615122Y1689051I0J303D01*
G01Y1699057D01*
G37*
G36*
G01X1607248Y1688821D02*
G02X1607551Y1689124I303J0D01*
G01X1611251D01*
G02X1611554Y1688821I0J-303D01*
G01Y1678815D01*
G02X1611251Y1678512I-303J0D01*
G01X1607551D01*
G02X1607248Y1678815I0J303D01*
G01Y1688821D01*
G37*
G36*
G01X1622996D02*
G02X1623299Y1689124I303J0D01*
G01X1626999D01*
G02X1627302Y1688821I0J-303D01*
G01Y1678815D01*
G02X1626999Y1678512I-303J0D01*
G01X1623299D01*
G02X1622996Y1678815I0J303D01*
G01Y1688821D01*
G37*
G36*
G01X1599374Y1684884D02*
G02X1599677Y1685186I303J-1D01*
G01X1603377D01*
G02X1603680Y1684884I1J-302D01*
G01Y1674878D01*
G02X1603377Y1674576I-303J1D01*
G01X1599677D01*
G02X1599374Y1674878I-1J302D01*
G01Y1684884D01*
G37*
G36*
G01X1615122D02*
G02X1615425Y1685186I303J-1D01*
G01X1619125D01*
G02X1619428Y1684884I1J-302D01*
G01Y1674878D01*
G02X1619125Y1674576I-303J1D01*
G01X1615425D01*
G02X1615122Y1674878I-1J302D01*
G01Y1684884D01*
G37*
G36*
G01X1575752Y1731340D02*
G02X1576055Y1731642I303J-1D01*
G01X1579755D01*
G02X1580058Y1731340I1J-302D01*
G01Y1721334D01*
G02X1579755Y1721032I-303J1D01*
G01X1576055D01*
G02X1575752Y1721334I-1J302D01*
G01Y1731340D01*
G37*
G36*
G01X1591500D02*
G02X1591803Y1731642I303J-1D01*
G01X1595503D01*
G02X1595806Y1731340I1J-302D01*
G01Y1721334D01*
G02X1595503Y1721032I-303J1D01*
G01X1591803D01*
G02X1591500Y1721334I-1J302D01*
G01Y1731340D01*
G37*
G36*
G01X1567878Y1727403D02*
G02X1568181Y1727706I303J0D01*
G01X1571881D01*
G02X1572184Y1727403I0J-303D01*
G01Y1717397D01*
G02X1571881Y1717094I-303J0D01*
G01X1568181D01*
G02X1567878Y1717397I0J303D01*
G01Y1727403D01*
G37*
G36*
G01X1583626D02*
G02X1583929Y1727706I303J0D01*
G01X1587629D01*
G02X1587932Y1727403I0J-303D01*
G01Y1717397D01*
G02X1587629Y1717094I-303J0D01*
G01X1583929D01*
G02X1583626Y1717397I0J303D01*
G01Y1727403D01*
G37*
G36*
G01X1575752Y1717167D02*
G02X1576055Y1717470I303J0D01*
G01X1579755D01*
G02X1580058Y1717167I0J-303D01*
G01Y1707161D01*
G02X1579755Y1706858I-303J0D01*
G01X1576055D01*
G02X1575752Y1707161I0J303D01*
G01Y1717167D01*
G37*
G36*
G01X1591500D02*
G02X1591803Y1717470I303J0D01*
G01X1595503D01*
G02X1595806Y1717167I0J-303D01*
G01Y1707161D01*
G02X1595503Y1706858I-303J0D01*
G01X1591803D01*
G02X1591500Y1707161I0J303D01*
G01Y1717167D01*
G37*
G36*
G01X1567878Y1713230D02*
G02X1568181Y1713532I303J-1D01*
G01X1571881D01*
G02X1572184Y1713230I1J-302D01*
G01Y1703224D01*
G02X1571881Y1702922I-303J1D01*
G01X1568181D01*
G02X1567878Y1703224I-1J302D01*
G01Y1713230D01*
G37*
G36*
G01X1583626D02*
G02X1583929Y1713532I303J-1D01*
G01X1587629D01*
G02X1587932Y1713230I1J-302D01*
G01Y1703224D01*
G02X1587629Y1702922I-303J1D01*
G01X1583929D01*
G02X1583626Y1703224I-1J302D01*
G01Y1713230D01*
G37*
G36*
G01X1575752Y1702994D02*
G02X1576055Y1703296I303J-1D01*
G01X1579755D01*
G02X1580058Y1702994I1J-302D01*
G01Y1692988D01*
G02X1579755Y1692686I-303J1D01*
G01X1576055D01*
G02X1575752Y1692988I-1J302D01*
G01Y1702994D01*
G37*
G36*
G01X1591500D02*
G02X1591803Y1703296I303J-1D01*
G01X1595503D01*
G02X1595806Y1702994I1J-302D01*
G01Y1692988D01*
G02X1595503Y1692686I-303J1D01*
G01X1591803D01*
G02X1591500Y1692988I-1J302D01*
G01Y1702994D01*
G37*
G36*
G01X1567878Y1699057D02*
G02X1568181Y1699360I303J0D01*
G01X1571881D01*
G02X1572184Y1699057I0J-303D01*
G01Y1689051D01*
G02X1571881Y1688748I-303J0D01*
G01X1568181D01*
G02X1567878Y1689051I0J303D01*
G01Y1699057D01*
G37*
G36*
G01X1583626D02*
G02X1583929Y1699360I303J0D01*
G01X1587629D01*
G02X1587932Y1699057I0J-303D01*
G01Y1689051D01*
G02X1587629Y1688748I-303J0D01*
G01X1583929D01*
G02X1583626Y1689051I0J303D01*
G01Y1699057D01*
G37*
G36*
G01X1575752Y1688821D02*
G02X1576055Y1689124I303J0D01*
G01X1579755D01*
G02X1580058Y1688821I0J-303D01*
G01Y1678815D01*
G02X1579755Y1678512I-303J0D01*
G01X1576055D01*
G02X1575752Y1678815I0J303D01*
G01Y1688821D01*
G37*
G36*
G01X1591500D02*
G02X1591803Y1689124I303J0D01*
G01X1595503D01*
G02X1595806Y1688821I0J-303D01*
G01Y1678815D01*
G02X1595503Y1678512I-303J0D01*
G01X1591803D01*
G02X1591500Y1678815I0J303D01*
G01Y1688821D01*
G37*
G36*
G01X1567878Y1684884D02*
G02X1568181Y1685186I303J-1D01*
G01X1571881D01*
G02X1572184Y1684884I1J-302D01*
G01Y1674878D01*
G02X1571881Y1674576I-303J1D01*
G01X1568181D01*
G02X1567878Y1674878I-1J302D01*
G01Y1684884D01*
G37*
G36*
G01X1583626D02*
G02X1583929Y1685186I303J-1D01*
G01X1587629D01*
G02X1587932Y1684884I1J-302D01*
G01Y1674878D01*
G02X1587629Y1674576I-303J1D01*
G01X1583929D01*
G02X1583626Y1674878I-1J302D01*
G01Y1684884D01*
G37*
G36*
G01X1540320Y1731340D02*
G02X1540622Y1731642I302J0D01*
G01X1544322D01*
G02X1544624Y1731340I0J-302D01*
G01Y1721334D01*
G02X1544322Y1721032I-302J0D01*
G01X1540622D01*
G02X1540320Y1721334I0J302D01*
G01Y1731340D01*
G37*
G36*
G01X1556068D02*
G02X1556370Y1731642I302J0D01*
G01X1560070D01*
G02X1560372Y1731340I0J-302D01*
G01Y1721334D01*
G02X1560070Y1721032I-302J0D01*
G01X1556370D01*
G02X1556068Y1721334I0J302D01*
G01Y1731340D01*
G37*
G36*
G01X1532446Y1727403D02*
G02X1532748Y1727706I302J1D01*
G01X1536448D01*
G02X1536750Y1727403I-1J-303D01*
G01Y1717397D01*
G02X1536448Y1717094I-302J-1D01*
G01X1532748D01*
G02X1532446Y1717397I1J303D01*
G01Y1727403D01*
G37*
G36*
G01X1548194D02*
G02X1548496Y1727706I302J1D01*
G01X1552196D01*
G02X1552498Y1727403I-1J-303D01*
G01Y1717397D01*
G02X1552196Y1717094I-302J-1D01*
G01X1548496D01*
G02X1548194Y1717397I1J303D01*
G01Y1727403D01*
G37*
G36*
G01X1540320Y1717167D02*
G02X1540622Y1717470I302J1D01*
G01X1544322D01*
G02X1544624Y1717167I-1J-303D01*
G01Y1707161D01*
G02X1544322Y1706858I-302J-1D01*
G01X1540622D01*
G02X1540320Y1707161I1J303D01*
G01Y1717167D01*
G37*
G36*
G01X1556068D02*
G02X1556370Y1717470I302J1D01*
G01X1560070D01*
G02X1560372Y1717167I-1J-303D01*
G01Y1707161D01*
G02X1560070Y1706858I-302J-1D01*
G01X1556370D01*
G02X1556068Y1707161I1J303D01*
G01Y1717167D01*
G37*
G36*
G01X1532446Y1713230D02*
G02X1532748Y1713532I302J0D01*
G01X1536448D01*
G02X1536750Y1713230I0J-302D01*
G01Y1703224D01*
G02X1536448Y1702922I-302J0D01*
G01X1532748D01*
G02X1532446Y1703224I0J302D01*
G01Y1713230D01*
G37*
G36*
G01X1548194D02*
G02X1548496Y1713532I302J0D01*
G01X1552196D01*
G02X1552498Y1713230I0J-302D01*
G01Y1703224D01*
G02X1552196Y1702922I-302J0D01*
G01X1548496D01*
G02X1548194Y1703224I0J302D01*
G01Y1713230D01*
G37*
G36*
G01X1540320Y1702994D02*
G02X1540622Y1703296I302J0D01*
G01X1544322D01*
G02X1544624Y1702994I0J-302D01*
G01Y1692988D01*
G02X1544322Y1692686I-302J0D01*
G01X1540622D01*
G02X1540320Y1692988I0J302D01*
G01Y1702994D01*
G37*
G36*
G01X1556068D02*
G02X1556370Y1703296I302J0D01*
G01X1560070D01*
G02X1560372Y1702994I0J-302D01*
G01Y1692988D01*
G02X1560070Y1692686I-302J0D01*
G01X1556370D01*
G02X1556068Y1692988I0J302D01*
G01Y1702994D01*
G37*
G36*
G01X1532446Y1699057D02*
G02X1532748Y1699360I302J1D01*
G01X1536448D01*
G02X1536750Y1699057I-1J-303D01*
G01Y1689051D01*
G02X1536448Y1688748I-302J-1D01*
G01X1532748D01*
G02X1532446Y1689051I1J303D01*
G01Y1699057D01*
G37*
G36*
G01X1548194D02*
G02X1548496Y1699360I302J1D01*
G01X1552196D01*
G02X1552498Y1699057I-1J-303D01*
G01Y1689051D01*
G02X1552196Y1688748I-302J-1D01*
G01X1548496D01*
G02X1548194Y1689051I1J303D01*
G01Y1699057D01*
G37*
G36*
G01X1540320Y1688821D02*
G02X1540622Y1689124I302J1D01*
G01X1544322D01*
G02X1544624Y1688821I-1J-303D01*
G01Y1678815D01*
G02X1544322Y1678512I-302J-1D01*
G01X1540622D01*
G02X1540320Y1678815I1J303D01*
G01Y1688821D01*
G37*
G36*
G01X1556068D02*
G02X1556370Y1689124I302J1D01*
G01X1560070D01*
G02X1560372Y1688821I-1J-303D01*
G01Y1678815D01*
G02X1560070Y1678512I-302J-1D01*
G01X1556370D01*
G02X1556068Y1678815I1J303D01*
G01Y1688821D01*
G37*
G36*
G01X1532446Y1684884D02*
G02X1532748Y1685186I302J0D01*
G01X1536448D01*
G02X1536750Y1684884I0J-302D01*
G01Y1674878D01*
G02X1536448Y1674576I-302J0D01*
G01X1532748D01*
G02X1532446Y1674878I0J302D01*
G01Y1684884D01*
G37*
G36*
G01X1548194D02*
G02X1548496Y1685186I302J0D01*
G01X1552196D01*
G02X1552498Y1684884I0J-302D01*
G01Y1674878D01*
G02X1552196Y1674576I-302J0D01*
G01X1548496D01*
G02X1548194Y1674878I0J302D01*
G01Y1684884D01*
G37*
G36*
G01X1508824Y1731340D02*
G02X1509126Y1731642I302J0D01*
G01X1512826D01*
G02X1513128Y1731340I0J-302D01*
G01Y1721334D01*
G02X1512826Y1721032I-302J0D01*
G01X1509126D01*
G02X1508824Y1721334I0J302D01*
G01Y1731340D01*
G37*
G36*
G01X1524572D02*
G02X1524874Y1731642I302J0D01*
G01X1528574D01*
G02X1528876Y1731340I0J-302D01*
G01Y1721334D01*
G02X1528574Y1721032I-302J0D01*
G01X1524874D01*
G02X1524572Y1721334I0J302D01*
G01Y1731340D01*
G37*
G36*
G01X1500950Y1727403D02*
G02X1501252Y1727706I302J1D01*
G01X1504952D01*
G02X1505254Y1727403I-1J-303D01*
G01Y1717397D01*
G02X1504952Y1717094I-302J-1D01*
G01X1501252D01*
G02X1500950Y1717397I1J303D01*
G01Y1727403D01*
G37*
G36*
G01X1516698D02*
G02X1517000Y1727706I302J1D01*
G01X1520700D01*
G02X1521002Y1727403I-1J-303D01*
G01Y1717397D01*
G02X1520700Y1717094I-302J-1D01*
G01X1517000D01*
G02X1516698Y1717397I1J303D01*
G01Y1727403D01*
G37*
G36*
G01X1508824Y1717167D02*
G02X1509126Y1717470I302J1D01*
G01X1512826D01*
G02X1513128Y1717167I-1J-303D01*
G01Y1707161D01*
G02X1512826Y1706858I-302J-1D01*
G01X1509126D01*
G02X1508824Y1707161I1J303D01*
G01Y1717167D01*
G37*
G36*
G01X1524572D02*
G02X1524874Y1717470I302J1D01*
G01X1528574D01*
G02X1528876Y1717167I-1J-303D01*
G01Y1707161D01*
G02X1528574Y1706858I-302J-1D01*
G01X1524874D01*
G02X1524572Y1707161I1J303D01*
G01Y1717167D01*
G37*
G36*
G01X1500950Y1713230D02*
G02X1501252Y1713532I302J0D01*
G01X1504952D01*
G02X1505254Y1713230I0J-302D01*
G01Y1703224D01*
G02X1504952Y1702922I-302J0D01*
G01X1501252D01*
G02X1500950Y1703224I0J302D01*
G01Y1713230D01*
G37*
G36*
G01X1516698D02*
G02X1517000Y1713532I302J0D01*
G01X1520700D01*
G02X1521002Y1713230I0J-302D01*
G01Y1703224D01*
G02X1520700Y1702922I-302J0D01*
G01X1517000D01*
G02X1516698Y1703224I0J302D01*
G01Y1713230D01*
G37*
G36*
G01X1508824Y1702994D02*
G02X1509126Y1703296I302J0D01*
G01X1512826D01*
G02X1513128Y1702994I0J-302D01*
G01Y1692988D01*
G02X1512826Y1692686I-302J0D01*
G01X1509126D01*
G02X1508824Y1692988I0J302D01*
G01Y1702994D01*
G37*
G36*
G01X1524572D02*
G02X1524874Y1703296I302J0D01*
G01X1528574D01*
G02X1528876Y1702994I0J-302D01*
G01Y1692988D01*
G02X1528574Y1692686I-302J0D01*
G01X1524874D01*
G02X1524572Y1692988I0J302D01*
G01Y1702994D01*
G37*
G36*
G01X1500950Y1699057D02*
G02X1501252Y1699360I302J1D01*
G01X1504952D01*
G02X1505254Y1699057I-1J-303D01*
G01Y1689051D01*
G02X1504952Y1688748I-302J-1D01*
G01X1501252D01*
G02X1500950Y1689051I1J303D01*
G01Y1699057D01*
G37*
G36*
G01X1516698D02*
G02X1517000Y1699360I302J1D01*
G01X1520700D01*
G02X1521002Y1699057I-1J-303D01*
G01Y1689051D01*
G02X1520700Y1688748I-302J-1D01*
G01X1517000D01*
G02X1516698Y1689051I1J303D01*
G01Y1699057D01*
G37*
G36*
G01X1508824Y1688821D02*
G02X1509126Y1689124I302J1D01*
G01X1512826D01*
G02X1513128Y1688821I-1J-303D01*
G01Y1678815D01*
G02X1512826Y1678512I-302J-1D01*
G01X1509126D01*
G02X1508824Y1678815I1J303D01*
G01Y1688821D01*
G37*
G36*
G01X1524572D02*
G02X1524874Y1689124I302J1D01*
G01X1528574D01*
G02X1528876Y1688821I-1J-303D01*
G01Y1678815D01*
G02X1528574Y1678512I-302J-1D01*
G01X1524874D01*
G02X1524572Y1678815I1J303D01*
G01Y1688821D01*
G37*
G36*
G01X1500950Y1684884D02*
G02X1501252Y1685186I302J0D01*
G01X1504952D01*
G02X1505254Y1684884I0J-302D01*
G01Y1674878D01*
G02X1504952Y1674576I-302J0D01*
G01X1501252D01*
G02X1500950Y1674878I0J302D01*
G01Y1684884D01*
G37*
G36*
G01X1516698D02*
G02X1517000Y1685186I302J0D01*
G01X1520700D01*
G02X1521002Y1684884I0J-302D01*
G01Y1674878D01*
G02X1520700Y1674576I-302J0D01*
G01X1517000D01*
G02X1516698Y1674878I0J302D01*
G01Y1684884D01*
G37*
G36*
G01X1343076Y1731341D02*
G02X1343378Y1731644I302J1D01*
G01X1347078D01*
G02X1347380Y1731341I-1J-303D01*
G01Y1721335D01*
G02X1347078Y1721032I-302J-1D01*
G01X1343378D01*
G02X1343076Y1721335I1J303D01*
G01Y1731341D01*
G37*
G36*
G01X1358824D02*
G02X1359126Y1731644I302J1D01*
G01X1362826D01*
G02X1363128Y1731341I-1J-303D01*
G01Y1721335D01*
G02X1362826Y1721032I-302J-1D01*
G01X1359126D01*
G02X1358824Y1721335I1J303D01*
G01Y1731341D01*
G37*
G36*
G01X1335202Y1727404D02*
G02X1335504Y1727706I302J0D01*
G01X1339204D01*
G02X1339506Y1727404I0J-302D01*
G01Y1717398D01*
G02X1339204Y1717096I-302J0D01*
G01X1335504D01*
G02X1335202Y1717398I0J302D01*
G01Y1727404D01*
G37*
G36*
G01X1350950D02*
G02X1351252Y1727706I302J0D01*
G01X1354952D01*
G02X1355254Y1727404I0J-302D01*
G01Y1717398D01*
G02X1354952Y1717096I-302J0D01*
G01X1351252D01*
G02X1350950Y1717398I0J302D01*
G01Y1727404D01*
G37*
G36*
G01X1343076Y1717168D02*
G02X1343378Y1717470I302J0D01*
G01X1347078D01*
G02X1347380Y1717168I0J-302D01*
G01Y1707162D01*
G02X1347078Y1706860I-302J0D01*
G01X1343378D01*
G02X1343076Y1707162I0J302D01*
G01Y1717168D01*
G37*
G36*
G01X1358824D02*
G02X1359126Y1717470I302J0D01*
G01X1362826D01*
G02X1363128Y1717168I0J-302D01*
G01Y1707162D01*
G02X1362826Y1706860I-302J0D01*
G01X1359126D01*
G02X1358824Y1707162I0J302D01*
G01Y1717168D01*
G37*
G36*
G01X1335202Y1713231D02*
G02X1335504Y1713534I302J1D01*
G01X1339204D01*
G02X1339506Y1713231I-1J-303D01*
G01Y1703225D01*
G02X1339204Y1702922I-302J-1D01*
G01X1335504D01*
G02X1335202Y1703225I1J303D01*
G01Y1713231D01*
G37*
G36*
G01X1350950D02*
G02X1351252Y1713534I302J1D01*
G01X1354952D01*
G02X1355254Y1713231I-1J-303D01*
G01Y1703225D01*
G02X1354952Y1702922I-302J-1D01*
G01X1351252D01*
G02X1350950Y1703225I1J303D01*
G01Y1713231D01*
G37*
G36*
G01X1343076Y1702994D02*
G02X1343378Y1703296I302J0D01*
G01X1347078D01*
G02X1347380Y1702994I0J-302D01*
G01Y1692988D01*
G02X1347078Y1692686I-302J0D01*
G01X1343378D01*
G02X1343076Y1692988I0J302D01*
G01Y1702994D01*
G37*
G36*
G01X1358824D02*
G02X1359126Y1703296I302J0D01*
G01X1362826D01*
G02X1363128Y1702994I0J-302D01*
G01Y1692988D01*
G02X1362826Y1692686I-302J0D01*
G01X1359126D01*
G02X1358824Y1692988I0J302D01*
G01Y1702994D01*
G37*
G36*
G01X1335202Y1699057D02*
G02X1335504Y1699360I302J1D01*
G01X1339204D01*
G02X1339506Y1699057I-1J-303D01*
G01Y1689051D01*
G02X1339204Y1688748I-302J-1D01*
G01X1335504D01*
G02X1335202Y1689051I1J303D01*
G01Y1699057D01*
G37*
G36*
G01X1350950D02*
G02X1351252Y1699360I302J1D01*
G01X1354952D01*
G02X1355254Y1699057I-1J-303D01*
G01Y1689051D01*
G02X1354952Y1688748I-302J-1D01*
G01X1351252D01*
G02X1350950Y1689051I1J303D01*
G01Y1699057D01*
G37*
G36*
G01X1343074Y1688821D02*
G02X1343377Y1689124I303J0D01*
G01X1347077D01*
G02X1347380Y1688821I0J-303D01*
G01Y1678815D01*
G02X1347077Y1678512I-303J0D01*
G01X1343377D01*
G02X1343074Y1678815I0J303D01*
G01Y1688821D01*
G37*
G36*
G01X1358822D02*
G02X1359125Y1689124I303J0D01*
G01X1362825D01*
G02X1363128Y1688821I0J-303D01*
G01Y1678815D01*
G02X1362825Y1678512I-303J0D01*
G01X1359125D01*
G02X1358822Y1678815I0J303D01*
G01Y1688821D01*
G37*
G36*
G01X1335200Y1684884D02*
G02X1335503Y1685186I303J-1D01*
G01X1339203D01*
G02X1339506Y1684884I1J-302D01*
G01Y1674878D01*
G02X1339203Y1674576I-303J1D01*
G01X1335503D01*
G02X1335200Y1674878I-1J302D01*
G01Y1684884D01*
G37*
G36*
G01X1350948D02*
G02X1351251Y1685186I303J-1D01*
G01X1354951D01*
G02X1355254Y1684884I1J-302D01*
G01Y1674878D01*
G02X1354951Y1674576I-303J1D01*
G01X1351251D01*
G02X1350948Y1674878I-1J302D01*
G01Y1684884D01*
G37*
G36*
G01X1311580Y1731341D02*
G02X1311882Y1731644I302J1D01*
G01X1315582D01*
G02X1315884Y1731341I-1J-303D01*
G01Y1721335D01*
G02X1315582Y1721032I-302J-1D01*
G01X1311882D01*
G02X1311580Y1721335I1J303D01*
G01Y1731341D01*
G37*
G36*
G01X1327328D02*
G02X1327630Y1731644I302J1D01*
G01X1331330D01*
G02X1331632Y1731341I-1J-303D01*
G01Y1721335D01*
G02X1331330Y1721032I-302J-1D01*
G01X1327630D01*
G02X1327328Y1721335I1J303D01*
G01Y1731341D01*
G37*
G36*
G01X1303706Y1727404D02*
G02X1304008Y1727706I302J0D01*
G01X1307708D01*
G02X1308010Y1727404I0J-302D01*
G01Y1717398D01*
G02X1307708Y1717096I-302J0D01*
G01X1304008D01*
G02X1303706Y1717398I0J302D01*
G01Y1727404D01*
G37*
G36*
G01X1319454D02*
G02X1319756Y1727706I302J0D01*
G01X1323456D01*
G02X1323758Y1727404I0J-302D01*
G01Y1717398D01*
G02X1323456Y1717096I-302J0D01*
G01X1319756D01*
G02X1319454Y1717398I0J302D01*
G01Y1727404D01*
G37*
G36*
G01X1311580Y1717168D02*
G02X1311882Y1717470I302J0D01*
G01X1315582D01*
G02X1315884Y1717168I0J-302D01*
G01Y1707162D01*
G02X1315582Y1706860I-302J0D01*
G01X1311882D01*
G02X1311580Y1707162I0J302D01*
G01Y1717168D01*
G37*
G36*
G01X1327328D02*
G02X1327630Y1717470I302J0D01*
G01X1331330D01*
G02X1331632Y1717168I0J-302D01*
G01Y1707162D01*
G02X1331330Y1706860I-302J0D01*
G01X1327630D01*
G02X1327328Y1707162I0J302D01*
G01Y1717168D01*
G37*
G36*
G01X1303706Y1713231D02*
G02X1304008Y1713534I302J1D01*
G01X1307708D01*
G02X1308010Y1713231I-1J-303D01*
G01Y1703225D01*
G02X1307708Y1702922I-302J-1D01*
G01X1304008D01*
G02X1303706Y1703225I1J303D01*
G01Y1713231D01*
G37*
G36*
G01X1319454D02*
G02X1319756Y1713534I302J1D01*
G01X1323456D01*
G02X1323758Y1713231I-1J-303D01*
G01Y1703225D01*
G02X1323456Y1702922I-302J-1D01*
G01X1319756D01*
G02X1319454Y1703225I1J303D01*
G01Y1713231D01*
G37*
G36*
G01X1311580Y1702994D02*
G02X1311882Y1703296I302J0D01*
G01X1315582D01*
G02X1315884Y1702994I0J-302D01*
G01Y1692988D01*
G02X1315582Y1692686I-302J0D01*
G01X1311882D01*
G02X1311580Y1692988I0J302D01*
G01Y1702994D01*
G37*
G36*
G01X1327328D02*
G02X1327630Y1703296I302J0D01*
G01X1331330D01*
G02X1331632Y1702994I0J-302D01*
G01Y1692988D01*
G02X1331330Y1692686I-302J0D01*
G01X1327630D01*
G02X1327328Y1692988I0J302D01*
G01Y1702994D01*
G37*
G36*
G01X1303706Y1699057D02*
G02X1304008Y1699360I302J1D01*
G01X1307708D01*
G02X1308010Y1699057I-1J-303D01*
G01Y1689051D01*
G02X1307708Y1688748I-302J-1D01*
G01X1304008D01*
G02X1303706Y1689051I1J303D01*
G01Y1699057D01*
G37*
G36*
G01X1319454D02*
G02X1319756Y1699360I302J1D01*
G01X1323456D01*
G02X1323758Y1699057I-1J-303D01*
G01Y1689051D01*
G02X1323456Y1688748I-302J-1D01*
G01X1319756D01*
G02X1319454Y1689051I1J303D01*
G01Y1699057D01*
G37*
G36*
G01X1311578Y1688821D02*
G02X1311881Y1689124I303J0D01*
G01X1315581D01*
G02X1315884Y1688821I0J-303D01*
G01Y1678815D01*
G02X1315581Y1678512I-303J0D01*
G01X1311881D01*
G02X1311578Y1678815I0J303D01*
G01Y1688821D01*
G37*
G36*
G01X1327326D02*
G02X1327629Y1689124I303J0D01*
G01X1331329D01*
G02X1331632Y1688821I0J-303D01*
G01Y1678815D01*
G02X1331329Y1678512I-303J0D01*
G01X1327629D01*
G02X1327326Y1678815I0J303D01*
G01Y1688821D01*
G37*
G36*
G01X1303704Y1684884D02*
G02X1304007Y1685186I303J-1D01*
G01X1307707D01*
G02X1308010Y1684884I1J-302D01*
G01Y1674878D01*
G02X1307707Y1674576I-303J1D01*
G01X1304007D01*
G02X1303704Y1674878I-1J302D01*
G01Y1684884D01*
G37*
G36*
G01X1319452D02*
G02X1319755Y1685186I303J-1D01*
G01X1323455D01*
G02X1323758Y1684884I1J-302D01*
G01Y1674878D01*
G02X1323455Y1674576I-303J1D01*
G01X1319755D01*
G02X1319452Y1674878I-1J302D01*
G01Y1684884D01*
G37*
G36*
G01X1276146Y1731341D02*
G02X1276449Y1731644I303J0D01*
G01X1280149D01*
G02X1280452Y1731341I0J-303D01*
G01Y1721335D01*
G02X1280149Y1721032I-303J0D01*
G01X1276449D01*
G02X1276146Y1721335I0J303D01*
G01Y1731341D01*
G37*
G36*
G01X1291894D02*
G02X1292197Y1731644I303J0D01*
G01X1295897D01*
G02X1296200Y1731341I0J-303D01*
G01Y1721335D01*
G02X1295897Y1721032I-303J0D01*
G01X1292197D01*
G02X1291894Y1721335I0J303D01*
G01Y1731341D01*
G37*
G36*
G01X1268272Y1727404D02*
G02X1268575Y1727706I303J-1D01*
G01X1272275D01*
G02X1272578Y1727404I1J-302D01*
G01Y1717398D01*
G02X1272275Y1717096I-303J1D01*
G01X1268575D01*
G02X1268272Y1717398I-1J302D01*
G01Y1727404D01*
G37*
G36*
G01X1284020D02*
G02X1284323Y1727706I303J-1D01*
G01X1288023D01*
G02X1288326Y1727404I1J-302D01*
G01Y1717398D01*
G02X1288023Y1717096I-303J1D01*
G01X1284323D01*
G02X1284020Y1717398I-1J302D01*
G01Y1727404D01*
G37*
G36*
G01X1276146Y1717168D02*
G02X1276449Y1717470I303J-1D01*
G01X1280149D01*
G02X1280452Y1717168I1J-302D01*
G01Y1707162D01*
G02X1280149Y1706860I-303J1D01*
G01X1276449D01*
G02X1276146Y1707162I-1J302D01*
G01Y1717168D01*
G37*
G36*
G01X1291894D02*
G02X1292197Y1717470I303J-1D01*
G01X1295897D01*
G02X1296200Y1717168I1J-302D01*
G01Y1707162D01*
G02X1295897Y1706860I-303J1D01*
G01X1292197D01*
G02X1291894Y1707162I-1J302D01*
G01Y1717168D01*
G37*
G36*
G01X1268272Y1713231D02*
G02X1268575Y1713534I303J0D01*
G01X1272275D01*
G02X1272578Y1713231I0J-303D01*
G01Y1703225D01*
G02X1272275Y1702922I-303J0D01*
G01X1268575D01*
G02X1268272Y1703225I0J303D01*
G01Y1713231D01*
G37*
G36*
G01X1284020D02*
G02X1284323Y1713534I303J0D01*
G01X1288023D01*
G02X1288326Y1713231I0J-303D01*
G01Y1703225D01*
G02X1288023Y1702922I-303J0D01*
G01X1284323D01*
G02X1284020Y1703225I0J303D01*
G01Y1713231D01*
G37*
G36*
G01X1276146Y1702994D02*
G02X1276449Y1703296I303J-1D01*
G01X1280149D01*
G02X1280452Y1702994I1J-302D01*
G01Y1692988D01*
G02X1280149Y1692686I-303J1D01*
G01X1276449D01*
G02X1276146Y1692988I-1J302D01*
G01Y1702994D01*
G37*
G36*
G01X1291894D02*
G02X1292197Y1703296I303J-1D01*
G01X1295897D01*
G02X1296200Y1702994I1J-302D01*
G01Y1692988D01*
G02X1295897Y1692686I-303J1D01*
G01X1292197D01*
G02X1291894Y1692988I-1J302D01*
G01Y1702994D01*
G37*
G36*
G01X1268272Y1699057D02*
G02X1268575Y1699360I303J0D01*
G01X1272275D01*
G02X1272578Y1699057I0J-303D01*
G01Y1689051D01*
G02X1272275Y1688748I-303J0D01*
G01X1268575D01*
G02X1268272Y1689051I0J303D01*
G01Y1699057D01*
G37*
G36*
G01X1284020D02*
G02X1284323Y1699360I303J0D01*
G01X1288023D01*
G02X1288326Y1699057I0J-303D01*
G01Y1689051D01*
G02X1288023Y1688748I-303J0D01*
G01X1284323D01*
G02X1284020Y1689051I0J303D01*
G01Y1699057D01*
G37*
G36*
G01X1276146Y1688821D02*
G02X1276448Y1689124I302J1D01*
G01X1280148D01*
G02X1280450Y1688821I-1J-303D01*
G01Y1678815D01*
G02X1280148Y1678512I-302J-1D01*
G01X1276448D01*
G02X1276146Y1678815I1J303D01*
G01Y1688821D01*
G37*
G36*
G01X1291894D02*
G02X1292196Y1689124I302J1D01*
G01X1295896D01*
G02X1296198Y1688821I-1J-303D01*
G01Y1678815D01*
G02X1295896Y1678512I-302J-1D01*
G01X1292196D01*
G02X1291894Y1678815I1J303D01*
G01Y1688821D01*
G37*
G36*
G01X1268272Y1684884D02*
G02X1268574Y1685186I302J0D01*
G01X1272274D01*
G02X1272576Y1684884I0J-302D01*
G01Y1674878D01*
G02X1272274Y1674576I-302J0D01*
G01X1268574D01*
G02X1268272Y1674878I0J302D01*
G01Y1684884D01*
G37*
G36*
G01X1284020D02*
G02X1284322Y1685186I302J0D01*
G01X1288022D01*
G02X1288324Y1684884I0J-302D01*
G01Y1674878D01*
G02X1288022Y1674576I-302J0D01*
G01X1284322D01*
G02X1284020Y1674878I0J302D01*
G01Y1684884D01*
G37*
G36*
G01X1244650Y1731341D02*
G02X1244953Y1731644I303J0D01*
G01X1248653D01*
G02X1248956Y1731341I0J-303D01*
G01Y1721335D01*
G02X1248653Y1721032I-303J0D01*
G01X1244953D01*
G02X1244650Y1721335I0J303D01*
G01Y1731341D01*
G37*
G36*
G01X1260398D02*
G02X1260701Y1731644I303J0D01*
G01X1264401D01*
G02X1264704Y1731341I0J-303D01*
G01Y1721335D01*
G02X1264401Y1721032I-303J0D01*
G01X1260701D01*
G02X1260398Y1721335I0J303D01*
G01Y1731341D01*
G37*
G36*
G01X1236776Y1727404D02*
G02X1237079Y1727706I303J-1D01*
G01X1240779D01*
G02X1241082Y1727404I1J-302D01*
G01Y1717398D01*
G02X1240779Y1717096I-303J1D01*
G01X1237079D01*
G02X1236776Y1717398I-1J302D01*
G01Y1727404D01*
G37*
G36*
G01X1252524D02*
G02X1252827Y1727706I303J-1D01*
G01X1256527D01*
G02X1256830Y1727404I1J-302D01*
G01Y1717398D01*
G02X1256527Y1717096I-303J1D01*
G01X1252827D01*
G02X1252524Y1717398I-1J302D01*
G01Y1727404D01*
G37*
G36*
G01X1244650Y1717168D02*
G02X1244953Y1717470I303J-1D01*
G01X1248653D01*
G02X1248956Y1717168I1J-302D01*
G01Y1707162D01*
G02X1248653Y1706860I-303J1D01*
G01X1244953D01*
G02X1244650Y1707162I-1J302D01*
G01Y1717168D01*
G37*
G36*
G01X1260398D02*
G02X1260701Y1717470I303J-1D01*
G01X1264401D01*
G02X1264704Y1717168I1J-302D01*
G01Y1707162D01*
G02X1264401Y1706860I-303J1D01*
G01X1260701D01*
G02X1260398Y1707162I-1J302D01*
G01Y1717168D01*
G37*
G36*
G01X1236776Y1713231D02*
G02X1237079Y1713534I303J0D01*
G01X1240779D01*
G02X1241082Y1713231I0J-303D01*
G01Y1703225D01*
G02X1240779Y1702922I-303J0D01*
G01X1237079D01*
G02X1236776Y1703225I0J303D01*
G01Y1713231D01*
G37*
G36*
G01X1252524D02*
G02X1252827Y1713534I303J0D01*
G01X1256527D01*
G02X1256830Y1713231I0J-303D01*
G01Y1703225D01*
G02X1256527Y1702922I-303J0D01*
G01X1252827D01*
G02X1252524Y1703225I0J303D01*
G01Y1713231D01*
G37*
G36*
G01X1244650Y1702994D02*
G02X1244953Y1703296I303J-1D01*
G01X1248653D01*
G02X1248956Y1702994I1J-302D01*
G01Y1692988D01*
G02X1248653Y1692686I-303J1D01*
G01X1244953D01*
G02X1244650Y1692988I-1J302D01*
G01Y1702994D01*
G37*
G36*
G01X1260398D02*
G02X1260701Y1703296I303J-1D01*
G01X1264401D01*
G02X1264704Y1702994I1J-302D01*
G01Y1692988D01*
G02X1264401Y1692686I-303J1D01*
G01X1260701D01*
G02X1260398Y1692988I-1J302D01*
G01Y1702994D01*
G37*
G36*
G01X1236776Y1699057D02*
G02X1237079Y1699360I303J0D01*
G01X1240779D01*
G02X1241082Y1699057I0J-303D01*
G01Y1689051D01*
G02X1240779Y1688748I-303J0D01*
G01X1237079D01*
G02X1236776Y1689051I0J303D01*
G01Y1699057D01*
G37*
G36*
G01X1252524D02*
G02X1252827Y1699360I303J0D01*
G01X1256527D01*
G02X1256830Y1699057I0J-303D01*
G01Y1689051D01*
G02X1256527Y1688748I-303J0D01*
G01X1252827D01*
G02X1252524Y1689051I0J303D01*
G01Y1699057D01*
G37*
G36*
G01X1244650Y1688821D02*
G02X1244952Y1689124I302J1D01*
G01X1248652D01*
G02X1248954Y1688821I-1J-303D01*
G01Y1678815D01*
G02X1248652Y1678512I-302J-1D01*
G01X1244952D01*
G02X1244650Y1678815I1J303D01*
G01Y1688821D01*
G37*
G36*
G01X1260398D02*
G02X1260700Y1689124I302J1D01*
G01X1264400D01*
G02X1264702Y1688821I-1J-303D01*
G01Y1678815D01*
G02X1264400Y1678512I-302J-1D01*
G01X1260700D01*
G02X1260398Y1678815I1J303D01*
G01Y1688821D01*
G37*
G36*
G01X1236776Y1684884D02*
G02X1237078Y1685186I302J0D01*
G01X1240778D01*
G02X1241080Y1684884I0J-302D01*
G01Y1674878D01*
G02X1240778Y1674576I-302J0D01*
G01X1237078D01*
G02X1236776Y1674878I0J302D01*
G01Y1684884D01*
G37*
G36*
G01X1252524D02*
G02X1252826Y1685186I302J0D01*
G01X1256526D01*
G02X1256828Y1684884I0J-302D01*
G01Y1674878D01*
G02X1256526Y1674576I-302J0D01*
G01X1252826D01*
G02X1252524Y1674878I0J302D01*
G01Y1684884D01*
G37*
G36*
G01X599374Y1731340D02*
G02X599677Y1731642I303J-1D01*
G01X603377D01*
G02X603680Y1731340I1J-302D01*
G01Y1721334D01*
G02X603377Y1721032I-303J1D01*
G01X599677D01*
G02X599374Y1721334I-1J302D01*
G01Y1731340D01*
G37*
G36*
G01X615122D02*
G02X615425Y1731642I303J-1D01*
G01X619125D01*
G02X619428Y1731340I1J-302D01*
G01Y1721334D01*
G02X619125Y1721032I-303J1D01*
G01X615425D01*
G02X615122Y1721334I-1J302D01*
G01Y1731340D01*
G37*
G36*
G01X591500Y1727403D02*
G02X591803Y1727706I303J0D01*
G01X595503D01*
G02X595806Y1727403I0J-303D01*
G01Y1717397D01*
G02X595503Y1717094I-303J0D01*
G01X591803D01*
G02X591500Y1717397I0J303D01*
G01Y1727403D01*
G37*
G36*
G01X607248D02*
G02X607551Y1727706I303J0D01*
G01X611251D01*
G02X611554Y1727403I0J-303D01*
G01Y1717397D01*
G02X611251Y1717094I-303J0D01*
G01X607551D01*
G02X607248Y1717397I0J303D01*
G01Y1727403D01*
G37*
G36*
G01X599374Y1717167D02*
G02X599677Y1717470I303J0D01*
G01X603377D01*
G02X603680Y1717167I0J-303D01*
G01Y1707161D01*
G02X603377Y1706858I-303J0D01*
G01X599677D01*
G02X599374Y1707161I0J303D01*
G01Y1717167D01*
G37*
G36*
G01X615122D02*
G02X615425Y1717470I303J0D01*
G01X619125D01*
G02X619428Y1717167I0J-303D01*
G01Y1707161D01*
G02X619125Y1706858I-303J0D01*
G01X615425D01*
G02X615122Y1707161I0J303D01*
G01Y1717167D01*
G37*
G36*
G01X591500Y1713230D02*
G02X591803Y1713532I303J-1D01*
G01X595503D01*
G02X595806Y1713230I1J-302D01*
G01Y1703224D01*
G02X595503Y1702922I-303J1D01*
G01X591803D01*
G02X591500Y1703224I-1J302D01*
G01Y1713230D01*
G37*
G36*
G01X607248D02*
G02X607551Y1713532I303J-1D01*
G01X611251D01*
G02X611554Y1713230I1J-302D01*
G01Y1703224D01*
G02X611251Y1702922I-303J1D01*
G01X607551D01*
G02X607248Y1703224I-1J302D01*
G01Y1713230D01*
G37*
G36*
G01X599374Y1702994D02*
G02X599677Y1703296I303J-1D01*
G01X603377D01*
G02X603680Y1702994I1J-302D01*
G01Y1692988D01*
G02X603377Y1692686I-303J1D01*
G01X599677D01*
G02X599374Y1692988I-1J302D01*
G01Y1702994D01*
G37*
G36*
G01X615122D02*
G02X615425Y1703296I303J-1D01*
G01X619125D01*
G02X619428Y1702994I1J-302D01*
G01Y1692988D01*
G02X619125Y1692686I-303J1D01*
G01X615425D01*
G02X615122Y1692988I-1J302D01*
G01Y1702994D01*
G37*
G36*
G01X591500Y1699057D02*
G02X591803Y1699360I303J0D01*
G01X595503D01*
G02X595806Y1699057I0J-303D01*
G01Y1689051D01*
G02X595503Y1688748I-303J0D01*
G01X591803D01*
G02X591500Y1689051I0J303D01*
G01Y1699057D01*
G37*
G36*
G01X607248D02*
G02X607551Y1699360I303J0D01*
G01X611251D01*
G02X611554Y1699057I0J-303D01*
G01Y1689051D01*
G02X611251Y1688748I-303J0D01*
G01X607551D01*
G02X607248Y1689051I0J303D01*
G01Y1699057D01*
G37*
G36*
G01X599374Y1688821D02*
G02X599677Y1689124I303J0D01*
G01X603377D01*
G02X603680Y1688821I0J-303D01*
G01Y1678815D01*
G02X603377Y1678512I-303J0D01*
G01X599677D01*
G02X599374Y1678815I0J303D01*
G01Y1688821D01*
G37*
G36*
G01X615122D02*
G02X615425Y1689124I303J0D01*
G01X619125D01*
G02X619428Y1688821I0J-303D01*
G01Y1678815D01*
G02X619125Y1678512I-303J0D01*
G01X615425D01*
G02X615122Y1678815I0J303D01*
G01Y1688821D01*
G37*
G36*
G01X591500Y1684884D02*
G02X591803Y1685186I303J-1D01*
G01X595503D01*
G02X595806Y1684884I1J-302D01*
G01Y1674878D01*
G02X595503Y1674576I-303J1D01*
G01X591803D01*
G02X591500Y1674878I-1J302D01*
G01Y1684884D01*
G37*
G36*
G01X607248D02*
G02X607551Y1685186I303J-1D01*
G01X611251D01*
G02X611554Y1684884I1J-302D01*
G01Y1674878D01*
G02X611251Y1674576I-303J1D01*
G01X607551D01*
G02X607248Y1674878I-1J302D01*
G01Y1684884D01*
G37*
G36*
G01X567878Y1731340D02*
G02X568181Y1731642I303J-1D01*
G01X571881D01*
G02X572184Y1731340I1J-302D01*
G01Y1721334D01*
G02X571881Y1721032I-303J1D01*
G01X568181D01*
G02X567878Y1721334I-1J302D01*
G01Y1731340D01*
G37*
G36*
G01X583626D02*
G02X583929Y1731642I303J-1D01*
G01X587629D01*
G02X587932Y1731340I1J-302D01*
G01Y1721334D01*
G02X587629Y1721032I-303J1D01*
G01X583929D01*
G02X583626Y1721334I-1J302D01*
G01Y1731340D01*
G37*
G36*
G01X560004Y1727403D02*
G02X560307Y1727706I303J0D01*
G01X564007D01*
G02X564310Y1727403I0J-303D01*
G01Y1717397D01*
G02X564007Y1717094I-303J0D01*
G01X560307D01*
G02X560004Y1717397I0J303D01*
G01Y1727403D01*
G37*
G36*
G01X575752D02*
G02X576055Y1727706I303J0D01*
G01X579755D01*
G02X580058Y1727403I0J-303D01*
G01Y1717397D01*
G02X579755Y1717094I-303J0D01*
G01X576055D01*
G02X575752Y1717397I0J303D01*
G01Y1727403D01*
G37*
G36*
G01X567878Y1717167D02*
G02X568181Y1717470I303J0D01*
G01X571881D01*
G02X572184Y1717167I0J-303D01*
G01Y1707161D01*
G02X571881Y1706858I-303J0D01*
G01X568181D01*
G02X567878Y1707161I0J303D01*
G01Y1717167D01*
G37*
G36*
G01X583626D02*
G02X583929Y1717470I303J0D01*
G01X587629D01*
G02X587932Y1717167I0J-303D01*
G01Y1707161D01*
G02X587629Y1706858I-303J0D01*
G01X583929D01*
G02X583626Y1707161I0J303D01*
G01Y1717167D01*
G37*
G36*
G01X560004Y1713230D02*
G02X560307Y1713532I303J-1D01*
G01X564007D01*
G02X564310Y1713230I1J-302D01*
G01Y1703224D01*
G02X564007Y1702922I-303J1D01*
G01X560307D01*
G02X560004Y1703224I-1J302D01*
G01Y1713230D01*
G37*
G36*
G01X575752D02*
G02X576055Y1713532I303J-1D01*
G01X579755D01*
G02X580058Y1713230I1J-302D01*
G01Y1703224D01*
G02X579755Y1702922I-303J1D01*
G01X576055D01*
G02X575752Y1703224I-1J302D01*
G01Y1713230D01*
G37*
G36*
G01X567878Y1702994D02*
G02X568181Y1703296I303J-1D01*
G01X571881D01*
G02X572184Y1702994I1J-302D01*
G01Y1692988D01*
G02X571881Y1692686I-303J1D01*
G01X568181D01*
G02X567878Y1692988I-1J302D01*
G01Y1702994D01*
G37*
G36*
G01X583626D02*
G02X583929Y1703296I303J-1D01*
G01X587629D01*
G02X587932Y1702994I1J-302D01*
G01Y1692988D01*
G02X587629Y1692686I-303J1D01*
G01X583929D01*
G02X583626Y1692988I-1J302D01*
G01Y1702994D01*
G37*
G36*
G01X560004Y1699057D02*
G02X560307Y1699360I303J0D01*
G01X564007D01*
G02X564310Y1699057I0J-303D01*
G01Y1689051D01*
G02X564007Y1688748I-303J0D01*
G01X560307D01*
G02X560004Y1689051I0J303D01*
G01Y1699057D01*
G37*
G36*
G01X575752D02*
G02X576055Y1699360I303J0D01*
G01X579755D01*
G02X580058Y1699057I0J-303D01*
G01Y1689051D01*
G02X579755Y1688748I-303J0D01*
G01X576055D01*
G02X575752Y1689051I0J303D01*
G01Y1699057D01*
G37*
G36*
G01X567878Y1688821D02*
G02X568181Y1689124I303J0D01*
G01X571881D01*
G02X572184Y1688821I0J-303D01*
G01Y1678815D01*
G02X571881Y1678512I-303J0D01*
G01X568181D01*
G02X567878Y1678815I0J303D01*
G01Y1688821D01*
G37*
G36*
G01X583626D02*
G02X583929Y1689124I303J0D01*
G01X587629D01*
G02X587932Y1688821I0J-303D01*
G01Y1678815D01*
G02X587629Y1678512I-303J0D01*
G01X583929D01*
G02X583626Y1678815I0J303D01*
G01Y1688821D01*
G37*
G36*
G01X560004Y1684884D02*
G02X560307Y1685186I303J-1D01*
G01X564007D01*
G02X564310Y1684884I1J-302D01*
G01Y1674878D01*
G02X564007Y1674576I-303J1D01*
G01X560307D01*
G02X560004Y1674878I-1J302D01*
G01Y1684884D01*
G37*
G36*
G01X575752D02*
G02X576055Y1685186I303J-1D01*
G01X579755D01*
G02X580058Y1684884I1J-302D01*
G01Y1674878D01*
G02X579755Y1674576I-303J1D01*
G01X576055D01*
G02X575752Y1674878I-1J302D01*
G01Y1684884D01*
G37*
G36*
G01X532446Y1731340D02*
G02X532748Y1731642I302J0D01*
G01X536448D01*
G02X536750Y1731340I0J-302D01*
G01Y1721334D01*
G02X536448Y1721032I-302J0D01*
G01X532748D01*
G02X532446Y1721334I0J302D01*
G01Y1731340D01*
G37*
G36*
G01X548194D02*
G02X548496Y1731642I302J0D01*
G01X552196D01*
G02X552498Y1731340I0J-302D01*
G01Y1721334D01*
G02X552196Y1721032I-302J0D01*
G01X548496D01*
G02X548194Y1721334I0J302D01*
G01Y1731340D01*
G37*
G36*
G01X524572Y1727403D02*
G02X524874Y1727706I302J1D01*
G01X528574D01*
G02X528876Y1727403I-1J-303D01*
G01Y1717397D01*
G02X528574Y1717094I-302J-1D01*
G01X524874D01*
G02X524572Y1717397I1J303D01*
G01Y1727403D01*
G37*
G36*
G01X540320D02*
G02X540622Y1727706I302J1D01*
G01X544322D01*
G02X544624Y1727403I-1J-303D01*
G01Y1717397D01*
G02X544322Y1717094I-302J-1D01*
G01X540622D01*
G02X540320Y1717397I1J303D01*
G01Y1727403D01*
G37*
G36*
G01X532446Y1717167D02*
G02X532748Y1717470I302J1D01*
G01X536448D01*
G02X536750Y1717167I-1J-303D01*
G01Y1707161D01*
G02X536448Y1706858I-302J-1D01*
G01X532748D01*
G02X532446Y1707161I1J303D01*
G01Y1717167D01*
G37*
G36*
G01X548194D02*
G02X548496Y1717470I302J1D01*
G01X552196D01*
G02X552498Y1717167I-1J-303D01*
G01Y1707161D01*
G02X552196Y1706858I-302J-1D01*
G01X548496D01*
G02X548194Y1707161I1J303D01*
G01Y1717167D01*
G37*
G36*
G01X524572Y1713230D02*
G02X524874Y1713532I302J0D01*
G01X528574D01*
G02X528876Y1713230I0J-302D01*
G01Y1703224D01*
G02X528574Y1702922I-302J0D01*
G01X524874D01*
G02X524572Y1703224I0J302D01*
G01Y1713230D01*
G37*
G36*
G01X540320D02*
G02X540622Y1713532I302J0D01*
G01X544322D01*
G02X544624Y1713230I0J-302D01*
G01Y1703224D01*
G02X544322Y1702922I-302J0D01*
G01X540622D01*
G02X540320Y1703224I0J302D01*
G01Y1713230D01*
G37*
G36*
G01X532446Y1702994D02*
G02X532748Y1703296I302J0D01*
G01X536448D01*
G02X536750Y1702994I0J-302D01*
G01Y1692988D01*
G02X536448Y1692686I-302J0D01*
G01X532748D01*
G02X532446Y1692988I0J302D01*
G01Y1702994D01*
G37*
G36*
G01X548194D02*
G02X548496Y1703296I302J0D01*
G01X552196D01*
G02X552498Y1702994I0J-302D01*
G01Y1692988D01*
G02X552196Y1692686I-302J0D01*
G01X548496D01*
G02X548194Y1692988I0J302D01*
G01Y1702994D01*
G37*
G36*
G01X524572Y1699057D02*
G02X524874Y1699360I302J1D01*
G01X528574D01*
G02X528876Y1699057I-1J-303D01*
G01Y1689051D01*
G02X528574Y1688748I-302J-1D01*
G01X524874D01*
G02X524572Y1689051I1J303D01*
G01Y1699057D01*
G37*
G36*
G01X540320D02*
G02X540622Y1699360I302J1D01*
G01X544322D01*
G02X544624Y1699057I-1J-303D01*
G01Y1689051D01*
G02X544322Y1688748I-302J-1D01*
G01X540622D01*
G02X540320Y1689051I1J303D01*
G01Y1699057D01*
G37*
G36*
G01X532446Y1688821D02*
G02X532748Y1689124I302J1D01*
G01X536448D01*
G02X536750Y1688821I-1J-303D01*
G01Y1678815D01*
G02X536448Y1678512I-302J-1D01*
G01X532748D01*
G02X532446Y1678815I1J303D01*
G01Y1688821D01*
G37*
G36*
G01X548194D02*
G02X548496Y1689124I302J1D01*
G01X552196D01*
G02X552498Y1688821I-1J-303D01*
G01Y1678815D01*
G02X552196Y1678512I-302J-1D01*
G01X548496D01*
G02X548194Y1678815I1J303D01*
G01Y1688821D01*
G37*
G36*
G01X524572Y1684884D02*
G02X524874Y1685186I302J0D01*
G01X528574D01*
G02X528876Y1684884I0J-302D01*
G01Y1674878D01*
G02X528574Y1674576I-302J0D01*
G01X524874D01*
G02X524572Y1674878I0J302D01*
G01Y1684884D01*
G37*
G36*
G01X540320D02*
G02X540622Y1685186I302J0D01*
G01X544322D01*
G02X544624Y1684884I0J-302D01*
G01Y1674878D01*
G02X544322Y1674576I-302J0D01*
G01X540622D01*
G02X540320Y1674878I0J302D01*
G01Y1684884D01*
G37*
G36*
G01X500950Y1731340D02*
G02X501252Y1731642I302J0D01*
G01X504952D01*
G02X505254Y1731340I0J-302D01*
G01Y1721334D01*
G02X504952Y1721032I-302J0D01*
G01X501252D01*
G02X500950Y1721334I0J302D01*
G01Y1731340D01*
G37*
G36*
G01X516698D02*
G02X517000Y1731642I302J0D01*
G01X520700D01*
G02X521002Y1731340I0J-302D01*
G01Y1721334D01*
G02X520700Y1721032I-302J0D01*
G01X517000D01*
G02X516698Y1721334I0J302D01*
G01Y1731340D01*
G37*
G36*
G01X493076Y1727403D02*
G02X493378Y1727706I302J1D01*
G01X497078D01*
G02X497380Y1727403I-1J-303D01*
G01Y1717397D01*
G02X497078Y1717094I-302J-1D01*
G01X493378D01*
G02X493076Y1717397I1J303D01*
G01Y1727403D01*
G37*
G36*
G01X508824D02*
G02X509126Y1727706I302J1D01*
G01X512826D01*
G02X513128Y1727403I-1J-303D01*
G01Y1717397D01*
G02X512826Y1717094I-302J-1D01*
G01X509126D01*
G02X508824Y1717397I1J303D01*
G01Y1727403D01*
G37*
G36*
G01X500950Y1717167D02*
G02X501252Y1717470I302J1D01*
G01X504952D01*
G02X505254Y1717167I-1J-303D01*
G01Y1707161D01*
G02X504952Y1706858I-302J-1D01*
G01X501252D01*
G02X500950Y1707161I1J303D01*
G01Y1717167D01*
G37*
G36*
G01X516698D02*
G02X517000Y1717470I302J1D01*
G01X520700D01*
G02X521002Y1717167I-1J-303D01*
G01Y1707161D01*
G02X520700Y1706858I-302J-1D01*
G01X517000D01*
G02X516698Y1707161I1J303D01*
G01Y1717167D01*
G37*
G36*
G01X493076Y1713230D02*
G02X493378Y1713532I302J0D01*
G01X497078D01*
G02X497380Y1713230I0J-302D01*
G01Y1703224D01*
G02X497078Y1702922I-302J0D01*
G01X493378D01*
G02X493076Y1703224I0J302D01*
G01Y1713230D01*
G37*
G36*
G01X508824D02*
G02X509126Y1713532I302J0D01*
G01X512826D01*
G02X513128Y1713230I0J-302D01*
G01Y1703224D01*
G02X512826Y1702922I-302J0D01*
G01X509126D01*
G02X508824Y1703224I0J302D01*
G01Y1713230D01*
G37*
G36*
G01X500950Y1702994D02*
G02X501252Y1703296I302J0D01*
G01X504952D01*
G02X505254Y1702994I0J-302D01*
G01Y1692988D01*
G02X504952Y1692686I-302J0D01*
G01X501252D01*
G02X500950Y1692988I0J302D01*
G01Y1702994D01*
G37*
G36*
G01X516698D02*
G02X517000Y1703296I302J0D01*
G01X520700D01*
G02X521002Y1702994I0J-302D01*
G01Y1692988D01*
G02X520700Y1692686I-302J0D01*
G01X517000D01*
G02X516698Y1692988I0J302D01*
G01Y1702994D01*
G37*
G36*
G01X493076Y1699057D02*
G02X493378Y1699360I302J1D01*
G01X497078D01*
G02X497380Y1699057I-1J-303D01*
G01Y1689051D01*
G02X497078Y1688748I-302J-1D01*
G01X493378D01*
G02X493076Y1689051I1J303D01*
G01Y1699057D01*
G37*
G36*
G01X508824D02*
G02X509126Y1699360I302J1D01*
G01X512826D01*
G02X513128Y1699057I-1J-303D01*
G01Y1689051D01*
G02X512826Y1688748I-302J-1D01*
G01X509126D01*
G02X508824Y1689051I1J303D01*
G01Y1699057D01*
G37*
G36*
G01X500950Y1688821D02*
G02X501252Y1689124I302J1D01*
G01X504952D01*
G02X505254Y1688821I-1J-303D01*
G01Y1678815D01*
G02X504952Y1678512I-302J-1D01*
G01X501252D01*
G02X500950Y1678815I1J303D01*
G01Y1688821D01*
G37*
G36*
G01X516698D02*
G02X517000Y1689124I302J1D01*
G01X520700D01*
G02X521002Y1688821I-1J-303D01*
G01Y1678815D01*
G02X520700Y1678512I-302J-1D01*
G01X517000D01*
G02X516698Y1678815I1J303D01*
G01Y1688821D01*
G37*
G36*
G01X493076Y1684884D02*
G02X493378Y1685186I302J0D01*
G01X497078D01*
G02X497380Y1684884I0J-302D01*
G01Y1674878D01*
G02X497078Y1674576I-302J0D01*
G01X493378D01*
G02X493076Y1674878I0J302D01*
G01Y1684884D01*
G37*
G36*
G01X508824D02*
G02X509126Y1685186I302J0D01*
G01X512826D01*
G02X513128Y1684884I0J-302D01*
G01Y1674878D01*
G02X512826Y1674576I-302J0D01*
G01X509126D01*
G02X508824Y1674878I0J302D01*
G01Y1684884D01*
G37*
G36*
G01X335202Y1731341D02*
G02X335504Y1731644I302J1D01*
G01X339204D01*
G02X339506Y1731341I-1J-303D01*
G01Y1721335D01*
G02X339204Y1721032I-302J-1D01*
G01X335504D01*
G02X335202Y1721335I1J303D01*
G01Y1731341D01*
G37*
G36*
G01X350950D02*
G02X351252Y1731644I302J1D01*
G01X354952D01*
G02X355254Y1731341I-1J-303D01*
G01Y1721335D01*
G02X354952Y1721032I-302J-1D01*
G01X351252D01*
G02X350950Y1721335I1J303D01*
G01Y1731341D01*
G37*
G36*
G01X327328Y1727404D02*
G02X327630Y1727706I302J0D01*
G01X331330D01*
G02X331632Y1727404I0J-302D01*
G01Y1717398D01*
G02X331330Y1717096I-302J0D01*
G01X327630D01*
G02X327328Y1717398I0J302D01*
G01Y1727404D01*
G37*
G36*
G01X343076D02*
G02X343378Y1727706I302J0D01*
G01X347078D01*
G02X347380Y1727404I0J-302D01*
G01Y1717398D01*
G02X347078Y1717096I-302J0D01*
G01X343378D01*
G02X343076Y1717398I0J302D01*
G01Y1727404D01*
G37*
G36*
G01X335202Y1717167D02*
G02X335504Y1717470I302J1D01*
G01X339204D01*
G02X339506Y1717167I-1J-303D01*
G01Y1707161D01*
G02X339204Y1706858I-302J-1D01*
G01X335504D01*
G02X335202Y1707161I1J303D01*
G01Y1717167D01*
G37*
G36*
G01X350950D02*
G02X351252Y1717470I302J1D01*
G01X354952D01*
G02X355254Y1717167I-1J-303D01*
G01Y1707161D01*
G02X354952Y1706858I-302J-1D01*
G01X351252D01*
G02X350950Y1707161I1J303D01*
G01Y1717167D01*
G37*
G36*
G01X327328Y1713230D02*
G02X327630Y1713532I302J0D01*
G01X331330D01*
G02X331632Y1713230I0J-302D01*
G01Y1703224D01*
G02X331330Y1702922I-302J0D01*
G01X327630D01*
G02X327328Y1703224I0J302D01*
G01Y1713230D01*
G37*
G36*
G01X343076D02*
G02X343378Y1713532I302J0D01*
G01X347078D01*
G02X347380Y1713230I0J-302D01*
G01Y1703224D01*
G02X347078Y1702922I-302J0D01*
G01X343378D01*
G02X343076Y1703224I0J302D01*
G01Y1713230D01*
G37*
G36*
G01X335202Y1702994D02*
G02X335504Y1703296I302J0D01*
G01X339204D01*
G02X339506Y1702994I0J-302D01*
G01Y1692988D01*
G02X339204Y1692686I-302J0D01*
G01X335504D01*
G02X335202Y1692988I0J302D01*
G01Y1702994D01*
G37*
G36*
G01X350950D02*
G02X351252Y1703296I302J0D01*
G01X354952D01*
G02X355254Y1702994I0J-302D01*
G01Y1692988D01*
G02X354952Y1692686I-302J0D01*
G01X351252D01*
G02X350950Y1692988I0J302D01*
G01Y1702994D01*
G37*
G36*
G01X327328Y1699057D02*
G02X327630Y1699360I302J1D01*
G01X331330D01*
G02X331632Y1699057I-1J-303D01*
G01Y1689051D01*
G02X331330Y1688748I-302J-1D01*
G01X327630D01*
G02X327328Y1689051I1J303D01*
G01Y1699057D01*
G37*
G36*
G01X343076D02*
G02X343378Y1699360I302J1D01*
G01X347078D01*
G02X347380Y1699057I-1J-303D01*
G01Y1689051D01*
G02X347078Y1688748I-302J-1D01*
G01X343378D01*
G02X343076Y1689051I1J303D01*
G01Y1699057D01*
G37*
G36*
G01X335202Y1688821D02*
G02X335504Y1689124I302J1D01*
G01X339204D01*
G02X339506Y1688821I-1J-303D01*
G01Y1678815D01*
G02X339204Y1678512I-302J-1D01*
G01X335504D01*
G02X335202Y1678815I1J303D01*
G01Y1688821D01*
G37*
G36*
G01X350950D02*
G02X351252Y1689124I302J1D01*
G01X354952D01*
G02X355254Y1688821I-1J-303D01*
G01Y1678815D01*
G02X354952Y1678512I-302J-1D01*
G01X351252D01*
G02X350950Y1678815I1J303D01*
G01Y1688821D01*
G37*
G36*
G01X327328Y1684884D02*
G02X327630Y1685186I302J0D01*
G01X331330D01*
G02X331632Y1684884I0J-302D01*
G01Y1674878D01*
G02X331330Y1674576I-302J0D01*
G01X327630D01*
G02X327328Y1674878I0J302D01*
G01Y1684884D01*
G37*
G36*
G01X343076D02*
G02X343378Y1685186I302J0D01*
G01X347078D01*
G02X347380Y1684884I0J-302D01*
G01Y1674878D01*
G02X347078Y1674576I-302J0D01*
G01X343378D01*
G02X343076Y1674878I0J302D01*
G01Y1684884D01*
G37*
G36*
G01X303706Y1731341D02*
G02X304008Y1731644I302J1D01*
G01X307708D01*
G02X308010Y1731341I-1J-303D01*
G01Y1721335D01*
G02X307708Y1721032I-302J-1D01*
G01X304008D01*
G02X303706Y1721335I1J303D01*
G01Y1731341D01*
G37*
G36*
G01X319454D02*
G02X319756Y1731644I302J1D01*
G01X323456D01*
G02X323758Y1731341I-1J-303D01*
G01Y1721335D01*
G02X323456Y1721032I-302J-1D01*
G01X319756D01*
G02X319454Y1721335I1J303D01*
G01Y1731341D01*
G37*
G36*
G01X295832Y1727404D02*
G02X296134Y1727706I302J0D01*
G01X299834D01*
G02X300136Y1727404I0J-302D01*
G01Y1717398D01*
G02X299834Y1717096I-302J0D01*
G01X296134D01*
G02X295832Y1717398I0J302D01*
G01Y1727404D01*
G37*
G36*
G01X311580D02*
G02X311882Y1727706I302J0D01*
G01X315582D01*
G02X315884Y1727404I0J-302D01*
G01Y1717398D01*
G02X315582Y1717096I-302J0D01*
G01X311882D01*
G02X311580Y1717398I0J302D01*
G01Y1727404D01*
G37*
G36*
G01X303706Y1717167D02*
G02X304008Y1717470I302J1D01*
G01X307708D01*
G02X308010Y1717167I-1J-303D01*
G01Y1707161D01*
G02X307708Y1706858I-302J-1D01*
G01X304008D01*
G02X303706Y1707161I1J303D01*
G01Y1717167D01*
G37*
G36*
G01X319454D02*
G02X319756Y1717470I302J1D01*
G01X323456D01*
G02X323758Y1717167I-1J-303D01*
G01Y1707161D01*
G02X323456Y1706858I-302J-1D01*
G01X319756D01*
G02X319454Y1707161I1J303D01*
G01Y1717167D01*
G37*
G36*
G01X295832Y1713230D02*
G02X296134Y1713532I302J0D01*
G01X299834D01*
G02X300136Y1713230I0J-302D01*
G01Y1703224D01*
G02X299834Y1702922I-302J0D01*
G01X296134D01*
G02X295832Y1703224I0J302D01*
G01Y1713230D01*
G37*
G36*
G01X311580D02*
G02X311882Y1713532I302J0D01*
G01X315582D01*
G02X315884Y1713230I0J-302D01*
G01Y1703224D01*
G02X315582Y1702922I-302J0D01*
G01X311882D01*
G02X311580Y1703224I0J302D01*
G01Y1713230D01*
G37*
G36*
G01X303706Y1702994D02*
G02X304008Y1703296I302J0D01*
G01X307708D01*
G02X308010Y1702994I0J-302D01*
G01Y1692988D01*
G02X307708Y1692686I-302J0D01*
G01X304008D01*
G02X303706Y1692988I0J302D01*
G01Y1702994D01*
G37*
G36*
G01X319454D02*
G02X319756Y1703296I302J0D01*
G01X323456D01*
G02X323758Y1702994I0J-302D01*
G01Y1692988D01*
G02X323456Y1692686I-302J0D01*
G01X319756D01*
G02X319454Y1692988I0J302D01*
G01Y1702994D01*
G37*
G36*
G01X295832Y1699057D02*
G02X296134Y1699360I302J1D01*
G01X299834D01*
G02X300136Y1699057I-1J-303D01*
G01Y1689051D01*
G02X299834Y1688748I-302J-1D01*
G01X296134D01*
G02X295832Y1689051I1J303D01*
G01Y1699057D01*
G37*
G36*
G01X311580D02*
G02X311882Y1699360I302J1D01*
G01X315582D01*
G02X315884Y1699057I-1J-303D01*
G01Y1689051D01*
G02X315582Y1688748I-302J-1D01*
G01X311882D01*
G02X311580Y1689051I1J303D01*
G01Y1699057D01*
G37*
G36*
G01X303706Y1688821D02*
G02X304008Y1689124I302J1D01*
G01X307708D01*
G02X308010Y1688821I-1J-303D01*
G01Y1678815D01*
G02X307708Y1678512I-302J-1D01*
G01X304008D01*
G02X303706Y1678815I1J303D01*
G01Y1688821D01*
G37*
G36*
G01X319454D02*
G02X319756Y1689124I302J1D01*
G01X323456D01*
G02X323758Y1688821I-1J-303D01*
G01Y1678815D01*
G02X323456Y1678512I-302J-1D01*
G01X319756D01*
G02X319454Y1678815I1J303D01*
G01Y1688821D01*
G37*
G36*
G01X295832Y1684884D02*
G02X296134Y1685186I302J0D01*
G01X299834D01*
G02X300136Y1684884I0J-302D01*
G01Y1674878D01*
G02X299834Y1674576I-302J0D01*
G01X296134D01*
G02X295832Y1674878I0J302D01*
G01Y1684884D01*
G37*
G36*
G01X311580D02*
G02X311882Y1685186I302J0D01*
G01X315582D01*
G02X315884Y1684884I0J-302D01*
G01Y1674878D01*
G02X315582Y1674576I-302J0D01*
G01X311882D01*
G02X311580Y1674878I0J302D01*
G01Y1684884D01*
G37*
G36*
G01X268272Y1731341D02*
G02X268575Y1731644I303J0D01*
G01X272275D01*
G02X272578Y1731341I0J-303D01*
G01Y1721335D01*
G02X272275Y1721032I-303J0D01*
G01X268575D01*
G02X268272Y1721335I0J303D01*
G01Y1731341D01*
G37*
G36*
G01X284020D02*
G02X284323Y1731644I303J0D01*
G01X288023D01*
G02X288326Y1731341I0J-303D01*
G01Y1721335D01*
G02X288023Y1721032I-303J0D01*
G01X284323D01*
G02X284020Y1721335I0J303D01*
G01Y1731341D01*
G37*
G36*
G01X260398Y1727404D02*
G02X260701Y1727706I303J-1D01*
G01X264401D01*
G02X264704Y1727404I1J-302D01*
G01Y1717398D01*
G02X264401Y1717096I-303J1D01*
G01X260701D01*
G02X260398Y1717398I-1J302D01*
G01Y1727404D01*
G37*
G36*
G01X276146D02*
G02X276449Y1727706I303J-1D01*
G01X280149D01*
G02X280452Y1727404I1J-302D01*
G01Y1717398D01*
G02X280149Y1717096I-303J1D01*
G01X276449D01*
G02X276146Y1717398I-1J302D01*
G01Y1727404D01*
G37*
G36*
G01X268272Y1717167D02*
G02X268575Y1717470I303J0D01*
G01X272275D01*
G02X272578Y1717167I0J-303D01*
G01Y1707161D01*
G02X272275Y1706858I-303J0D01*
G01X268575D01*
G02X268272Y1707161I0J303D01*
G01Y1717167D01*
G37*
G36*
G01X284020D02*
G02X284323Y1717470I303J0D01*
G01X288023D01*
G02X288326Y1717167I0J-303D01*
G01Y1707161D01*
G02X288023Y1706858I-303J0D01*
G01X284323D01*
G02X284020Y1707161I0J303D01*
G01Y1717167D01*
G37*
G36*
G01X260398Y1713230D02*
G02X260701Y1713532I303J-1D01*
G01X264401D01*
G02X264704Y1713230I1J-302D01*
G01Y1703224D01*
G02X264401Y1702922I-303J1D01*
G01X260701D01*
G02X260398Y1703224I-1J302D01*
G01Y1713230D01*
G37*
G36*
G01X276146D02*
G02X276449Y1713532I303J-1D01*
G01X280149D01*
G02X280452Y1713230I1J-302D01*
G01Y1703224D01*
G02X280149Y1702922I-303J1D01*
G01X276449D01*
G02X276146Y1703224I-1J302D01*
G01Y1713230D01*
G37*
G36*
G01X268272Y1702994D02*
G02X268575Y1703296I303J-1D01*
G01X272275D01*
G02X272578Y1702994I1J-302D01*
G01Y1692988D01*
G02X272275Y1692686I-303J1D01*
G01X268575D01*
G02X268272Y1692988I-1J302D01*
G01Y1702994D01*
G37*
G36*
G01X284020D02*
G02X284323Y1703296I303J-1D01*
G01X288023D01*
G02X288326Y1702994I1J-302D01*
G01Y1692988D01*
G02X288023Y1692686I-303J1D01*
G01X284323D01*
G02X284020Y1692988I-1J302D01*
G01Y1702994D01*
G37*
G36*
G01X260398Y1699057D02*
G02X260701Y1699360I303J0D01*
G01X264401D01*
G02X264704Y1699057I0J-303D01*
G01Y1689051D01*
G02X264401Y1688748I-303J0D01*
G01X260701D01*
G02X260398Y1689051I0J303D01*
G01Y1699057D01*
G37*
G36*
G01X276146D02*
G02X276449Y1699360I303J0D01*
G01X280149D01*
G02X280452Y1699057I0J-303D01*
G01Y1689051D01*
G02X280149Y1688748I-303J0D01*
G01X276449D01*
G02X276146Y1689051I0J303D01*
G01Y1699057D01*
G37*
G36*
G01X268272Y1688821D02*
G02X268575Y1689124I303J0D01*
G01X272275D01*
G02X272578Y1688821I0J-303D01*
G01Y1678815D01*
G02X272275Y1678512I-303J0D01*
G01X268575D01*
G02X268272Y1678815I0J303D01*
G01Y1688821D01*
G37*
G36*
G01X284020D02*
G02X284323Y1689124I303J0D01*
G01X288023D01*
G02X288326Y1688821I0J-303D01*
G01Y1678815D01*
G02X288023Y1678512I-303J0D01*
G01X284323D01*
G02X284020Y1678815I0J303D01*
G01Y1688821D01*
G37*
G36*
G01X260398Y1684884D02*
G02X260701Y1685186I303J-1D01*
G01X264401D01*
G02X264704Y1684884I1J-302D01*
G01Y1674878D01*
G02X264401Y1674576I-303J1D01*
G01X260701D01*
G02X260398Y1674878I-1J302D01*
G01Y1684884D01*
G37*
G36*
G01X276146D02*
G02X276449Y1685186I303J-1D01*
G01X280149D01*
G02X280452Y1684884I1J-302D01*
G01Y1674878D01*
G02X280149Y1674576I-303J1D01*
G01X276449D01*
G02X276146Y1674878I-1J302D01*
G01Y1684884D01*
G37*
G36*
G01X268272Y1674648D02*
G02X268575Y1674950I303J-1D01*
G01X272275D01*
G02X272578Y1674648I1J-302D01*
G01Y1664642D01*
G02X272275Y1664340I-303J1D01*
G01X268575D01*
G02X268272Y1664642I-1J302D01*
G01Y1674648D01*
G37*
G36*
G01X284020D02*
G02X284323Y1674950I303J-1D01*
G01X288023D01*
G02X288326Y1674648I1J-302D01*
G01Y1664642D01*
G02X288023Y1664340I-303J1D01*
G01X284323D01*
G02X284020Y1664642I-1J302D01*
G01Y1674648D01*
G37*
G36*
G01X276146Y1670711D02*
G02X276449Y1671014I303J0D01*
G01X280149D01*
G02X280452Y1670711I0J-303D01*
G01Y1660705D01*
G02X280149Y1660402I-303J0D01*
G01X276449D01*
G02X276146Y1660705I0J303D01*
G01Y1670711D01*
G37*
G36*
G01X268272Y1660474D02*
G02X268575Y1660776I303J-1D01*
G01X272275D01*
G02X272578Y1660474I1J-302D01*
G01Y1650468D01*
G02X272275Y1650166I-303J1D01*
G01X268575D01*
G02X268272Y1650468I-1J302D01*
G01Y1660474D01*
G37*
G36*
G01X284020D02*
G02X284323Y1660776I303J-1D01*
G01X288023D01*
G02X288326Y1660474I1J-302D01*
G01Y1650468D01*
G02X288023Y1650166I-303J1D01*
G01X284323D01*
G02X284020Y1650468I-1J302D01*
G01Y1660474D01*
G37*
G36*
G01X276146Y1656537D02*
G02X276449Y1656840I303J0D01*
G01X280149D01*
G02X280452Y1656537I0J-303D01*
G01Y1646531D01*
G02X280149Y1646228I-303J0D01*
G01X276449D01*
G02X276146Y1646531I0J303D01*
G01Y1656537D01*
G37*
G36*
G01X236776Y1731341D02*
G02X237079Y1731644I303J0D01*
G01X240779D01*
G02X241082Y1731341I0J-303D01*
G01Y1721335D01*
G02X240779Y1721032I-303J0D01*
G01X237079D01*
G02X236776Y1721335I0J303D01*
G01Y1731341D01*
G37*
G36*
G01X252524D02*
G02X252827Y1731644I303J0D01*
G01X256527D01*
G02X256830Y1731341I0J-303D01*
G01Y1721335D01*
G02X256527Y1721032I-303J0D01*
G01X252827D01*
G02X252524Y1721335I0J303D01*
G01Y1731341D01*
G37*
G36*
G01X228902Y1727404D02*
G02X229205Y1727706I303J-1D01*
G01X232905D01*
G02X233208Y1727404I1J-302D01*
G01Y1717398D01*
G02X232905Y1717096I-303J1D01*
G01X229205D01*
G02X228902Y1717398I-1J302D01*
G01Y1727404D01*
G37*
G36*
G01X244650D02*
G02X244953Y1727706I303J-1D01*
G01X248653D01*
G02X248956Y1727404I1J-302D01*
G01Y1717398D01*
G02X248653Y1717096I-303J1D01*
G01X244953D01*
G02X244650Y1717398I-1J302D01*
G01Y1727404D01*
G37*
G36*
G01X236776Y1717167D02*
G02X237079Y1717470I303J0D01*
G01X240779D01*
G02X241082Y1717167I0J-303D01*
G01Y1707161D01*
G02X240779Y1706858I-303J0D01*
G01X237079D01*
G02X236776Y1707161I0J303D01*
G01Y1717167D01*
G37*
G36*
G01X252524D02*
G02X252827Y1717470I303J0D01*
G01X256527D01*
G02X256830Y1717167I0J-303D01*
G01Y1707161D01*
G02X256527Y1706858I-303J0D01*
G01X252827D01*
G02X252524Y1707161I0J303D01*
G01Y1717167D01*
G37*
G36*
G01X228902Y1713230D02*
G02X229205Y1713532I303J-1D01*
G01X232905D01*
G02X233208Y1713230I1J-302D01*
G01Y1703224D01*
G02X232905Y1702922I-303J1D01*
G01X229205D01*
G02X228902Y1703224I-1J302D01*
G01Y1713230D01*
G37*
G36*
G01X244650D02*
G02X244953Y1713532I303J-1D01*
G01X248653D01*
G02X248956Y1713230I1J-302D01*
G01Y1703224D01*
G02X248653Y1702922I-303J1D01*
G01X244953D01*
G02X244650Y1703224I-1J302D01*
G01Y1713230D01*
G37*
G36*
G01X236776Y1702994D02*
G02X237079Y1703296I303J-1D01*
G01X240779D01*
G02X241082Y1702994I1J-302D01*
G01Y1692988D01*
G02X240779Y1692686I-303J1D01*
G01X237079D01*
G02X236776Y1692988I-1J302D01*
G01Y1702994D01*
G37*
G36*
G01X252524D02*
G02X252827Y1703296I303J-1D01*
G01X256527D01*
G02X256830Y1702994I1J-302D01*
G01Y1692988D01*
G02X256527Y1692686I-303J1D01*
G01X252827D01*
G02X252524Y1692988I-1J302D01*
G01Y1702994D01*
G37*
G36*
G01X228902Y1699057D02*
G02X229205Y1699360I303J0D01*
G01X232905D01*
G02X233208Y1699057I0J-303D01*
G01Y1689051D01*
G02X232905Y1688748I-303J0D01*
G01X229205D01*
G02X228902Y1689051I0J303D01*
G01Y1699057D01*
G37*
G36*
G01X244650D02*
G02X244953Y1699360I303J0D01*
G01X248653D01*
G02X248956Y1699057I0J-303D01*
G01Y1689051D01*
G02X248653Y1688748I-303J0D01*
G01X244953D01*
G02X244650Y1689051I0J303D01*
G01Y1699057D01*
G37*
G36*
G01X236776Y1688821D02*
G02X237079Y1689124I303J0D01*
G01X240779D01*
G02X241082Y1688821I0J-303D01*
G01Y1678815D01*
G02X240779Y1678512I-303J0D01*
G01X237079D01*
G02X236776Y1678815I0J303D01*
G01Y1688821D01*
G37*
G36*
G01X252524D02*
G02X252827Y1689124I303J0D01*
G01X256527D01*
G02X256830Y1688821I0J-303D01*
G01Y1678815D01*
G02X256527Y1678512I-303J0D01*
G01X252827D01*
G02X252524Y1678815I0J303D01*
G01Y1688821D01*
G37*
G36*
G01X228902Y1684884D02*
G02X229205Y1685186I303J-1D01*
G01X232905D01*
G02X233208Y1684884I1J-302D01*
G01Y1674878D01*
G02X232905Y1674576I-303J1D01*
G01X229205D01*
G02X228902Y1674878I-1J302D01*
G01Y1684884D01*
G37*
G36*
G01X244650D02*
G02X244953Y1685186I303J-1D01*
G01X248653D01*
G02X248956Y1684884I1J-302D01*
G01Y1674878D01*
G02X248653Y1674576I-303J1D01*
G01X244953D01*
G02X244650Y1674878I-1J302D01*
G01Y1684884D01*
G37*
G36*
G01X252524Y1674648D02*
G02X252827Y1674950I303J-1D01*
G01X256527D01*
G02X256830Y1674648I1J-302D01*
G01Y1664642D01*
G02X256527Y1664340I-303J1D01*
G01X252827D01*
G02X252524Y1664642I-1J302D01*
G01Y1674648D01*
G37*
G36*
G01X228902Y1670711D02*
G02X229205Y1671014I303J0D01*
G01X232905D01*
G02X233208Y1670711I0J-303D01*
G01Y1660705D01*
G02X232905Y1660402I-303J0D01*
G01X229205D01*
G02X228902Y1660705I0J303D01*
G01Y1670711D01*
G37*
G36*
G01X244650D02*
G02X244953Y1671014I303J0D01*
G01X248653D01*
G02X248956Y1670711I0J-303D01*
G01Y1660705D01*
G02X248653Y1660402I-303J0D01*
G01X244953D01*
G02X244650Y1660705I0J303D01*
G01Y1670711D01*
G37*
G36*
G01X236776Y1660474D02*
G02X237079Y1660776I303J-1D01*
G01X240779D01*
G02X241082Y1660474I1J-302D01*
G01Y1650468D01*
G02X240779Y1650166I-303J1D01*
G01X237079D01*
G02X236776Y1650468I-1J302D01*
G01Y1660474D01*
G37*
G36*
G01X228902Y1656537D02*
G02X229205Y1656840I303J0D01*
G01X232905D01*
G02X233208Y1656537I0J-303D01*
G01Y1646531D01*
G02X232905Y1646228I-303J0D01*
G01X229205D01*
G02X228902Y1646531I0J303D01*
G01Y1656537D01*
G37*
G36*
G01X1553704Y90275D02*
G02X1553665Y90394I162J119D01*
G02X1553865Y90594I200J0D01*
G02X1554026Y90513I0J-201D01*
G01X1559094Y83689D01*
G02X1559133Y83570I-162J-119D01*
G02X1559052Y83409I-201J0D01*
G01X1556744Y81695D01*
G02X1556625Y81656I-119J162D01*
G02X1556464Y81737I0J201D01*
G01X1551396Y88561D01*
G02X1551357Y88680I162J119D01*
G02X1551557Y88880I200J0D01*
G02X1551718Y88799I0J-201D01*
G01X1556547Y82297D01*
G03X1556827Y82255I161J119D01*
G01X1557659Y82873D01*
X1557660Y82874D01*
X1558492Y83492D01*
G03X1558533Y83772I-119J160D01*
G01X1553704Y90275D01*
G37*
G36*
G01X1652546Y90578D02*
G02X1652497Y90709I151J131D01*
G02X1652697Y90909I200J0D01*
G02X1652848Y90840I0J-200D01*
G01X1658410Y84412D01*
G02X1658459Y84281I-151J-131D01*
G02X1658390Y84130I-200J0D01*
G01X1656216Y82250D01*
G02X1656085Y82201I-131J151D01*
G02X1655934Y82270I0J200D01*
G01X1650372Y88698D01*
G02X1650323Y88829I151J131D01*
G02X1650523Y89029I200J0D01*
G02X1650674Y88960I0J-200D01*
G01X1655974Y82834D01*
G03X1656256Y82814I151J131D01*
G01X1657041Y83492D01*
X1657825Y84170D01*
G03X1657846Y84452I-130J151D01*
G01X1652546Y90578D01*
G37*
G36*
G01X1574998Y90939D02*
G02X1575198Y91139I200J0D01*
G02X1575356Y91061I0J-199D01*
G01X1580543Y84327D01*
G02X1580585Y84205I-158J-123D01*
G02X1580507Y84047I-199J0D01*
G01X1578230Y82293D01*
G02X1578108Y82251I-123J158D01*
G02X1577950Y82329I0J199D01*
G01X1572763Y89063D01*
G02X1572721Y89185I158J123D01*
G02X1572921Y89385I200J0D01*
G02X1573079Y89307I0J-199D01*
G01X1578022Y82890D01*
G03X1578302Y82853I159J122D01*
G01X1579124Y83486D01*
X1579125D01*
X1579946Y84119D01*
G03X1579983Y84399I-122J159D01*
G01X1575040Y90817D01*
G02X1574998Y90939I158J123D01*
G37*
G36*
G01X1673694Y91421D02*
G02X1673643Y91554I148J133D01*
G02X1673843Y91754I200J0D01*
G02X1673992Y91687I0J-199D01*
G01X1679646Y85341D01*
G02X1679697Y85208I-148J-133D01*
G02X1679630Y85059I-199J0D01*
G01X1677484Y83147D01*
G02X1677351Y83096I-133J148D01*
G02X1677202Y83163I0J199D01*
G01X1671548Y89509D01*
G02X1671497Y89642I148J133D01*
G02X1671697Y89842I200J0D01*
G02X1671846Y89775I0J-199D01*
G01X1677234Y83727D01*
G03X1677516Y83711I149J133D01*
G01X1678291Y84401D01*
X1679065Y85091D01*
G03X1679082Y85373I-133J150D01*
G01X1673694Y91421D01*
G37*
G36*
G01X1595902Y91919D02*
G02X1595858Y92044I156J125D01*
G02X1596058Y92244I200J0D01*
G02X1596214Y92169I0J-200D01*
G01X1601513Y85523D01*
G02X1601557Y85398I-156J-125D01*
G02X1601482Y85242I-200J0D01*
G01X1599235Y83450D01*
G02X1599110Y83406I-125J156D01*
G02X1598954Y83481I0J200D01*
G01X1593655Y90127D01*
G02X1593611Y90252I156J125D01*
G02X1593811Y90452I200J0D01*
G02X1593967Y90377I0J-200D01*
G01X1599017Y84044D01*
G03X1599298Y84012I156J124D01*
G01X1600109Y84658D01*
Y84659D01*
X1600919Y85305D01*
G03X1600951Y85586I-124J156D01*
G01X1595902Y91919D01*
G37*
G36*
G01X1530115Y92852D02*
G02X1530078Y92968I163J116D01*
G02X1530278Y93168I200J0D01*
G02X1530441Y93084I0J-200D01*
G01X1535383Y86169D01*
G02X1535420Y86053I-163J-116D01*
G02X1535336Y85890I-200J0D01*
G01X1532998Y84219D01*
G02X1532882Y84182I-116J163D01*
G02X1532719Y84266I0J200D01*
G01X1527777Y91181D01*
G02X1527740Y91297I163J116D01*
G02X1527940Y91497I200J0D01*
G02X1528103Y91413I0J-200D01*
G01X1532812Y84824D01*
G03X1533091Y84777I163J116D01*
G01X1533934Y85380D01*
X1533935D01*
X1534778Y85983D01*
G03X1534824Y86262I-116J162D01*
G01X1530115Y92852D01*
G37*
G36*
G01X1615957Y94009D02*
G02X1616157Y94209I200J0D01*
G02X1616311Y94136I0J-199D01*
G01X1621715Y87575D01*
G02X1621761Y87448I-154J-128D01*
G02X1621688Y87294I-199J0D01*
G01X1619470Y85467D01*
G02X1619343Y85421I-128J154D01*
G02X1619189Y85494I0J199D01*
G01X1613785Y92055D01*
G02X1613739Y92182I154J128D01*
G02X1613939Y92382I200J0D01*
G02X1614093Y92309I0J-199D01*
G01X1619243Y86057D01*
G03X1619524Y86030I154J128D01*
G01X1620324Y86689D01*
X1620325D01*
X1621124Y87348D01*
G03X1621152Y87629I-127J155D01*
G01X1616003Y93882D01*
G02X1615957Y94009I154J128D01*
G37*
G36*
G01X1539594Y94775D02*
Y94776D01*
G02X1539794Y94976I200J0D01*
G02X1539956Y94894I0J-201D01*
G01X1544962Y88024D01*
G02X1545000Y87907I-162J-117D01*
G01Y87906D01*
G02X1544918Y87744I-201J0D01*
G01X1542596Y86052D01*
G02X1542479Y86014I-117J162D01*
G01X1542478D01*
G02X1542316Y86096I0J201D01*
G01X1537310Y92966D01*
G02X1537272Y93083I162J117D01*
G01Y93084D01*
G02X1537472Y93284I200J0D01*
G02X1537634Y93202I0J-201D01*
G01X1542404Y86655D01*
X1542453Y86587D01*
X1542616Y86562D01*
X1544359Y87832D01*
X1544427Y87881D01*
X1544452Y88044D01*
X1539632Y94658D01*
G02X1539594Y94775I162J117D01*
G37*
G36*
G01X1690696Y95048D02*
G02X1690644Y95183I149J135D01*
G02X1690844Y95383I200J0D01*
G02X1690992Y95318I0J-201D01*
G01X1696720Y89038D01*
G02X1696772Y88903I-149J-135D01*
G02X1696707Y88755I-201J0D01*
G01X1694583Y86819D01*
G02X1694448Y86767I-135J149D01*
G02X1694300Y86832I0J201D01*
G01X1688572Y93112D01*
G02X1688520Y93247I149J135D01*
G02X1688720Y93447I200J0D01*
G02X1688868Y93382I0J-201D01*
G01X1694382Y87335D01*
X1694548Y87328D01*
X1694609Y87384D01*
X1696203Y88837D01*
X1696210Y89003D01*
X1696154Y89064D01*
X1690696Y95048D01*
G37*
G36*
G01X1558471Y98002D02*
G02X1558671Y98202I200J0D01*
G01X1558672D01*
G02X1558831Y98123I0J-200D01*
G01X1563956Y91342D01*
G02X1563996Y91222I-160J-120D01*
G01Y91221D01*
Y91220D01*
G02X1563917Y91061I-200J0D01*
G01X1561624Y89328D01*
G02X1561504Y89288I-120J160D01*
G01X1561503D01*
X1561502D01*
G02X1561343Y89367I0J200D01*
G01X1556218Y96148D01*
G02X1556178Y96268I160J120D01*
G01Y96269D01*
G02X1556378Y96469I200J0D01*
G01X1556379D01*
G02X1556538Y96390I0J-200D01*
G01X1561472Y89861D01*
X1561635Y89838D01*
X1561702Y89889D01*
X1563423Y91190D01*
X1563446Y91353D01*
X1563395Y91420D01*
X1558511Y97881D01*
G02X1558471Y98001I160J120D01*
G01Y98002D01*
G37*
G36*
G01X1656898Y98015D02*
G02X1656848Y98147I149J132D01*
G02X1657048Y98347I200J0D01*
G02X1657198Y98279I0J-199D01*
G01X1662807Y91892D01*
G02X1662857Y91760I-149J-132D01*
G02X1662789Y91610I-199J0D01*
G01X1660630Y89713D01*
G02X1660498Y89663I-132J149D01*
G02X1660348Y89731I0J199D01*
G01X1654739Y96118D01*
G02X1654689Y96250I149J132D01*
G02X1654889Y96450I200J0D01*
G02X1655039Y96382I0J-199D01*
G01X1660384Y90295D01*
G03X1660666Y90277I150J132D01*
G01X1661445Y90961D01*
X1661446Y90962D01*
X1662225Y91646D01*
G03X1662243Y91928I-132J150D01*
G01X1656898Y98015D01*
G37*
G36*
G01X1624495Y98065D02*
G02X1624448Y98194I154J129D01*
G02X1624648Y98394I200J0D01*
G02X1624801Y98323I0J-200D01*
G01X1630267Y91813D01*
G02X1630314Y91684I-154J-129D01*
G02X1630243Y91531I-200J0D01*
G01X1628043Y89683D01*
G02X1627914Y89636I-129J154D01*
G02X1627761Y89707I0J200D01*
G01X1622295Y96217D01*
G02X1622248Y96346I154J129D01*
G02X1622448Y96546I200J0D01*
G02X1622601Y96475I0J-200D01*
G01X1627810Y90271D01*
G03X1628092Y90247I153J129D01*
G01X1628885Y90913D01*
X1628886Y90914D01*
X1629679Y91580D01*
G03X1629703Y91862I-129J153D01*
G01X1624495Y98065D01*
G37*
G36*
G01X1580139Y98246D02*
G02X1580339Y98446I200J0D01*
G02X1580496Y98369I-1J-200D01*
G01X1585740Y91680D01*
G02X1585783Y91557I-157J-124D01*
G02X1585706Y91400I-200J1D01*
G01X1583444Y89627D01*
G02X1583321Y89584I-124J157D01*
G02X1583164Y89661I1J200D01*
G01X1577920Y96350D01*
G02X1577877Y96473I157J124D01*
G02X1578077Y96673I200J0D01*
G02X1578234Y96596I-1J-200D01*
G01X1583232Y90222D01*
G03X1583512Y90188I157J124D01*
G01X1585145Y91468D01*
G03X1585179Y91748I-124J157D01*
G01X1580182Y98123D01*
G02X1580139Y98246I157J124D01*
G37*
G36*
G01X1682741Y93437D02*
X1677313Y99448D01*
G02X1677261Y99582I147J134D01*
G02X1677461Y99782I200J0D01*
G02X1677609Y99716I0J-199D01*
G01X1683306Y93408D01*
G02X1683358Y93274I-147J-134D01*
G02X1683292Y93126I-199J0D01*
G01X1681159Y91200D01*
G02X1681025Y91148I-134J147D01*
G02X1680877Y91214I0J199D01*
G01X1675180Y97522D01*
G02X1675128Y97656I147J134D01*
G02X1675328Y97856I200J0D01*
G02X1675476Y97790I0J-199D01*
G01X1680905Y91779D01*
G03X1681187Y91764I149J134D01*
G01X1682727Y93154D01*
G03X1682741Y93437I-134J148D01*
G37*
G36*
G01X1604812Y94322D02*
X1599711Y100615D01*
G02X1599666Y100741I154J126D01*
G02X1599866Y100941I200J0D01*
G02X1600021Y100867I0J-199D01*
G01X1605374Y94264D01*
G02X1605419Y94138I-154J-126D01*
G02X1605345Y93983I-199J0D01*
G01X1603112Y92174D01*
G02X1602986Y92129I-126J154D01*
G02X1602831Y92203I0J199D01*
G01X1597478Y98806D01*
G02X1597433Y98932I154J126D01*
G02X1597633Y99132I200J0D01*
G02X1597788Y99058I0J-199D01*
G01X1602889Y92766D01*
G03X1603170Y92736I156J126D01*
G01X1604782Y94041D01*
G03X1604812Y94322I-126J156D01*
G37*
G36*
G01X186968Y1530801D02*
G02X187102Y1531189I1187J-193D01*
G01X188666Y1533895D01*
X188667Y1533898D01*
G02X189730Y1534538I1063J-563D01*
G02X190932Y1533336I0J-1202D01*
G01Y1533335D01*
G02X190779Y1532748I-1202J0D01*
G01X190774Y1532738D01*
X190773D01*
X190772Y1532736D01*
X189229Y1530066D01*
X189227Y1530061D01*
G02X186968Y1530800I-1072J545D01*
G01Y1530801D01*
G37*
G36*
G01X191692D02*
G02X191826Y1531189I1187J-193D01*
G01X193390Y1533895D01*
X193391Y1533898D01*
G02X194454Y1534538I1063J-563D01*
G02X195656Y1533336I0J-1202D01*
G01Y1533335D01*
G02X195503Y1532748I-1202J0D01*
G01X195498Y1532738D01*
X195497D01*
X195496Y1532736D01*
X193953Y1530066D01*
X193951Y1530061D01*
G02X191692Y1530800I-1072J545D01*
G01Y1530801D01*
G37*
G36*
G01X196416D02*
G02X196550Y1531189I1187J-193D01*
G01X198114Y1533895D01*
X198115Y1533898D01*
G02X199178Y1534538I1063J-563D01*
G02X200380Y1533336I0J-1202D01*
G01Y1533335D01*
G02X200227Y1532748I-1202J0D01*
G01X200222Y1532738D01*
X200221D01*
X200220Y1532736D01*
X198677Y1530066D01*
X198675Y1530061D01*
G02X196416Y1530800I-1072J545D01*
G01Y1530801D01*
G37*
G36*
G01X201141D02*
G02X201275Y1531189I1187J-193D01*
G01X202839Y1533895D01*
X202840Y1533898D01*
G02X203903Y1534538I1063J-563D01*
G02X205106Y1533336I1J-1202D01*
G01Y1533335D01*
G02X204952Y1532748I-1203J2D01*
G01X204947Y1532738D01*
X204946D01*
X204945Y1532736D01*
X203402Y1530066D01*
X203400Y1530061D01*
G02X201141Y1530800I-1072J545D01*
G01Y1530801D01*
G37*
G36*
G01X205865D02*
G02X205999Y1531189I1187J-193D01*
G01X207563Y1533895D01*
X207564Y1533898D01*
G02X208627Y1534538I1063J-563D01*
G02X209830Y1533336I1J-1202D01*
G01Y1533335D01*
G02X209676Y1532748I-1203J2D01*
G01X209671Y1532738D01*
X209670D01*
X209669Y1532736D01*
X208126Y1530066D01*
X208124Y1530061D01*
G02X205865Y1530800I-1072J545D01*
G01Y1530801D01*
G37*
G36*
G01X210590D02*
G02X210724Y1531189I1187J-193D01*
G01X212288Y1533895D01*
X212289Y1533898D01*
G02X213352Y1534538I1063J-563D01*
G02X214554Y1533336I0J-1202D01*
G01Y1533335D01*
G02X214401Y1532748I-1202J0D01*
G01X214396Y1532738D01*
X214395D01*
X214394Y1532736D01*
X212851Y1530066D01*
X212849Y1530061D01*
G02X210590Y1530800I-1072J545D01*
G01Y1530801D01*
G37*
G36*
G01X215314D02*
G02X215448Y1531189I1187J-193D01*
G01X217012Y1533895D01*
X217013Y1533898D01*
G02X218076Y1534538I1063J-563D01*
G02X219278Y1533336I0J-1202D01*
G01Y1533335D01*
G02X219125Y1532748I-1202J0D01*
G01X219120Y1532738D01*
X219119D01*
X219118Y1532736D01*
X217575Y1530066D01*
X217573Y1530061D01*
G02X215314Y1530800I-1072J545D01*
G01Y1530801D01*
G37*
G36*
G01X220038D02*
G02X220172Y1531189I1187J-193D01*
G01X221736Y1533895D01*
X221737Y1533898D01*
G02X222800Y1534538I1063J-563D01*
G02X224002Y1533336I0J-1202D01*
G01Y1533335D01*
G02X223849Y1532748I-1202J0D01*
G01X223844Y1532738D01*
X223843D01*
X223842Y1532736D01*
X222299Y1530066D01*
X222297Y1530061D01*
G02X220038Y1530800I-1072J545D01*
G01Y1530801D01*
G37*
G36*
G01X224763D02*
G02X224897Y1531189I1187J-193D01*
G01X226461Y1533895D01*
X226462Y1533898D01*
G02X227525Y1534538I1063J-563D01*
G02X228728Y1533336I1J-1202D01*
G01Y1533335D01*
G02X228574Y1532748I-1203J2D01*
G01X228569Y1532738D01*
X228568D01*
X228567Y1532736D01*
X227024Y1530066D01*
X227022Y1530061D01*
G02X224763Y1530800I-1072J545D01*
G01Y1530801D01*
G37*
G36*
G01X229487D02*
G02X229621Y1531189I1187J-193D01*
G01X231185Y1533895D01*
X231186Y1533898D01*
G02X232249Y1534538I1063J-563D01*
G02X233452Y1533336I1J-1202D01*
G01Y1533335D01*
G02X233298Y1532748I-1203J2D01*
G01X233293Y1532738D01*
X233292D01*
X233291Y1532736D01*
X231748Y1530066D01*
X231746Y1530061D01*
G02X229487Y1530800I-1072J545D01*
G01Y1530801D01*
G37*
G36*
G01X234212D02*
G02X234346Y1531189I1187J-193D01*
G01X235910Y1533895D01*
X235911Y1533898D01*
G02X236974Y1534538I1063J-563D01*
G02X238176Y1533336I0J-1202D01*
G01Y1533335D01*
G02X238023Y1532748I-1202J0D01*
G01X238018Y1532738D01*
X238017D01*
X238016Y1532736D01*
X236473Y1530066D01*
X236471Y1530061D01*
G02X234212Y1530800I-1072J545D01*
G01Y1530801D01*
G37*
G36*
G01X238936D02*
G02X239070Y1531189I1187J-193D01*
G01X240634Y1533895D01*
X240635Y1533898D01*
G02X241698Y1534538I1063J-563D01*
G02X242900Y1533336I0J-1202D01*
G01Y1533335D01*
G02X242747Y1532748I-1202J0D01*
G01X242742Y1532738D01*
X242741D01*
X242740Y1532736D01*
X241197Y1530066D01*
X241195Y1530061D01*
G02X238936Y1530800I-1072J545D01*
G01Y1530801D01*
G37*
G36*
G01X243660D02*
G02X243794Y1531189I1187J-193D01*
G01X245358Y1533895D01*
X245359Y1533898D01*
G02X246422Y1534538I1063J-563D01*
G02X247624Y1533336I0J-1202D01*
G01Y1533335D01*
G02X247471Y1532748I-1202J0D01*
G01X247466Y1532738D01*
X247465D01*
X247464Y1532736D01*
X245921Y1530066D01*
X245919Y1530061D01*
G02X243660Y1530800I-1072J545D01*
G01Y1530801D01*
G37*
G36*
G01X248385D02*
G02X248519Y1531189I1187J-193D01*
G01X250083Y1533895D01*
X250084Y1533898D01*
G02X251147Y1534538I1063J-563D01*
G02X252350Y1533336I1J-1202D01*
G01Y1533335D01*
G02X252196Y1532748I-1203J2D01*
G01X252191Y1532738D01*
X252190D01*
X252189Y1532736D01*
X250646Y1530066D01*
X250644Y1530061D01*
G02X248385Y1530800I-1072J545D01*
G01Y1530801D01*
G37*
G36*
G01X253109D02*
G02X253243Y1531189I1187J-193D01*
G01X254807Y1533895D01*
X254808Y1533898D01*
G02X255871Y1534538I1063J-563D01*
G02X257074Y1533336I1J-1202D01*
G01Y1533335D01*
G02X256920Y1532748I-1203J2D01*
G01X256915Y1532738D01*
X256914D01*
X256913Y1532736D01*
X255370Y1530066D01*
X255368Y1530061D01*
G02X253109Y1530800I-1072J545D01*
G01Y1530801D01*
G37*
G36*
G01X257834D02*
G02X257968Y1531189I1187J-193D01*
G01X259532Y1533895D01*
X259533Y1533898D01*
G02X260596Y1534538I1063J-563D01*
G02X261798Y1533336I0J-1202D01*
G01Y1533335D01*
G02X261645Y1532748I-1202J0D01*
G01X261640Y1532738D01*
X261639D01*
X261638Y1532736D01*
X260095Y1530066D01*
X260093Y1530061D01*
G02X257834Y1530800I-1072J545D01*
G01Y1530801D01*
G37*
G36*
G01X315030D02*
G02X315164Y1531189I1187J-193D01*
G01X316728Y1533895D01*
X316729Y1533898D01*
G02X317792Y1534538I1063J-563D01*
G02X318994Y1533336I0J-1202D01*
G01Y1533335D01*
G02X318841Y1532748I-1202J0D01*
G01X318836Y1532738D01*
X318835D01*
X318834Y1532736D01*
X317291Y1530066D01*
X317289Y1530061D01*
G02X315030Y1530800I-1072J545D01*
G01Y1530801D01*
G37*
G36*
G01X319754D02*
G02X319888Y1531189I1187J-193D01*
G01X321452Y1533895D01*
X321453Y1533898D01*
G02X322516Y1534538I1063J-563D01*
G02X323718Y1533336I0J-1202D01*
G01Y1533335D01*
G02X323565Y1532748I-1202J0D01*
G01X323560Y1532738D01*
X323559D01*
X323558Y1532736D01*
X322015Y1530066D01*
X322013Y1530061D01*
G02X319754Y1530800I-1072J545D01*
G01Y1530801D01*
G37*
G36*
G01X324478D02*
G02X324612Y1531189I1187J-193D01*
G01X326176Y1533895D01*
X326177Y1533898D01*
G02X327240Y1534538I1063J-563D01*
G02X328442Y1533336I0J-1202D01*
G01Y1533335D01*
G02X328289Y1532748I-1202J0D01*
G01X328284Y1532738D01*
X328283D01*
X328282Y1532736D01*
X326739Y1530066D01*
X326737Y1530061D01*
G02X324478Y1530800I-1072J545D01*
G01Y1530801D01*
G37*
G36*
G01X329203D02*
G02X329337Y1531189I1187J-193D01*
G01X330901Y1533895D01*
X330902Y1533898D01*
G02X331965Y1534538I1063J-563D01*
G02X333168Y1533336I1J-1202D01*
G01Y1533335D01*
G02X333014Y1532748I-1203J2D01*
G01X333009Y1532738D01*
X333008D01*
X333007Y1532736D01*
X331464Y1530066D01*
X331462Y1530061D01*
G02X329203Y1530800I-1072J545D01*
G01Y1530801D01*
G37*
G36*
G01X333927D02*
G02X334061Y1531189I1187J-193D01*
G01X335625Y1533895D01*
X335626Y1533898D01*
G02X336689Y1534538I1063J-563D01*
G02X337892Y1533336I1J-1202D01*
G01Y1533335D01*
G02X337738Y1532748I-1203J2D01*
G01X337733Y1532738D01*
X337732D01*
X337731Y1532736D01*
X336188Y1530066D01*
X336186Y1530061D01*
G02X333927Y1530800I-1072J545D01*
G01Y1530801D01*
G37*
G36*
G01X338652D02*
G02X338786Y1531189I1187J-193D01*
G01X340350Y1533895D01*
X340351Y1533898D01*
G02X341414Y1534538I1063J-563D01*
G02X342616Y1533336I0J-1202D01*
G01Y1533335D01*
G02X342463Y1532748I-1202J0D01*
G01X342458Y1532738D01*
X342457D01*
X342456Y1532736D01*
X340913Y1530066D01*
X340911Y1530061D01*
G02X338652Y1530800I-1072J545D01*
G01Y1530801D01*
G37*
G36*
G01X343376D02*
G02X343510Y1531189I1187J-193D01*
G01X345074Y1533895D01*
X345075Y1533898D01*
G02X346138Y1534538I1063J-563D01*
G02X347340Y1533336I0J-1202D01*
G01Y1533335D01*
G02X347187Y1532748I-1202J0D01*
G01X347182Y1532738D01*
X347181D01*
X347180Y1532736D01*
X345637Y1530066D01*
X345635Y1530061D01*
G02X343376Y1530800I-1072J545D01*
G01Y1530801D01*
G37*
G36*
G01X348100D02*
G02X348234Y1531189I1187J-193D01*
G01X349798Y1533895D01*
X349799Y1533898D01*
G02X350862Y1534538I1063J-563D01*
G02X352064Y1533336I0J-1202D01*
G01Y1533335D01*
G02X351911Y1532748I-1202J0D01*
G01X351906Y1532738D01*
X351905D01*
X351904Y1532736D01*
X350361Y1530066D01*
X350359Y1530061D01*
G02X348100Y1530800I-1072J545D01*
G01Y1530801D01*
G37*
G36*
G01X352825D02*
G02X352959Y1531189I1187J-193D01*
G01X354523Y1533895D01*
X354524Y1533898D01*
G02X355587Y1534538I1063J-563D01*
G02X356790Y1533336I1J-1202D01*
G01Y1533335D01*
G02X356636Y1532748I-1203J2D01*
G01X356631Y1532738D01*
X356630D01*
X356629Y1532736D01*
X355086Y1530066D01*
X355084Y1530061D01*
G02X352825Y1530800I-1072J545D01*
G01Y1530801D01*
G37*
G36*
G01X357549D02*
G02X357683Y1531189I1187J-193D01*
G01X359247Y1533895D01*
X359248Y1533898D01*
G02X360311Y1534538I1063J-563D01*
G02X361514Y1533336I1J-1202D01*
G01Y1533335D01*
G02X361360Y1532748I-1203J2D01*
G01X361355Y1532738D01*
X361354D01*
X361353Y1532736D01*
X359810Y1530066D01*
X359808Y1530061D01*
G02X357549Y1530800I-1072J545D01*
G01Y1530801D01*
G37*
G36*
G01X362274D02*
G02X362408Y1531189I1187J-193D01*
G01X363972Y1533895D01*
X363973Y1533898D01*
G02X365036Y1534538I1063J-563D01*
G02X366238Y1533336I0J-1202D01*
G01Y1533335D01*
G02X366085Y1532748I-1202J0D01*
G01X366080Y1532738D01*
X366079D01*
X366078Y1532736D01*
X364535Y1530066D01*
X364533Y1530061D01*
G02X362274Y1530800I-1072J545D01*
G01Y1530801D01*
G37*
G36*
G01X366998D02*
G02X367132Y1531189I1187J-193D01*
G01X368696Y1533895D01*
X368697Y1533898D01*
G02X369760Y1534538I1063J-563D01*
G02X370962Y1533336I0J-1202D01*
G01Y1533335D01*
G02X370809Y1532748I-1202J0D01*
G01X370804Y1532738D01*
X370803D01*
X370802Y1532736D01*
X369259Y1530066D01*
X369257Y1530061D01*
G02X366998Y1530800I-1072J545D01*
G01Y1530801D01*
G37*
G36*
G01X371722D02*
G02X371856Y1531189I1187J-193D01*
G01X373420Y1533895D01*
X373421Y1533898D01*
G02X374484Y1534538I1063J-563D01*
G02X375686Y1533336I0J-1202D01*
G01Y1533335D01*
G02X375533Y1532748I-1202J0D01*
G01X375528Y1532738D01*
X375527D01*
X375526Y1532736D01*
X373983Y1530066D01*
X373981Y1530061D01*
G02X371722Y1530800I-1072J545D01*
G01Y1530801D01*
G37*
G36*
G01X376447D02*
G02X376581Y1531189I1187J-193D01*
G01X378145Y1533895D01*
X378146Y1533898D01*
G02X379209Y1534538I1063J-563D01*
G02X380412Y1533336I1J-1202D01*
G01Y1533335D01*
G02X380258Y1532748I-1203J2D01*
G01X380253Y1532738D01*
X380252D01*
X380251Y1532736D01*
X378708Y1530066D01*
X378706Y1530061D01*
G02X376447Y1530800I-1072J545D01*
G01Y1530801D01*
G37*
G36*
G01X381171D02*
G02X381305Y1531189I1187J-193D01*
G01X382869Y1533895D01*
X382870Y1533898D01*
G02X383933Y1534538I1063J-563D01*
G02X385136Y1533336I1J-1202D01*
G01Y1533335D01*
G02X384982Y1532748I-1203J2D01*
G01X384977Y1532738D01*
X384976D01*
X384975Y1532736D01*
X383432Y1530066D01*
X383430Y1530061D01*
G02X381171Y1530800I-1072J545D01*
G01Y1530801D01*
G37*
G36*
G01X385896D02*
G02X386030Y1531189I1187J-193D01*
G01X387594Y1533895D01*
X387595Y1533898D01*
G02X388658Y1534538I1063J-563D01*
G02X389860Y1533336I0J-1202D01*
G01Y1533335D01*
G02X389707Y1532748I-1202J0D01*
G01X389702Y1532738D01*
X389701D01*
X389700Y1532736D01*
X388157Y1530066D01*
X388155Y1530061D01*
G02X385896Y1530800I-1072J545D01*
G01Y1530801D01*
G37*
G36*
G01X451141D02*
G02X451275Y1531189I1187J-193D01*
G01X452839Y1533895D01*
X452840Y1533898D01*
G02X453903Y1534538I1063J-563D01*
G02X455106Y1533336I1J-1202D01*
G01Y1533335D01*
G02X454952Y1532748I-1203J2D01*
G01X454947Y1532738D01*
X454946D01*
X454945Y1532736D01*
X453402Y1530066D01*
X453400Y1530061D01*
G02X451141Y1530800I-1072J545D01*
G01Y1530801D01*
G37*
G36*
G01X455865D02*
G02X455999Y1531189I1187J-193D01*
G01X457563Y1533895D01*
X457564Y1533898D01*
G02X458627Y1534538I1063J-563D01*
G02X459830Y1533336I1J-1202D01*
G01Y1533335D01*
G02X459676Y1532748I-1203J2D01*
G01X459671Y1532738D01*
X459670D01*
X459669Y1532736D01*
X458126Y1530066D01*
X458124Y1530061D01*
G02X455865Y1530800I-1072J545D01*
G01Y1530801D01*
G37*
G36*
G01X460589D02*
G02X460723Y1531189I1187J-193D01*
G01X462287Y1533895D01*
X462288Y1533898D01*
G02X463351Y1534538I1063J-563D01*
G02X464554Y1533336I1J-1202D01*
G01Y1533335D01*
G02X464400Y1532748I-1203J2D01*
G01X464395Y1532738D01*
X464394D01*
X464393Y1532736D01*
X462850Y1530066D01*
X462848Y1530061D01*
G02X460589Y1530800I-1072J545D01*
G01Y1530801D01*
G37*
G36*
G01X465314D02*
G02X465448Y1531189I1187J-193D01*
G01X467012Y1533895D01*
X467013Y1533898D01*
G02X468076Y1534538I1063J-563D01*
G02X469278Y1533336I0J-1202D01*
G01Y1533335D01*
G02X469125Y1532748I-1202J0D01*
G01X469120Y1532738D01*
X469119D01*
X469118Y1532736D01*
X467575Y1530066D01*
X467573Y1530061D01*
G02X465314Y1530800I-1072J545D01*
G01Y1530801D01*
G37*
G36*
G01X470038D02*
G02X470172Y1531189I1187J-193D01*
G01X471736Y1533895D01*
X471737Y1533898D01*
G02X472800Y1534538I1063J-563D01*
G02X474002Y1533336I0J-1202D01*
G01Y1533335D01*
G02X473849Y1532748I-1202J0D01*
G01X473844Y1532738D01*
X473843D01*
X473842Y1532736D01*
X472299Y1530066D01*
X472297Y1530061D01*
G02X470038Y1530800I-1072J545D01*
G01Y1530801D01*
G37*
G36*
G01X474763D02*
G02X474897Y1531189I1187J-193D01*
G01X476461Y1533895D01*
X476462Y1533898D01*
G02X477525Y1534538I1063J-563D01*
G02X478728Y1533336I1J-1202D01*
G01Y1533335D01*
G02X478574Y1532748I-1203J2D01*
G01X478569Y1532738D01*
X478568D01*
X478567Y1532736D01*
X477024Y1530066D01*
X477022Y1530061D01*
G02X474763Y1530800I-1072J545D01*
G01Y1530801D01*
G37*
G36*
G01X479487D02*
G02X479621Y1531189I1187J-193D01*
G01X481185Y1533895D01*
X481186Y1533898D01*
G02X482249Y1534538I1063J-563D01*
G02X483452Y1533336I1J-1202D01*
G01Y1533335D01*
G02X483298Y1532748I-1203J2D01*
G01X483293Y1532738D01*
X483292D01*
X483291Y1532736D01*
X481748Y1530066D01*
X481746Y1530061D01*
G02X479487Y1530800I-1072J545D01*
G01Y1530801D01*
G37*
G36*
G01X484211D02*
G02X484345Y1531189I1187J-193D01*
G01X485909Y1533895D01*
X485910Y1533898D01*
G02X486973Y1534538I1063J-563D01*
G02X488176Y1533336I1J-1202D01*
G01Y1533335D01*
G02X488022Y1532748I-1203J2D01*
G01X488017Y1532738D01*
X488016D01*
X488015Y1532736D01*
X486472Y1530066D01*
X486470Y1530061D01*
G02X484211Y1530800I-1072J545D01*
G01Y1530801D01*
G37*
G36*
G01X488936D02*
G02X489070Y1531189I1187J-193D01*
G01X490634Y1533895D01*
X490635Y1533898D01*
G02X491698Y1534538I1063J-563D01*
G02X492900Y1533336I0J-1202D01*
G01Y1533335D01*
G02X492747Y1532748I-1202J0D01*
G01X492742Y1532738D01*
X492741D01*
X492740Y1532736D01*
X491197Y1530066D01*
X491195Y1530061D01*
G02X488936Y1530800I-1072J545D01*
G01Y1530801D01*
G37*
G36*
G01X493660D02*
G02X493794Y1531189I1187J-193D01*
G01X495358Y1533895D01*
X495359Y1533898D01*
G02X496422Y1534538I1063J-563D01*
G02X497624Y1533336I0J-1202D01*
G01Y1533335D01*
G02X497471Y1532748I-1202J0D01*
G01X497466Y1532738D01*
X497465D01*
X497464Y1532736D01*
X495921Y1530066D01*
X495919Y1530061D01*
G02X493660Y1530800I-1072J545D01*
G01Y1530801D01*
G37*
G36*
G01X498385D02*
G02X498519Y1531189I1187J-193D01*
G01X500083Y1533895D01*
X500084Y1533898D01*
G02X501147Y1534538I1063J-563D01*
G02X502350Y1533336I1J-1202D01*
G01Y1533335D01*
G02X502196Y1532748I-1203J2D01*
G01X502191Y1532738D01*
X502190D01*
X502189Y1532736D01*
X500646Y1530066D01*
X500644Y1530061D01*
G02X498385Y1530800I-1072J545D01*
G01Y1530801D01*
G37*
G36*
G01X503109D02*
G02X503243Y1531189I1187J-193D01*
G01X504807Y1533895D01*
X504808Y1533898D01*
G02X505871Y1534538I1063J-563D01*
G02X507074Y1533336I1J-1202D01*
G01Y1533335D01*
G02X506920Y1532748I-1203J2D01*
G01X506915Y1532738D01*
X506914D01*
X506913Y1532736D01*
X505370Y1530066D01*
X505368Y1530061D01*
G02X503109Y1530800I-1072J545D01*
G01Y1530801D01*
G37*
G36*
G01X507833D02*
G02X507967Y1531189I1187J-193D01*
G01X509531Y1533895D01*
X509532Y1533898D01*
G02X510595Y1534538I1063J-563D01*
G02X511798Y1533336I1J-1202D01*
G01Y1533335D01*
G02X511644Y1532748I-1203J2D01*
G01X511639Y1532738D01*
X511638D01*
X511637Y1532736D01*
X510094Y1530066D01*
X510092Y1530061D01*
G02X507833Y1530800I-1072J545D01*
G01Y1530801D01*
G37*
G36*
G01X512558D02*
G02X512692Y1531189I1187J-193D01*
G01X514256Y1533895D01*
X514257Y1533898D01*
G02X515320Y1534538I1063J-563D01*
G02X516522Y1533336I0J-1202D01*
G01Y1533335D01*
G02X516369Y1532748I-1202J0D01*
G01X516364Y1532738D01*
X516363D01*
X516362Y1532736D01*
X514819Y1530066D01*
X514817Y1530061D01*
G02X512558Y1530800I-1072J545D01*
G01Y1530801D01*
G37*
G36*
G01X517282D02*
G02X517416Y1531189I1187J-193D01*
G01X518980Y1533895D01*
X518981Y1533898D01*
G02X520044Y1534538I1063J-563D01*
G02X521246Y1533336I0J-1202D01*
G01Y1533335D01*
G02X521093Y1532748I-1202J0D01*
G01X521088Y1532738D01*
X521087D01*
X521086Y1532736D01*
X519543Y1530066D01*
X519541Y1530061D01*
G02X517282Y1530800I-1072J545D01*
G01Y1530801D01*
G37*
G36*
G01X522007D02*
G02X522141Y1531189I1187J-193D01*
G01X523705Y1533895D01*
X523706Y1533898D01*
G02X524769Y1534538I1063J-563D01*
G02X525972Y1533336I1J-1202D01*
G01Y1533335D01*
G02X525818Y1532748I-1203J2D01*
G01X525813Y1532738D01*
X525812D01*
X525811Y1532736D01*
X524268Y1530066D01*
X524266Y1530061D01*
G02X522007Y1530800I-1072J545D01*
G01Y1530801D01*
G37*
G36*
G01X579203D02*
G02X579337Y1531189I1187J-193D01*
G01X580901Y1533895D01*
X580902Y1533898D01*
G02X581965Y1534538I1063J-563D01*
G02X583168Y1533336I1J-1202D01*
G01Y1533335D01*
G02X583014Y1532748I-1203J2D01*
G01X583009Y1532738D01*
X583008D01*
X583007Y1532736D01*
X581464Y1530066D01*
X581462Y1530061D01*
G02X579203Y1530800I-1072J545D01*
G01Y1530801D01*
G37*
G36*
G01X583927D02*
G02X584061Y1531189I1187J-193D01*
G01X585625Y1533895D01*
X585626Y1533898D01*
G02X586689Y1534538I1063J-563D01*
G02X587892Y1533336I1J-1202D01*
G01Y1533335D01*
G02X587738Y1532748I-1203J2D01*
G01X587733Y1532738D01*
X587732D01*
X587731Y1532736D01*
X586188Y1530066D01*
X586186Y1530061D01*
G02X583927Y1530800I-1072J545D01*
G01Y1530801D01*
G37*
G36*
G01X590353Y1533902D02*
G02X591413Y1534538I1060J-565D01*
G01X591414D01*
G02X592616Y1533336I0J-1202D01*
G01Y1533335D01*
G02X592463Y1532748I-1202J0D01*
G01X592386Y1532616D01*
G03X592385Y1532614I178J-90D01*
G01X590919Y1530078D01*
X590916Y1530072D01*
G02X588777Y1530042I-1077J535D01*
G01Y1530043D01*
G02X588636Y1530608I1062J565D01*
G01Y1530610D01*
G02X588785Y1531189I1202J-1D01*
G01X590351Y1533899D01*
X590353Y1533902D01*
G37*
G36*
G01X593376Y1530801D02*
G02X593510Y1531189I1187J-193D01*
G01X595074Y1533895D01*
X595075Y1533898D01*
G02X596138Y1534538I1063J-563D01*
G02X597340Y1533336I0J-1202D01*
G01Y1533335D01*
G02X597187Y1532748I-1202J0D01*
G01X597182Y1532738D01*
X597181D01*
X597180Y1532736D01*
X595637Y1530066D01*
X595635Y1530061D01*
G02X593376Y1530800I-1072J545D01*
G01Y1530801D01*
G37*
G36*
G01X598100D02*
G02X598234Y1531189I1187J-193D01*
G01X599798Y1533895D01*
X599799Y1533898D01*
G02X600862Y1534538I1063J-563D01*
G02X602064Y1533336I0J-1202D01*
G01Y1533335D01*
G02X601911Y1532748I-1202J0D01*
G01X601906Y1532738D01*
X601905D01*
X601904Y1532736D01*
X600361Y1530066D01*
X600359Y1530061D01*
G02X598100Y1530800I-1072J545D01*
G01Y1530801D01*
G37*
G36*
G01X602825D02*
G02X602959Y1531189I1187J-193D01*
G01X604523Y1533895D01*
X604524Y1533898D01*
G02X605587Y1534538I1063J-563D01*
G02X606790Y1533336I1J-1202D01*
G01Y1533335D01*
G02X606636Y1532748I-1203J2D01*
G01X606631Y1532738D01*
X606630D01*
X606629Y1532736D01*
X605086Y1530066D01*
X605084Y1530061D01*
G02X602825Y1530800I-1072J545D01*
G01Y1530801D01*
G37*
G36*
G01X607549D02*
G02X607683Y1531189I1187J-193D01*
G01X609247Y1533895D01*
X609248Y1533898D01*
G02X610311Y1534538I1063J-563D01*
G02X611514Y1533336I1J-1202D01*
G01Y1533335D01*
G02X611360Y1532748I-1203J2D01*
G01X611355Y1532738D01*
X611354D01*
X611353Y1532736D01*
X609810Y1530066D01*
X609808Y1530061D01*
G02X607549Y1530800I-1072J545D01*
G01Y1530801D01*
G37*
G36*
G01X613975Y1533902D02*
G02X615035Y1534538I1060J-565D01*
G01X615036D01*
G02X616238Y1533336I0J-1202D01*
G01Y1533335D01*
G02X616085Y1532748I-1202J0D01*
G01X616008Y1532616D01*
G03X616007Y1532614I178J-90D01*
G01X614541Y1530078D01*
X614538Y1530072D01*
G02X612399Y1530042I-1077J535D01*
G01Y1530043D01*
G02X612258Y1530608I1062J565D01*
G01Y1530610D01*
G02X612407Y1531189I1202J-1D01*
G01X613973Y1533899D01*
X613975Y1533902D01*
G37*
G36*
G01X616998Y1530801D02*
G02X617132Y1531189I1187J-193D01*
G01X618696Y1533895D01*
X618697Y1533898D01*
G02X619760Y1534538I1063J-563D01*
G02X620962Y1533336I0J-1202D01*
G01Y1533335D01*
G02X620809Y1532748I-1202J0D01*
G01X620804Y1532738D01*
X620803D01*
X620802Y1532736D01*
X619259Y1530066D01*
X619257Y1530061D01*
G02X616998Y1530800I-1072J545D01*
G01Y1530801D01*
G37*
G36*
G01X621722D02*
G02X621856Y1531189I1187J-193D01*
G01X623420Y1533895D01*
X623421Y1533898D01*
G02X624484Y1534538I1063J-563D01*
G02X625686Y1533336I0J-1202D01*
G01Y1533335D01*
G02X625533Y1532748I-1202J0D01*
G01X625528Y1532738D01*
X625527D01*
X625526Y1532736D01*
X623983Y1530066D01*
X623981Y1530061D01*
G02X621722Y1530800I-1072J545D01*
G01Y1530801D01*
G37*
G36*
G01X626447D02*
G02X626581Y1531189I1187J-193D01*
G01X628145Y1533895D01*
X628146Y1533898D01*
G02X629209Y1534538I1063J-563D01*
G02X630412Y1533336I1J-1202D01*
G01Y1533335D01*
G02X630258Y1532748I-1203J2D01*
G01X630253Y1532738D01*
X630252D01*
X630251Y1532736D01*
X628708Y1530066D01*
X628706Y1530061D01*
G02X626447Y1530800I-1072J545D01*
G01Y1530801D01*
G37*
G36*
G01X631171D02*
G02X631305Y1531189I1187J-193D01*
G01X632869Y1533895D01*
X632870Y1533898D01*
G02X633933Y1534538I1063J-563D01*
G02X635136Y1533336I1J-1202D01*
G01Y1533335D01*
G02X634982Y1532748I-1203J2D01*
G01X634977Y1532738D01*
X634976D01*
X634975Y1532736D01*
X633432Y1530066D01*
X633430Y1530061D01*
G02X631171Y1530800I-1072J545D01*
G01Y1530801D01*
G37*
G36*
G01X637597Y1533902D02*
G02X638657Y1534538I1060J-565D01*
G01X638658D01*
G02X639860Y1533336I0J-1202D01*
G01Y1533335D01*
G02X639707Y1532748I-1202J0D01*
G01X639630Y1532616D01*
G03X639629Y1532614I178J-90D01*
G01X638163Y1530078D01*
X638160Y1530072D01*
G02X636021Y1530042I-1077J535D01*
G01Y1530043D01*
G02X635880Y1530608I1062J565D01*
G01Y1530610D01*
G02X636029Y1531189I1202J-1D01*
G01X637595Y1533899D01*
X637597Y1533902D01*
G37*
G36*
G01X640620Y1530801D02*
G02X640754Y1531189I1187J-193D01*
G01X642318Y1533895D01*
X642319Y1533898D01*
G02X643382Y1534538I1063J-563D01*
G02X644584Y1533336I0J-1202D01*
G01Y1533335D01*
G02X644431Y1532748I-1202J0D01*
G01X644426Y1532738D01*
X644425D01*
X644424Y1532736D01*
X642881Y1530066D01*
X642879Y1530061D01*
G02X640620Y1530800I-1072J545D01*
G01Y1530801D01*
G37*
G36*
G01X647046Y1533902D02*
G02X648106Y1534538I1060J-565D01*
G01X648107D01*
G02X649310Y1533336I1J-1202D01*
G01Y1533335D01*
G02X649156Y1532748I-1203J2D01*
G01X649079Y1532616D01*
G03X649078Y1532614I178J-90D01*
G01X647612Y1530078D01*
X647609Y1530072D01*
G02X645470Y1530042I-1077J535D01*
G01Y1530043D01*
G02X645328Y1530608I1053J565D01*
G01Y1530610D01*
G02X645478Y1531189I1203J-3D01*
G01X647044Y1533899D01*
X647046Y1533902D01*
G37*
G36*
G01X650069Y1530801D02*
G02X650203Y1531189I1187J-193D01*
G01X651767Y1533895D01*
X651768Y1533898D01*
G02X652831Y1534538I1063J-563D01*
G02X654034Y1533336I1J-1202D01*
G01Y1533335D01*
G02X653880Y1532748I-1203J2D01*
G01X653875Y1532738D01*
X653874D01*
X653873Y1532736D01*
X652330Y1530066D01*
X652328Y1530061D01*
G02X650069Y1530800I-1072J545D01*
G01Y1530801D01*
G37*
G36*
G01X1205991Y1553264D02*
G02X1207051Y1553900I1060J-565D01*
G01X1207052D01*
G02X1208254Y1552698I0J-1202D01*
G02X1208094Y1552098I-1203J0D01*
G01X1206549Y1549425D01*
X1206547Y1549421D01*
G02X1205477Y1548768I-1070J550D01*
G01X1205476D01*
G02X1204274Y1549970I0J1202D01*
G01Y1549972D01*
G02X1204423Y1550551I1202J-1D01*
G01X1205989Y1553261D01*
X1205991Y1553264D01*
G37*
G36*
G01X1229613D02*
G02X1230673Y1553900I1060J-565D01*
G01X1230674D01*
G02X1231876Y1552698I0J-1202D01*
G02X1231716Y1552098I-1203J0D01*
G01X1230171Y1549425D01*
X1230169Y1549421D01*
G02X1229099Y1548768I-1070J550D01*
G01X1229098D01*
G02X1227896Y1549970I0J1202D01*
G01Y1549972D01*
G02X1228045Y1550551I1202J-1D01*
G01X1229611Y1553261D01*
X1229613Y1553264D01*
G37*
G36*
G01X1239062D02*
G02X1240122Y1553900I1060J-565D01*
G01X1240123D01*
G02X1241326Y1552698I1J-1202D01*
G02X1241165Y1552098I-1204J1D01*
G01X1239620Y1549425D01*
X1239618Y1549421D01*
G02X1238548Y1548768I-1070J550D01*
G01X1238547D01*
G02X1237344Y1549970I-1J1202D01*
G01Y1549972D01*
G02X1237494Y1550551I1203J-3D01*
G01X1239060Y1553261D01*
X1239062Y1553264D01*
G37*
G36*
G01X1248511D02*
G02X1249571Y1553900I1060J-565D01*
G01X1249572D01*
G02X1250774Y1552698I0J-1202D01*
G02X1250614Y1552098I-1203J0D01*
G01X1249069Y1549425D01*
X1249067Y1549421D01*
G02X1247997Y1548768I-1070J550D01*
G01X1247996D01*
G02X1246794Y1549970I0J1202D01*
G01Y1549972D01*
G02X1246943Y1550551I1202J-1D01*
G01X1248509Y1553261D01*
X1248511Y1553264D01*
G37*
G36*
G01X1257960D02*
G02X1259020Y1553900I1060J-565D01*
G01X1259021D01*
G02X1260224Y1552698I1J-1202D01*
G02X1260063Y1552098I-1204J1D01*
G01X1258518Y1549425D01*
X1258516Y1549421D01*
G02X1257446Y1548768I-1070J550D01*
G01X1257445D01*
G02X1256242Y1549970I-1J1202D01*
G01Y1549972D01*
G02X1256392Y1550551I1203J-3D01*
G01X1257958Y1553261D01*
X1257960Y1553264D01*
G37*
G36*
G01X1334053D02*
G02X1335113Y1553900I1060J-565D01*
G01X1335114D01*
G02X1336316Y1552698I0J-1202D01*
G02X1336156Y1552098I-1203J0D01*
G01X1334611Y1549425D01*
X1334609Y1549421D01*
G02X1333539Y1548768I-1070J550D01*
G01X1333538D01*
G02X1332336Y1549970I0J1202D01*
G01Y1549972D01*
G02X1332485Y1550551I1202J-1D01*
G01X1334051Y1553261D01*
X1334053Y1553264D01*
G37*
G36*
G01X1357675D02*
G02X1358735Y1553900I1060J-565D01*
G01X1358736D01*
G02X1359938Y1552698I0J-1202D01*
G02X1359778Y1552098I-1203J0D01*
G01X1358233Y1549425D01*
X1358231Y1549421D01*
G02X1357161Y1548768I-1070J550D01*
G01X1357160D01*
G02X1355958Y1549970I0J1202D01*
G01Y1549972D01*
G02X1356107Y1550551I1202J-1D01*
G01X1357673Y1553261D01*
X1357675Y1553264D01*
G37*
G36*
G01X1381297D02*
G02X1382357Y1553900I1060J-565D01*
G01X1382358D01*
G02X1383560Y1552698I0J-1202D01*
G02X1383400Y1552098I-1203J0D01*
G01X1381855Y1549425D01*
X1381853Y1549421D01*
G02X1380783Y1548768I-1070J550D01*
G01X1380782D01*
G02X1379580Y1549970I0J1202D01*
G01Y1549972D01*
G02X1379729Y1550551I1202J-1D01*
G01X1381295Y1553261D01*
X1381297Y1553264D01*
G37*
G36*
G01X1390746D02*
G02X1391806Y1553900I1060J-565D01*
G01X1391807D01*
G02X1393010Y1552698I1J-1202D01*
G02X1392849Y1552098I-1204J1D01*
G01X1391304Y1549425D01*
X1391302Y1549421D01*
G02X1390232Y1548768I-1070J550D01*
G01X1390231D01*
G02X1389028Y1549970I-1J1202D01*
G01Y1549972D01*
G02X1389178Y1550551I1203J-3D01*
G01X1390744Y1553261D01*
X1390746Y1553264D01*
G37*
G36*
G01X1194841Y1563801D02*
G02X1194975Y1564189I1187J-193D01*
G01X1196539Y1566895D01*
X1196540Y1566898D01*
G02X1197603Y1567538I1063J-563D01*
G02X1198806Y1566336I1J-1202D01*
G01Y1566335D01*
G02X1198652Y1565748I-1203J2D01*
G01X1198647Y1565738D01*
X1198646D01*
X1198645Y1565736D01*
X1197102Y1563066D01*
X1197100Y1563061D01*
G02X1194841Y1563800I-1072J545D01*
G01Y1563801D01*
G37*
G36*
G01X1199565D02*
G02X1199699Y1564189I1187J-193D01*
G01X1201263Y1566895D01*
X1201264Y1566898D01*
G02X1202327Y1567538I1063J-563D01*
G02X1203530Y1566336I1J-1202D01*
G01Y1566335D01*
G02X1203376Y1565748I-1203J2D01*
G01X1203371Y1565738D01*
X1203370D01*
X1203369Y1565736D01*
X1201826Y1563066D01*
X1201824Y1563061D01*
G02X1199565Y1563800I-1072J545D01*
G01Y1563801D01*
G37*
G36*
G01X1205991Y1566902D02*
G02X1207051Y1567538I1060J-565D01*
G01X1207052D01*
G02X1208254Y1566336I0J-1202D01*
G01Y1566335D01*
G02X1208101Y1565748I-1202J0D01*
G01X1208024Y1565616D01*
G03X1208023Y1565614I178J-90D01*
G01X1206557Y1563078D01*
X1206554Y1563072D01*
G02X1204415Y1563042I-1077J535D01*
G01Y1563043D01*
G02X1204274Y1563608I1062J565D01*
G01Y1563610D01*
G02X1204423Y1564189I1202J-1D01*
G01X1205989Y1566899D01*
X1205991Y1566902D01*
G37*
G36*
G01X1209014Y1563801D02*
G02X1209148Y1564189I1187J-193D01*
G01X1210712Y1566895D01*
X1210713Y1566898D01*
G02X1211776Y1567538I1063J-563D01*
G02X1212978Y1566336I0J-1202D01*
G01Y1566335D01*
G02X1212825Y1565748I-1202J0D01*
G01X1212820Y1565738D01*
X1212819D01*
X1212818Y1565736D01*
X1211275Y1563066D01*
X1211273Y1563061D01*
G02X1209014Y1563800I-1072J545D01*
G01Y1563801D01*
G37*
G36*
G01X1213738D02*
G02X1213872Y1564189I1187J-193D01*
G01X1215436Y1566895D01*
X1215437Y1566898D01*
G02X1216500Y1567538I1063J-563D01*
G02X1217702Y1566336I0J-1202D01*
G01Y1566335D01*
G02X1217549Y1565748I-1202J0D01*
G01X1217544Y1565738D01*
X1217543D01*
X1217542Y1565736D01*
X1215999Y1563066D01*
X1215997Y1563061D01*
G02X1213738Y1563800I-1072J545D01*
G01Y1563801D01*
G37*
G36*
G01X1218463D02*
G02X1218597Y1564189I1187J-193D01*
G01X1220161Y1566895D01*
X1220162Y1566898D01*
G02X1221225Y1567538I1063J-563D01*
G02X1222428Y1566336I1J-1202D01*
G01Y1566335D01*
G02X1222274Y1565748I-1203J2D01*
G01X1222269Y1565738D01*
X1222268D01*
X1222267Y1565736D01*
X1220724Y1563066D01*
X1220722Y1563061D01*
G02X1218463Y1563800I-1072J545D01*
G01Y1563801D01*
G37*
G36*
G01X1223187D02*
G02X1223321Y1564189I1187J-193D01*
G01X1224885Y1566895D01*
X1224886Y1566898D01*
G02X1225949Y1567538I1063J-563D01*
G02X1227152Y1566336I1J-1202D01*
G01Y1566335D01*
G02X1226998Y1565748I-1203J2D01*
G01X1226993Y1565738D01*
X1226992D01*
X1226991Y1565736D01*
X1225448Y1563066D01*
X1225446Y1563061D01*
G02X1223187Y1563800I-1072J545D01*
G01Y1563801D01*
G37*
G36*
G01X1229613Y1566902D02*
G02X1230673Y1567538I1060J-565D01*
G01X1230674D01*
G02X1231876Y1566336I0J-1202D01*
G01Y1566335D01*
G02X1231723Y1565748I-1202J0D01*
G01X1231646Y1565616D01*
G03X1231645Y1565614I178J-90D01*
G01X1230179Y1563078D01*
X1230176Y1563072D01*
G02X1228037Y1563042I-1077J535D01*
G01Y1563043D01*
G02X1227896Y1563608I1062J565D01*
G01Y1563610D01*
G02X1228045Y1564189I1202J-1D01*
G01X1229611Y1566899D01*
X1229613Y1566902D01*
G37*
G36*
G01X1232636Y1563801D02*
G02X1232770Y1564189I1187J-193D01*
G01X1234334Y1566895D01*
X1234335Y1566898D01*
G02X1235398Y1567538I1063J-563D01*
G02X1236600Y1566336I0J-1202D01*
G01Y1566335D01*
G02X1236447Y1565748I-1202J0D01*
G01X1236442Y1565738D01*
X1236441D01*
X1236440Y1565736D01*
X1234897Y1563066D01*
X1234895Y1563061D01*
G02X1232636Y1563800I-1072J545D01*
G01Y1563801D01*
G37*
G36*
G01X1237360D02*
G02X1237494Y1564189I1187J-193D01*
G01X1239058Y1566895D01*
X1239059Y1566898D01*
G02X1240122Y1567538I1063J-563D01*
G02X1241324Y1566336I0J-1202D01*
G01Y1566335D01*
G02X1241171Y1565748I-1202J0D01*
G01X1241166Y1565738D01*
X1241165D01*
X1241164Y1565736D01*
X1239621Y1563066D01*
X1239619Y1563061D01*
G02X1237360Y1563800I-1072J545D01*
G01Y1563801D01*
G37*
G36*
G01X1242085D02*
G02X1242219Y1564189I1187J-193D01*
G01X1243783Y1566895D01*
X1243784Y1566898D01*
G02X1244847Y1567538I1063J-563D01*
G02X1246050Y1566336I1J-1202D01*
G01Y1566335D01*
G02X1245896Y1565748I-1203J2D01*
G01X1245891Y1565738D01*
X1245890D01*
X1245889Y1565736D01*
X1244346Y1563066D01*
X1244344Y1563061D01*
G02X1242085Y1563800I-1072J545D01*
G01Y1563801D01*
G37*
G36*
G01X1246809D02*
G02X1246943Y1564189I1187J-193D01*
G01X1248507Y1566895D01*
X1248508Y1566898D01*
G02X1249571Y1567538I1063J-563D01*
G02X1250774Y1566336I1J-1202D01*
G01Y1566335D01*
G02X1250620Y1565748I-1203J2D01*
G01X1250615Y1565738D01*
X1250614D01*
X1250613Y1565736D01*
X1249070Y1563066D01*
X1249068Y1563061D01*
G02X1246809Y1563800I-1072J545D01*
G01Y1563801D01*
G37*
G36*
G01X1253235Y1566902D02*
G02X1254295Y1567538I1060J-565D01*
G01X1254296D01*
G02X1255498Y1566336I0J-1202D01*
G01Y1566335D01*
G02X1255345Y1565748I-1202J0D01*
G01X1255268Y1565616D01*
G03X1255267Y1565614I178J-90D01*
G01X1253801Y1563078D01*
X1253798Y1563072D01*
G02X1251659Y1563042I-1077J535D01*
G01Y1563043D01*
G02X1251518Y1563608I1062J565D01*
G01Y1563610D01*
G02X1251667Y1564189I1202J-1D01*
G01X1253233Y1566899D01*
X1253235Y1566902D01*
G37*
G36*
G01X1256258Y1563801D02*
G02X1256392Y1564189I1187J-193D01*
G01X1257956Y1566895D01*
X1257957Y1566898D01*
G02X1259020Y1567538I1063J-563D01*
G02X1260222Y1566336I0J-1202D01*
G01Y1566335D01*
G02X1260069Y1565748I-1202J0D01*
G01X1260064Y1565738D01*
X1260063D01*
X1260062Y1565736D01*
X1258519Y1563066D01*
X1258517Y1563061D01*
G02X1256258Y1563800I-1072J545D01*
G01Y1563801D01*
G37*
G36*
G01X1262684Y1566902D02*
G02X1263744Y1567538I1060J-565D01*
G01X1263745D01*
G02X1264948Y1566336I1J-1202D01*
G01Y1566335D01*
G02X1264794Y1565748I-1203J2D01*
G01X1264717Y1565616D01*
G03X1264716Y1565614I178J-90D01*
G01X1263250Y1563078D01*
X1263247Y1563072D01*
G02X1261108Y1563042I-1077J535D01*
G01Y1563043D01*
G02X1260966Y1563608I1053J565D01*
G01Y1563610D01*
G02X1261116Y1564189I1203J-3D01*
G01X1262682Y1566899D01*
X1262684Y1566902D01*
G37*
G36*
G01X1265707Y1563801D02*
G02X1265841Y1564189I1187J-193D01*
G01X1267405Y1566895D01*
X1267406Y1566898D01*
G02X1268469Y1567538I1063J-563D01*
G02X1269672Y1566336I1J-1202D01*
G01Y1566335D01*
G02X1269518Y1565748I-1203J2D01*
G01X1269513Y1565738D01*
X1269512D01*
X1269511Y1565736D01*
X1267968Y1563066D01*
X1267966Y1563061D01*
G02X1265707Y1563800I-1072J545D01*
G01Y1563801D01*
G37*
G36*
G01X1322903D02*
G02X1323037Y1564189I1187J-193D01*
G01X1324601Y1566895D01*
X1324602Y1566898D01*
G02X1325665Y1567538I1063J-563D01*
G02X1326868Y1566336I1J-1202D01*
G01Y1566335D01*
G02X1326714Y1565748I-1203J2D01*
G01X1326709Y1565738D01*
X1326708D01*
X1326707Y1565736D01*
X1325164Y1563066D01*
X1325162Y1563061D01*
G02X1322903Y1563800I-1072J545D01*
G01Y1563801D01*
G37*
G36*
G01X1327627D02*
G02X1327761Y1564189I1187J-193D01*
G01X1329325Y1566895D01*
X1329326Y1566898D01*
G02X1330389Y1567538I1063J-563D01*
G02X1331592Y1566336I1J-1202D01*
G01Y1566335D01*
G02X1331438Y1565748I-1203J2D01*
G01X1331433Y1565738D01*
X1331432D01*
X1331431Y1565736D01*
X1329888Y1563066D01*
X1329886Y1563061D01*
G02X1327627Y1563800I-1072J545D01*
G01Y1563801D01*
G37*
G36*
G01X1332351D02*
G02X1332485Y1564189I1187J-193D01*
G01X1334049Y1566895D01*
X1334050Y1566898D01*
G02X1335113Y1567538I1063J-563D01*
G02X1336316Y1566336I1J-1202D01*
G01Y1566335D01*
G02X1336162Y1565748I-1203J2D01*
G01X1336157Y1565738D01*
X1336156D01*
X1336155Y1565736D01*
X1334612Y1563066D01*
X1334610Y1563061D01*
G02X1332351Y1563800I-1072J545D01*
G01Y1563801D01*
G37*
G36*
G01X1337076D02*
G02X1337210Y1564189I1187J-193D01*
G01X1338774Y1566895D01*
X1338775Y1566898D01*
G02X1339838Y1567538I1063J-563D01*
G02X1341040Y1566336I0J-1202D01*
G01Y1566335D01*
G02X1340887Y1565748I-1202J0D01*
G01X1340882Y1565738D01*
X1340881D01*
X1340880Y1565736D01*
X1339337Y1563066D01*
X1339335Y1563061D01*
G02X1337076Y1563800I-1072J545D01*
G01Y1563801D01*
G37*
G36*
G01X1341800D02*
G02X1341934Y1564189I1187J-193D01*
G01X1343498Y1566895D01*
X1343499Y1566898D01*
G02X1344562Y1567538I1063J-563D01*
G02X1345764Y1566336I0J-1202D01*
G01Y1566335D01*
G02X1345611Y1565748I-1202J0D01*
G01X1345606Y1565738D01*
X1345605D01*
X1345604Y1565736D01*
X1344061Y1563066D01*
X1344059Y1563061D01*
G02X1341800Y1563800I-1072J545D01*
G01Y1563801D01*
G37*
G36*
G01X1346525D02*
G02X1346659Y1564189I1187J-193D01*
G01X1348223Y1566895D01*
X1348224Y1566898D01*
G02X1349287Y1567538I1063J-563D01*
G02X1350490Y1566336I1J-1202D01*
G01Y1566335D01*
G02X1350336Y1565748I-1203J2D01*
G01X1350331Y1565738D01*
X1350330D01*
X1350329Y1565736D01*
X1348786Y1563066D01*
X1348784Y1563061D01*
G02X1346525Y1563800I-1072J545D01*
G01Y1563801D01*
G37*
G36*
G01X1351249D02*
G02X1351383Y1564189I1187J-193D01*
G01X1352947Y1566895D01*
X1352948Y1566898D01*
G02X1354011Y1567538I1063J-563D01*
G02X1355214Y1566336I1J-1202D01*
G01Y1566335D01*
G02X1355060Y1565748I-1203J2D01*
G01X1355055Y1565738D01*
X1355054D01*
X1355053Y1565736D01*
X1353510Y1563066D01*
X1353508Y1563061D01*
G02X1351249Y1563800I-1072J545D01*
G01Y1563801D01*
G37*
G36*
G01X1355973D02*
G02X1356107Y1564189I1187J-193D01*
G01X1357671Y1566895D01*
X1357672Y1566898D01*
G02X1358735Y1567538I1063J-563D01*
G02X1359938Y1566336I1J-1202D01*
G01Y1566335D01*
G02X1359784Y1565748I-1203J2D01*
G01X1359779Y1565738D01*
X1359778D01*
X1359777Y1565736D01*
X1358234Y1563066D01*
X1358232Y1563061D01*
G02X1355973Y1563800I-1072J545D01*
G01Y1563801D01*
G37*
G36*
G01X1360698D02*
G02X1360832Y1564189I1187J-193D01*
G01X1362396Y1566895D01*
X1362397Y1566898D01*
G02X1363460Y1567538I1063J-563D01*
G02X1364662Y1566336I0J-1202D01*
G01Y1566335D01*
G02X1364509Y1565748I-1202J0D01*
G01X1364504Y1565738D01*
X1364503D01*
X1364502Y1565736D01*
X1362959Y1563066D01*
X1362957Y1563061D01*
G02X1360698Y1563800I-1072J545D01*
G01Y1563801D01*
G37*
G36*
G01X1365422D02*
G02X1365556Y1564189I1187J-193D01*
G01X1367120Y1566895D01*
X1367121Y1566898D01*
G02X1368184Y1567538I1063J-563D01*
G02X1369386Y1566336I0J-1202D01*
G01Y1566335D01*
G02X1369233Y1565748I-1202J0D01*
G01X1369228Y1565738D01*
X1369227D01*
X1369226Y1565736D01*
X1367683Y1563066D01*
X1367681Y1563061D01*
G02X1365422Y1563800I-1072J545D01*
G01Y1563801D01*
G37*
G36*
G01X1370147D02*
G02X1370281Y1564189I1187J-193D01*
G01X1371845Y1566895D01*
X1371846Y1566898D01*
G02X1372909Y1567538I1063J-563D01*
G02X1374112Y1566336I1J-1202D01*
G01Y1566335D01*
G02X1373958Y1565748I-1203J2D01*
G01X1373953Y1565738D01*
X1373952D01*
X1373951Y1565736D01*
X1372408Y1563066D01*
X1372406Y1563061D01*
G02X1370147Y1563800I-1072J545D01*
G01Y1563801D01*
G37*
G36*
G01X1374871D02*
G02X1375005Y1564189I1187J-193D01*
G01X1376569Y1566895D01*
X1376570Y1566898D01*
G02X1377633Y1567538I1063J-563D01*
G02X1378836Y1566336I1J-1202D01*
G01Y1566335D01*
G02X1378682Y1565748I-1203J2D01*
G01X1378677Y1565738D01*
X1378676D01*
X1378675Y1565736D01*
X1377132Y1563066D01*
X1377130Y1563061D01*
G02X1374871Y1563800I-1072J545D01*
G01Y1563801D01*
G37*
G36*
G01X1379595D02*
G02X1379729Y1564189I1187J-193D01*
G01X1381293Y1566895D01*
X1381294Y1566898D01*
G02X1382357Y1567538I1063J-563D01*
G02X1383560Y1566336I1J-1202D01*
G01Y1566335D01*
G02X1383406Y1565748I-1203J2D01*
G01X1383401Y1565738D01*
X1383400D01*
X1383399Y1565736D01*
X1381856Y1563066D01*
X1381854Y1563061D01*
G02X1379595Y1563800I-1072J545D01*
G01Y1563801D01*
G37*
G36*
G01X1384320D02*
G02X1384454Y1564189I1187J-193D01*
G01X1386018Y1566895D01*
X1386019Y1566898D01*
G02X1387082Y1567538I1063J-563D01*
G02X1388284Y1566336I0J-1202D01*
G01Y1566335D01*
G02X1388131Y1565748I-1202J0D01*
G01X1388126Y1565738D01*
X1388125D01*
X1388124Y1565736D01*
X1386581Y1563066D01*
X1386579Y1563061D01*
G02X1384320Y1563800I-1072J545D01*
G01Y1563801D01*
G37*
G36*
G01X1389044D02*
G02X1389178Y1564189I1187J-193D01*
G01X1390742Y1566895D01*
X1390743Y1566898D01*
G02X1391806Y1567538I1063J-563D01*
G02X1393008Y1566336I0J-1202D01*
G01Y1566335D01*
G02X1392855Y1565748I-1202J0D01*
G01X1392850Y1565738D01*
X1392849D01*
X1392848Y1565736D01*
X1391305Y1563066D01*
X1391303Y1563061D01*
G02X1389044Y1563800I-1072J545D01*
G01Y1563801D01*
G37*
G36*
G01X1393769D02*
G02X1393903Y1564189I1187J-193D01*
G01X1395467Y1566895D01*
X1395468Y1566898D01*
G02X1396531Y1567538I1063J-563D01*
G02X1397734Y1566336I1J-1202D01*
G01Y1566335D01*
G02X1397580Y1565748I-1203J2D01*
G01X1397575Y1565738D01*
X1397574D01*
X1397573Y1565736D01*
X1396030Y1563066D01*
X1396028Y1563061D01*
G02X1393769Y1563800I-1072J545D01*
G01Y1563801D01*
G37*
G36*
G01X1459015D02*
G02X1459149Y1564189I1187J-193D01*
G01X1460713Y1566895D01*
X1460714Y1566898D01*
G02X1461777Y1567538I1063J-563D01*
G02X1462980Y1566336I1J-1202D01*
G01Y1566335D01*
G02X1462826Y1565748I-1203J2D01*
G01X1462821Y1565738D01*
X1462820D01*
X1462819Y1565736D01*
X1461276Y1563066D01*
X1461274Y1563061D01*
G02X1459015Y1563800I-1072J545D01*
G01Y1563801D01*
G37*
G36*
G01X1463739D02*
G02X1463873Y1564189I1187J-193D01*
G01X1465437Y1566895D01*
X1465438Y1566898D01*
G02X1466501Y1567538I1063J-563D01*
G02X1467704Y1566336I1J-1202D01*
G01Y1566335D01*
G02X1467550Y1565748I-1203J2D01*
G01X1467545Y1565738D01*
X1467544D01*
X1467543Y1565736D01*
X1466000Y1563066D01*
X1465998Y1563061D01*
G02X1463739Y1563800I-1072J545D01*
G01Y1563801D01*
G37*
G36*
G01X1468463D02*
G02X1468597Y1564189I1187J-193D01*
G01X1470161Y1566895D01*
X1470162Y1566898D01*
G02X1471225Y1567538I1063J-563D01*
G02X1472428Y1566336I1J-1202D01*
G01Y1566335D01*
G02X1472274Y1565748I-1203J2D01*
G01X1472269Y1565738D01*
X1472268D01*
X1472267Y1565736D01*
X1470724Y1563066D01*
X1470722Y1563061D01*
G02X1468463Y1563800I-1072J545D01*
G01Y1563801D01*
G37*
G36*
G01X1473188D02*
G02X1473322Y1564189I1187J-193D01*
G01X1474886Y1566895D01*
X1474887Y1566898D01*
G02X1475950Y1567538I1063J-563D01*
G02X1477152Y1566336I0J-1202D01*
G01Y1566335D01*
G02X1476999Y1565748I-1202J0D01*
G01X1476994Y1565738D01*
X1476993D01*
X1476992Y1565736D01*
X1475449Y1563066D01*
X1475447Y1563061D01*
G02X1473188Y1563800I-1072J545D01*
G01Y1563801D01*
G37*
G36*
G01X1477912D02*
G02X1478046Y1564189I1187J-193D01*
G01X1479610Y1566895D01*
X1479611Y1566898D01*
G02X1480674Y1567538I1063J-563D01*
G02X1481876Y1566336I0J-1202D01*
G01Y1566335D01*
G02X1481723Y1565748I-1202J0D01*
G01X1481718Y1565738D01*
X1481717D01*
X1481716Y1565736D01*
X1480173Y1563066D01*
X1480171Y1563061D01*
G02X1477912Y1563800I-1072J545D01*
G01Y1563801D01*
G37*
G36*
G01X1482637D02*
G02X1482771Y1564189I1187J-193D01*
G01X1484335Y1566895D01*
X1484336Y1566898D01*
G02X1485399Y1567538I1063J-563D01*
G02X1486602Y1566336I1J-1202D01*
G01Y1566335D01*
G02X1486448Y1565748I-1203J2D01*
G01X1486443Y1565738D01*
X1486442D01*
X1486441Y1565736D01*
X1484898Y1563066D01*
X1484896Y1563061D01*
G02X1482637Y1563800I-1072J545D01*
G01Y1563801D01*
G37*
G36*
G01X1487361D02*
G02X1487495Y1564189I1187J-193D01*
G01X1489059Y1566895D01*
X1489060Y1566898D01*
G02X1490123Y1567538I1063J-563D01*
G02X1491326Y1566336I1J-1202D01*
G01Y1566335D01*
G02X1491172Y1565748I-1203J2D01*
G01X1491167Y1565738D01*
X1491166D01*
X1491165Y1565736D01*
X1489622Y1563066D01*
X1489620Y1563061D01*
G02X1487361Y1563800I-1072J545D01*
G01Y1563801D01*
G37*
G36*
G01X1492085D02*
G02X1492219Y1564189I1187J-193D01*
G01X1493783Y1566895D01*
X1493784Y1566898D01*
G02X1494847Y1567538I1063J-563D01*
G02X1496050Y1566336I1J-1202D01*
G01Y1566335D01*
G02X1495896Y1565748I-1203J2D01*
G01X1495891Y1565738D01*
X1495890D01*
X1495889Y1565736D01*
X1494346Y1563066D01*
X1494344Y1563061D01*
G02X1492085Y1563800I-1072J545D01*
G01Y1563801D01*
G37*
G36*
G01X1496810D02*
G02X1496944Y1564189I1187J-193D01*
G01X1498508Y1566895D01*
X1498509Y1566898D01*
G02X1499572Y1567538I1063J-563D01*
G02X1500774Y1566336I0J-1202D01*
G01Y1566335D01*
G02X1500621Y1565748I-1202J0D01*
G01X1500616Y1565738D01*
X1500615D01*
X1500614Y1565736D01*
X1499071Y1563066D01*
X1499069Y1563061D01*
G02X1496810Y1563800I-1072J545D01*
G01Y1563801D01*
G37*
G36*
G01X1501534D02*
G02X1501668Y1564189I1187J-193D01*
G01X1503232Y1566895D01*
X1503233Y1566898D01*
G02X1504296Y1567538I1063J-563D01*
G02X1505498Y1566336I0J-1202D01*
G01Y1566335D01*
G02X1505345Y1565748I-1202J0D01*
G01X1505340Y1565738D01*
X1505339D01*
X1505338Y1565736D01*
X1503795Y1563066D01*
X1503793Y1563061D01*
G02X1501534Y1563800I-1072J545D01*
G01Y1563801D01*
G37*
G36*
G01X1506259D02*
G02X1506393Y1564189I1187J-193D01*
G01X1507957Y1566895D01*
X1507958Y1566898D01*
G02X1509021Y1567538I1063J-563D01*
G02X1510224Y1566336I1J-1202D01*
G01Y1566335D01*
G02X1510070Y1565748I-1203J2D01*
G01X1510065Y1565738D01*
X1510064D01*
X1510063Y1565736D01*
X1508520Y1563066D01*
X1508518Y1563061D01*
G02X1506259Y1563800I-1072J545D01*
G01Y1563801D01*
G37*
G36*
G01X1510983D02*
G02X1511117Y1564189I1187J-193D01*
G01X1512681Y1566895D01*
X1512682Y1566898D01*
G02X1513745Y1567538I1063J-563D01*
G02X1514948Y1566336I1J-1202D01*
G01Y1566335D01*
G02X1514794Y1565748I-1203J2D01*
G01X1514789Y1565738D01*
X1514788D01*
X1514787Y1565736D01*
X1513244Y1563066D01*
X1513242Y1563061D01*
G02X1510983Y1563800I-1072J545D01*
G01Y1563801D01*
G37*
G36*
G01X1515707D02*
G02X1515841Y1564189I1187J-193D01*
G01X1517405Y1566895D01*
X1517406Y1566898D01*
G02X1518469Y1567538I1063J-563D01*
G02X1519672Y1566336I1J-1202D01*
G01Y1566335D01*
G02X1519518Y1565748I-1203J2D01*
G01X1519513Y1565738D01*
X1519512D01*
X1519511Y1565736D01*
X1517968Y1563066D01*
X1517966Y1563061D01*
G02X1515707Y1563800I-1072J545D01*
G01Y1563801D01*
G37*
G36*
G01X1520432D02*
G02X1520566Y1564189I1187J-193D01*
G01X1522130Y1566895D01*
X1522131Y1566898D01*
G02X1523194Y1567538I1063J-563D01*
G02X1524396Y1566336I0J-1202D01*
G01Y1566335D01*
G02X1524243Y1565748I-1202J0D01*
G01X1524238Y1565738D01*
X1524237D01*
X1524236Y1565736D01*
X1522693Y1563066D01*
X1522691Y1563061D01*
G02X1520432Y1563800I-1072J545D01*
G01Y1563801D01*
G37*
G36*
G01X1525156D02*
G02X1525290Y1564189I1187J-193D01*
G01X1526854Y1566895D01*
X1526855Y1566898D01*
G02X1527918Y1567538I1063J-563D01*
G02X1529120Y1566336I0J-1202D01*
G01Y1566335D01*
G02X1528967Y1565748I-1202J0D01*
G01X1528962Y1565738D01*
X1528961D01*
X1528960Y1565736D01*
X1527417Y1563066D01*
X1527415Y1563061D01*
G02X1525156Y1563800I-1072J545D01*
G01Y1563801D01*
G37*
G36*
G01X1529881D02*
G02X1530015Y1564189I1187J-193D01*
G01X1531579Y1566895D01*
X1531580Y1566898D01*
G02X1532643Y1567538I1063J-563D01*
G02X1533846Y1566336I1J-1202D01*
G01Y1566335D01*
G02X1533692Y1565748I-1203J2D01*
G01X1533687Y1565738D01*
X1533686D01*
X1533685Y1565736D01*
X1532142Y1563066D01*
X1532140Y1563061D01*
G02X1529881Y1563800I-1072J545D01*
G01Y1563801D01*
G37*
G36*
G01X1587077D02*
G02X1587211Y1564189I1187J-193D01*
G01X1588775Y1566895D01*
X1588776Y1566898D01*
G02X1589839Y1567538I1063J-563D01*
G02X1591042Y1566336I1J-1202D01*
G01Y1566335D01*
G02X1590888Y1565748I-1203J2D01*
G01X1590883Y1565738D01*
X1590882D01*
X1590881Y1565736D01*
X1589338Y1563066D01*
X1589336Y1563061D01*
G02X1587077Y1563800I-1072J545D01*
G01Y1563801D01*
G37*
G36*
G01X1591801D02*
G02X1591935Y1564189I1187J-193D01*
G01X1593499Y1566895D01*
X1593500Y1566898D01*
G02X1594563Y1567538I1063J-563D01*
G02X1595766Y1566336I1J-1202D01*
G01Y1566335D01*
G02X1595612Y1565748I-1203J2D01*
G01X1595607Y1565738D01*
X1595606D01*
X1595605Y1565736D01*
X1594062Y1563066D01*
X1594060Y1563061D01*
G02X1591801Y1563800I-1072J545D01*
G01Y1563801D01*
G37*
G36*
G01X1598227Y1566902D02*
G02X1599287Y1567538I1060J-565D01*
G01X1599288D01*
G02X1600490Y1566336I0J-1202D01*
G01Y1566335D01*
G02X1600337Y1565748I-1202J0D01*
G01X1600260Y1565616D01*
G03X1600259Y1565614I178J-90D01*
G01X1598793Y1563078D01*
X1598790Y1563072D01*
G02X1596651Y1563042I-1077J535D01*
G01Y1563043D01*
G02X1596510Y1563608I1062J565D01*
G01Y1563610D01*
G02X1596659Y1564189I1202J-1D01*
G01X1598225Y1566899D01*
X1598227Y1566902D01*
G37*
G36*
G01X1601250Y1563801D02*
G02X1601384Y1564189I1187J-193D01*
G01X1602948Y1566895D01*
X1602949Y1566898D01*
G02X1604012Y1567538I1063J-563D01*
G02X1605214Y1566336I0J-1202D01*
G01Y1566335D01*
G02X1605061Y1565748I-1202J0D01*
G01X1605056Y1565738D01*
X1605055D01*
X1605054Y1565736D01*
X1603511Y1563066D01*
X1603509Y1563061D01*
G02X1601250Y1563800I-1072J545D01*
G01Y1563801D01*
G37*
G36*
G01X1605974D02*
G02X1606108Y1564189I1187J-193D01*
G01X1607672Y1566895D01*
X1607673Y1566898D01*
G02X1608736Y1567538I1063J-563D01*
G02X1609938Y1566336I0J-1202D01*
G01Y1566335D01*
G02X1609785Y1565748I-1202J0D01*
G01X1609780Y1565738D01*
X1609779D01*
X1609778Y1565736D01*
X1608235Y1563066D01*
X1608233Y1563061D01*
G02X1605974Y1563800I-1072J545D01*
G01Y1563801D01*
G37*
G36*
G01X1610699D02*
G02X1610833Y1564189I1187J-193D01*
G01X1612397Y1566895D01*
X1612398Y1566898D01*
G02X1613461Y1567538I1063J-563D01*
G02X1614664Y1566336I1J-1202D01*
G01Y1566335D01*
G02X1614510Y1565748I-1203J2D01*
G01X1614505Y1565738D01*
X1614504D01*
X1614503Y1565736D01*
X1612960Y1563066D01*
X1612958Y1563061D01*
G02X1610699Y1563800I-1072J545D01*
G01Y1563801D01*
G37*
G36*
G01X1615423D02*
G02X1615557Y1564189I1187J-193D01*
G01X1617121Y1566895D01*
X1617122Y1566898D01*
G02X1618185Y1567538I1063J-563D01*
G02X1619388Y1566336I1J-1202D01*
G01Y1566335D01*
G02X1619234Y1565748I-1203J2D01*
G01X1619229Y1565738D01*
X1619228D01*
X1619227Y1565736D01*
X1617684Y1563066D01*
X1617682Y1563061D01*
G02X1615423Y1563800I-1072J545D01*
G01Y1563801D01*
G37*
G36*
G01X1621849Y1566902D02*
G02X1622909Y1567538I1060J-565D01*
G01X1622910D01*
G02X1624112Y1566336I0J-1202D01*
G01Y1566335D01*
G02X1623959Y1565748I-1202J0D01*
G01X1623882Y1565616D01*
G03X1623881Y1565614I178J-90D01*
G01X1622415Y1563078D01*
X1622412Y1563072D01*
G02X1620273Y1563042I-1077J535D01*
G01Y1563043D01*
G02X1620132Y1563608I1062J565D01*
G01Y1563610D01*
G02X1620281Y1564189I1202J-1D01*
G01X1621847Y1566899D01*
X1621849Y1566902D01*
G37*
G36*
G01X1624872Y1563801D02*
G02X1625006Y1564189I1187J-193D01*
G01X1626570Y1566895D01*
X1626571Y1566898D01*
G02X1627634Y1567538I1063J-563D01*
G02X1628836Y1566336I0J-1202D01*
G01Y1566335D01*
G02X1628683Y1565748I-1202J0D01*
G01X1628678Y1565738D01*
X1628677D01*
X1628676Y1565736D01*
X1627133Y1563066D01*
X1627131Y1563061D01*
G02X1624872Y1563800I-1072J545D01*
G01Y1563801D01*
G37*
G36*
G01X1629596D02*
G02X1629730Y1564189I1187J-193D01*
G01X1631294Y1566895D01*
X1631295Y1566898D01*
G02X1632358Y1567538I1063J-563D01*
G02X1633560Y1566336I0J-1202D01*
G01Y1566335D01*
G02X1633407Y1565748I-1202J0D01*
G01X1633402Y1565738D01*
X1633401D01*
X1633400Y1565736D01*
X1631857Y1563066D01*
X1631855Y1563061D01*
G02X1629596Y1563800I-1072J545D01*
G01Y1563801D01*
G37*
G36*
G01X1634321D02*
G02X1634455Y1564189I1187J-193D01*
G01X1636019Y1566895D01*
X1636020Y1566898D01*
G02X1637083Y1567538I1063J-563D01*
G02X1638286Y1566336I1J-1202D01*
G01Y1566335D01*
G02X1638132Y1565748I-1203J2D01*
G01X1638127Y1565738D01*
X1638126D01*
X1638125Y1565736D01*
X1636582Y1563066D01*
X1636580Y1563061D01*
G02X1634321Y1563800I-1072J545D01*
G01Y1563801D01*
G37*
G36*
G01X1639045D02*
G02X1639179Y1564189I1187J-193D01*
G01X1640743Y1566895D01*
X1640744Y1566898D01*
G02X1641807Y1567538I1063J-563D01*
G02X1643010Y1566336I1J-1202D01*
G01Y1566335D01*
G02X1642856Y1565748I-1203J2D01*
G01X1642851Y1565738D01*
X1642850D01*
X1642849Y1565736D01*
X1641306Y1563066D01*
X1641304Y1563061D01*
G02X1639045Y1563800I-1072J545D01*
G01Y1563801D01*
G37*
G36*
G01X1645471Y1566902D02*
G02X1646531Y1567538I1060J-565D01*
G01X1646532D01*
G02X1647734Y1566336I0J-1202D01*
G01Y1566335D01*
G02X1647581Y1565748I-1202J0D01*
G01X1647504Y1565616D01*
G03X1647503Y1565614I178J-90D01*
G01X1646037Y1563078D01*
X1646034Y1563072D01*
G02X1643895Y1563042I-1077J535D01*
G01Y1563043D01*
G02X1643754Y1563608I1062J565D01*
G01Y1563610D01*
G02X1643903Y1564189I1202J-1D01*
G01X1645469Y1566899D01*
X1645471Y1566902D01*
G37*
G36*
G01X1648494Y1563801D02*
G02X1648628Y1564189I1187J-193D01*
G01X1650192Y1566895D01*
X1650193Y1566898D01*
G02X1651256Y1567538I1063J-563D01*
G02X1652458Y1566336I0J-1202D01*
G01Y1566335D01*
G02X1652305Y1565748I-1202J0D01*
G01X1652300Y1565738D01*
X1652299D01*
X1652298Y1565736D01*
X1650755Y1563066D01*
X1650753Y1563061D01*
G02X1648494Y1563800I-1072J545D01*
G01Y1563801D01*
G37*
G36*
G01X1654920Y1566902D02*
G02X1655980Y1567538I1060J-565D01*
G01X1655981D01*
G02X1657184Y1566336I1J-1202D01*
G01Y1566335D01*
G02X1657030Y1565748I-1203J2D01*
G01X1656953Y1565616D01*
G03X1656952Y1565614I178J-90D01*
G01X1655486Y1563078D01*
X1655483Y1563072D01*
G02X1653344Y1563042I-1077J535D01*
G01Y1563043D01*
G02X1653202Y1563608I1053J565D01*
G01Y1563610D01*
G02X1653352Y1564189I1203J-3D01*
G01X1654918Y1566899D01*
X1654920Y1566902D01*
G37*
G36*
G01X1657943Y1563801D02*
G02X1658077Y1564189I1187J-193D01*
G01X1659641Y1566895D01*
X1659642Y1566898D01*
G02X1660705Y1567538I1063J-563D01*
G02X1661908Y1566336I1J-1202D01*
G01Y1566335D01*
G02X1661754Y1565748I-1203J2D01*
G01X1661749Y1565738D01*
X1661748D01*
X1661747Y1565736D01*
X1660204Y1563066D01*
X1660202Y1563061D01*
G02X1657943Y1563800I-1072J545D01*
G01Y1563801D01*
G37*
G36*
G01X639269Y1612790D02*
G02Y1615794I0J1502D01*
G01X642669D01*
G02Y1612790I0J-1502D01*
G01X639269D01*
G37*
G36*
G01X627209D02*
G02Y1615794I0J1502D01*
G01X630609D01*
G02Y1612790I0J-1502D01*
G01X627209D01*
G37*
G36*
G01X621179Y1590878D02*
G02Y1593882I0J1502D01*
G01X624579D01*
G02Y1590878I0J-1502D01*
G01X621179D01*
G37*
G36*
G01X633239Y1622790D02*
G02Y1625794I0J1502D01*
G01X636639D01*
G02Y1622790I0J-1502D01*
G01X633239D01*
G37*
G36*
G01X615149Y1600878D02*
G02Y1603882I0J1502D01*
G01X618549D01*
G02Y1600878I0J-1502D01*
G01X615149D01*
G37*
G36*
G01X609119Y1590878D02*
G02Y1593882I0J1502D01*
G01X612519D01*
G02Y1590878I0J-1502D01*
G01X609119D01*
G37*
G36*
G01Y1622790D02*
G02Y1625794I0J1502D01*
G01X612519D01*
G02Y1622790I0J-1502D01*
G01X609119D01*
G37*
G36*
G01X621179D02*
G02Y1625794I0J1502D01*
G01X624579D01*
G02Y1622790I0J-1502D01*
G01X621179D01*
G37*
G36*
G01X615149Y1612790D02*
G02Y1615794I0J1502D01*
G01X618549D01*
G02Y1612790I0J-1502D01*
G01X615149D01*
G37*
G36*
G01X627209Y1600878D02*
G02Y1603882I0J1502D01*
G01X630609D01*
G02Y1600878I0J-1502D01*
G01X627209D01*
G37*
G36*
G01X639269D02*
G02Y1603882I0J1502D01*
G01X642669D01*
G02Y1600878I0J-1502D01*
G01X639269D01*
G37*
G36*
G01X633239Y1590878D02*
G02Y1593882I0J1502D01*
G01X636639D01*
G02Y1590878I0J-1502D01*
G01X633239D01*
G37*
G54D92*
X766889Y1486756D03*
Y1530256D03*
G54D99*
X1571516Y319099D03*
X1290127Y410635D03*
X1005307Y155043D03*
X944406Y1532791D03*
X820901Y147112D03*
X788710Y1488821D03*
X712291Y106722D03*
X263316Y87665D03*
X101675Y160694D03*
G54D108*
X505185Y41141D03*
X60303Y20354D03*
X1534712D03*
G54D86*
X398673Y-18871D03*
Y-8871D03*
X373673D03*
Y-18871D03*
X398673Y-28871D03*
X373673D03*
X718093Y-8871D03*
Y-18871D03*
X743093D03*
Y-8871D03*
X718093Y-28871D03*
X743093D03*
X850152Y-5011D03*
X825152D03*
X850152Y-15011D03*
X825152D03*
X850152Y-35011D03*
Y-25011D03*
X825152D03*
Y-35011D03*
X850152Y4989D03*
X825152D03*
X850152Y14989D03*
X825152D03*
X850152Y24989D03*
X825152D03*
X1169572Y-5011D03*
X1194572D03*
X1169572Y-15011D03*
X1194572D03*
X1169572Y-25011D03*
Y-35011D03*
X1194572D03*
Y-25011D03*
X1169572Y4989D03*
X1194572D03*
X1169572Y14989D03*
X1194572D03*
X1169572Y24989D03*
X1194572D03*
X1253672Y-15011D03*
X1228672D03*
X1253672Y-35011D03*
Y-25011D03*
X1228672D03*
Y-35011D03*
X1253672Y-5011D03*
X1228672D03*
X1253672Y4989D03*
Y14989D03*
X1228672D03*
Y4989D03*
X1253672Y24989D03*
X1228672D03*
X1428431Y-15011D03*
X1453431D03*
X1428431Y-25011D03*
Y-35011D03*
X1453431D03*
Y-25011D03*
X1428431Y-5011D03*
X1453431D03*
X1428431Y14989D03*
Y4989D03*
X1453431D03*
Y14989D03*
X1428431Y24989D03*
X1453431D03*
X1546966Y-39212D03*
Y-29212D03*
X1521966D03*
Y-39212D03*
X1546966Y-19212D03*
X1521966D03*
X1721725Y-29212D03*
Y-39212D03*
X1746725D03*
Y-29212D03*
X1721725Y-19212D03*
X1746725D03*
G54D93*
X1787330Y24291D03*
X922441Y237697D03*
X929331Y160413D03*
X312921Y24291D03*
G54D96*
X676509Y224606D03*
G54D97*
Y145866D03*
G54D104*
X1066280Y1704890D03*
G54D107*
X1340948Y1179681D03*
G54D98*
X1700840Y1424519D03*
X1524437Y640365D03*
X1487677Y640145D03*
X1415690Y601230D03*
X1320516Y1375715D03*
X1291146D03*
X1166535Y1412479D03*
X754645Y1426892D03*
X433624Y594259D03*
X363731Y653394D03*
X326731D03*
G54D103*
X1131824Y1602293D03*
X1141084Y1644972D03*
X1090958Y1648228D03*
X1115098Y1470571D03*
X1562640Y1558031D03*
X554766Y1525031D03*
X1170404Y1558031D03*
X558876Y1456605D03*
X1298466Y1558031D03*
X426704Y1525031D03*
X165336Y1676777D03*
X85836Y1656843D03*
X1434578Y1558031D03*
X436776Y1612094D03*
X388630Y1238447D03*
X390974Y1221149D03*
X313284Y1216822D03*
X814296Y1385745D03*
X1521718Y1579697D03*
X1516994D03*
X1512270D03*
X1507546D03*
X1474474D03*
X1469750D03*
X1493372D03*
X1488648D03*
X1649780D03*
X1645056D03*
X1640332D03*
X1635608D03*
X1602536D03*
X1597812D03*
X1621434D03*
X1616710D03*
X466600Y1546697D03*
X461876D03*
X1385606Y1579697D03*
X1380882D03*
X1376158D03*
X1371434D03*
X1338362D03*
X1333638D03*
X1357260D03*
X1352536D03*
X499672Y1546697D03*
X641906D03*
X637182D03*
X632458D03*
X627734D03*
X513844D03*
X509120D03*
X504396D03*
X485498D03*
X480774D03*
X1257544Y1579697D03*
X1252820D03*
X1248096D03*
X1243372D03*
X1210300D03*
X1205576D03*
X1229198D03*
X1224474D03*
X589938Y1546697D03*
X608836D03*
X594662D03*
X613560D03*
X1680730Y1515382D03*
X672856Y1482382D03*
X1563222Y1514890D03*
X1552668Y1515382D03*
X1435160Y1514890D03*
X1299048D03*
X555348Y1481890D03*
X544794Y1482382D03*
X427286Y1481890D03*
X387182Y1546697D03*
X382458D03*
X358836D03*
X354112D03*
X339938D03*
X335214D03*
X321040D03*
X316316D03*
X259120D03*
X254396D03*
X230774D03*
X226050D03*
X211876D03*
X207152D03*
X192978D03*
X188254D03*
X142576Y1641863D03*
X555348Y1503690D03*
X1170986Y1536690D03*
Y1514890D03*
X1416556Y1515382D03*
Y1528782D03*
X544794Y1495782D03*
X1680730Y1528782D03*
X1299048Y1536690D03*
X1342036Y1204729D03*
X427286Y1503690D03*
X1563222Y1536690D03*
X526460Y99195D03*
X40922Y1656569D03*
X372000Y844727D03*
Y833497D03*
X672856Y1495782D03*
X1435160Y1536690D03*
X1552668Y1528782D03*
X1288494D03*
Y1515382D03*
X400426Y114515D03*
X570860Y123010D03*
X553780Y122940D03*
X417486Y125879D03*
X50880Y1417263D03*
X35852Y690616D03*
Y679710D03*
Y701522D03*
Y668745D03*
G54D109*
X1681102Y1626654D03*
X163662Y1593661D03*
X1171536Y1626654D03*
X698819Y1482244D03*
X1706693Y1515236D03*
X1145945D03*
X138071Y1482244D03*
X673228Y1593661D03*
G54D102*
X403837Y1610756D03*
X1142917Y1585014D03*
X1118133Y1589698D03*
X1146501Y1653908D03*
X162531Y1525031D03*
X290593D03*
X546253Y1455807D03*
X165491Y1663882D03*
X87891Y1672821D03*
X704771Y169488D03*
X280621Y1495782D03*
X1370685Y1224732D03*
X653999Y1425057D03*
X58349Y1408031D03*
X154945Y1626050D03*
X1531167Y1579697D03*
X1526443D03*
X1502821D03*
X1498097D03*
X1483923D03*
X1479199D03*
X1465025D03*
X1460301D03*
X1659229D03*
X1654505D03*
X1630883D03*
X1626159D03*
X1611985D03*
X1607261D03*
X1593087D03*
X1588363D03*
X476049Y1546697D03*
X471325D03*
X1395055Y1579697D03*
X1390331D03*
X1366709D03*
X1361985D03*
X1347811D03*
X1343087D03*
X1328913D03*
X1324189D03*
X494947Y1546697D03*
X490223D03*
X646631D03*
X623009D03*
X618285D03*
X651355D03*
X518569D03*
X523293D03*
X452427D03*
X457151D03*
X1266993Y1579697D03*
X1262269D03*
X1238647D03*
X1233923D03*
X1219749D03*
X1215025D03*
X1200851D03*
X1196127D03*
X585213Y1546697D03*
X604111D03*
X599387D03*
X580489D03*
X1346063Y1216029D03*
X193679Y1641752D03*
X297323Y1655472D03*
X307255Y1645450D03*
X163113Y1503690D03*
Y1481890D03*
X280621Y1482382D03*
X291175Y1481890D03*
Y1503690D03*
X377733Y1546697D03*
X373009D03*
X368285D03*
X363561D03*
X349387D03*
X344663D03*
X330489D03*
X325765D03*
X249671D03*
X244947D03*
X240223D03*
X235499D03*
X221325D03*
X216601D03*
X202427D03*
X197703D03*
X205479Y1650430D03*
X408683Y1482382D03*
X1315657Y1197832D03*
X408683Y1495782D03*
X163735Y1633669D03*
X99443Y1660231D03*
X100443Y1685763D03*
X41679Y1675023D03*
X371999Y821227D03*
X385001Y815227D03*
X1007587Y774180D03*
Y763246D03*
Y840056D03*
Y829054D03*
Y818052D03*
Y807118D03*
Y796184D03*
Y785182D03*
X559069Y103685D03*
X482255Y131522D03*
X704771Y193110D03*
X716699Y210721D03*
Y198887D03*
Y175387D03*
Y187387D03*
X704771Y216732D03*
Y204921D03*
Y181299D03*
G54D106*
X516020Y107320D03*
X535170Y113180D03*
X80948Y523563D03*
X405606Y127765D03*
X80318Y541363D03*
G54D90*
X1766929Y1714960D03*
G54D94*
X1739745Y605411D03*
X1094076Y605378D03*
X763602Y605413D03*
X117933Y605376D03*
G54D84*
X1729562Y-24215D03*
Y-34215D03*
X1436268Y9986D03*
Y-14D03*
Y-20014D03*
Y-30014D03*
X725930Y-13874D03*
Y-23874D03*
X390846Y-13874D03*
Y-23874D03*
G54D83*
X1837795Y18819D03*
X19685Y-29134D03*
X1804650Y1667292D03*
X441043Y1672205D03*
X1416437D03*
X1800449Y126194D03*
X44000Y154200D03*
X31818Y1424257D03*
X1885039Y49021D03*
X2081889Y-29134D03*
X2081889Y1803261D03*
X1871260Y1291627D03*
G54D105*
X47619Y417134D03*
X1025493Y763769D03*
X62813Y414050D03*
G54D101*
X1829921Y130314D03*
G54D95*
X1057659Y204724D03*
X805690D03*
G54D85*
X1539139Y-24215D03*
Y-34215D03*
X1245845Y9986D03*
Y-14D03*
Y-20014D03*
Y-30014D03*
X1177409Y19986D03*
Y9986D03*
Y-10014D03*
Y-20014D03*
X842325Y19986D03*
Y9986D03*
Y-10014D03*
Y-20014D03*
G54D89*
X274913Y1019214D03*
X606409D03*
X1251055Y1019213D03*
X1582551D03*
G54D88*
X320189Y838505D03*
X1296331Y838504D03*
G54D87*
X561133Y838505D03*
Y1199923D03*
X1537275Y838504D03*
Y1199922D03*
X1296331D03*
X320189Y1199923D03*
G54D91*
X841240Y1420331D03*
X1016240D03*
G54D100*
X177413Y277208D03*
X704185Y277236D03*
X1153555Y277208D03*
X1680327Y277236D03*
%LPC*%
G75*
G36*
G01X923910Y1641951D02*
G03X924794Y1641585I884J885D01*
G01X1071014D01*
G02X1071156Y1641526I0J-200D01*
G01X1102501Y1610181D01*
G02X1102560Y1610039I-141J-142D01*
G01Y1569157D01*
G02X1102501Y1569015I-200J0D01*
G01X1099603Y1566117D01*
G02X1099461Y1566058I-142J141D01*
G01X943125D01*
G02X942983Y1566117I0J200D01*
G01X941792Y1567308D01*
G02X941733Y1567450I141J142D01*
G01Y1598999D01*
G03X941367Y1599883I-1251J0D01*
G01X924962Y1616288D01*
G03X924078Y1616654I-884J-885D01*
G01X904324D01*
G02X904182Y1616713I0J200D01*
G01X894316Y1626579D01*
G03X893432Y1626945I-884J-885D01*
G01X771453D01*
G02X771311Y1627004I0J200D01*
G01X768659Y1629656D01*
G02X768600Y1629798I141J142D01*
G01Y1656300D01*
G02X768659Y1656442I200J0D01*
G03X768660Y1656443I-883J884D01*
G01X810874Y1698657D01*
G03X811240Y1699541I-885J884D01*
G01Y1712907D01*
G02X811299Y1713049I200J0D01*
G01X816611Y1718361D01*
G02X816753Y1718420I142J-141D01*
G01X901267D01*
G02X901409Y1718361I0J-200D01*
G01X904191Y1715579D01*
G02X904250Y1715437I-141J-142D01*
G01Y1662129D01*
G03X904616Y1661245I1251J0D01*
G01X923910Y1641951D01*
G37*
%LPD*%
G75*
G54D14*
X11782Y167036D03*
X18691Y167208D03*
X22409Y230021D03*
X19684Y237154D03*
X19230Y1446459D03*
X34281Y277798D03*
Y282916D03*
X35689Y298207D03*
X34281Y312916D03*
Y307798D03*
X35740Y363337D03*
X39320Y392269D03*
X28562Y517025D03*
X39967Y526709D03*
X30562Y533055D03*
X35952Y551605D03*
X35010Y1289485D03*
X35040Y1292433D03*
X35080Y1298360D03*
X35040Y1295380D03*
X34584Y1307744D03*
Y1310244D03*
Y1312744D03*
Y1315244D03*
X33822Y1477075D03*
Y1486075D03*
Y1483075D03*
Y1480075D03*
X27205Y1501630D03*
Y1498230D03*
X38058Y1591405D03*
X35167Y1598896D03*
Y1626896D03*
Y1629405D03*
X32927Y1668587D03*
X42449Y282916D03*
Y277798D03*
X41492Y292892D03*
Y298207D03*
X47892Y295452D03*
X40500Y288500D03*
X55254Y292892D03*
X42449Y312916D03*
Y307798D03*
X51114Y360862D03*
X43020Y382942D03*
X40940Y387302D03*
X41933Y395652D03*
X47619Y419084D03*
X47618Y415184D03*
X49360Y428806D03*
X45960D03*
X49212Y451602D03*
X45812D03*
X47812Y517635D03*
X42810Y528070D03*
X39952Y551605D03*
X55099Y1298676D03*
Y1292676D03*
X51000Y1339200D03*
X50880Y1415563D03*
Y1418963D03*
X42822Y1477075D03*
Y1483075D03*
Y1486075D03*
Y1480075D03*
X49265Y1490950D03*
Y1493450D03*
X49188Y1499181D03*
X41360Y1498971D03*
X41309Y1496173D03*
X38650Y1499326D03*
X49177Y1496272D03*
X48383Y1532395D03*
X48157Y1536296D03*
X49196Y1551294D03*
X48324Y1545961D03*
X48758Y1559295D03*
X48907Y1554972D03*
X47735Y1584885D03*
X47973Y1589981D03*
X43633Y1606896D03*
X46833Y1612596D03*
X43933Y1613818D03*
X47633Y1600896D03*
X53633Y1629896D03*
X41208Y1619896D03*
X42491Y1638656D03*
X40167Y1632405D03*
X40922Y1654869D03*
Y1658269D03*
X45052Y1684283D03*
X41679Y1673323D03*
Y1676723D03*
X65933Y28406D03*
Y48720D03*
X61157Y69340D03*
X64557D03*
X66650Y265316D03*
X57271Y272357D03*
X59780Y282866D03*
X62567Y295103D03*
X66289Y298207D03*
X59780Y312866D03*
X59322Y360702D03*
X63429D03*
X67681D03*
X53406Y402862D03*
X62812Y412100D03*
X62813Y416000D03*
X64821Y430806D03*
X60921D03*
X63540Y438802D03*
X64442Y510667D03*
X55682Y517595D03*
X62142Y539495D03*
X56192Y537795D03*
X63633Y528229D03*
X58365Y552365D03*
X53299D03*
X56627Y585818D03*
X59259Y737422D03*
X58751Y777718D03*
X61251D03*
Y775218D03*
X58751D03*
X61620Y768510D03*
X56440Y766180D03*
X58751Y790218D03*
Y792718D03*
Y780218D03*
X61251D03*
X56057Y792750D03*
X61251Y792718D03*
Y790218D03*
X56057Y790250D03*
Y787750D03*
X61251Y787718D03*
X56057Y785250D03*
X61251Y785218D03*
Y782718D03*
X56057Y782750D03*
X58751Y782718D03*
Y785218D03*
Y787718D03*
X57752Y808020D03*
X60547Y1276036D03*
X57747Y1270470D03*
X55099Y1289676D03*
X55043Y1295676D03*
X53700Y1342300D03*
X58349Y1406331D03*
Y1409731D03*
X67010Y1476292D03*
X57822Y1477075D03*
X57777Y1490580D03*
X66710Y1485324D03*
Y1482324D03*
X66785Y1479175D03*
X57822Y1482791D03*
Y1485294D03*
Y1480075D03*
X64030Y1491595D03*
X57770Y1488047D03*
X66696Y1488010D03*
X64030Y1499095D03*
Y1501595D03*
Y1494095D03*
Y1496595D03*
X55370Y1551351D03*
X66229Y1549536D03*
X61605Y1546833D03*
X64275Y1546296D03*
X57811Y1598061D03*
X58633Y1587481D03*
X63633D03*
X61110Y1598146D03*
X58633Y1629896D03*
X64133Y1627896D03*
X64633Y1632896D03*
X64427Y1643496D03*
X64462Y1655624D03*
X61927Y1643496D03*
X65257Y1652941D03*
X56815Y1643431D03*
X62202Y1684579D03*
X66127Y1687362D03*
X78265Y26477D03*
X74865D03*
X81970Y19541D03*
X72153Y75343D03*
X75553D03*
X79726Y145191D03*
X82026Y143491D03*
X71659Y149191D03*
X71779Y165194D03*
X71775Y153194D03*
X72462Y268223D03*
X77680Y378395D03*
Y380895D03*
X68020Y395222D03*
X80948Y525513D03*
Y521613D03*
X80318Y543313D03*
Y539413D03*
X80915Y767400D03*
X80784Y771366D03*
X68354Y1314097D03*
X80378Y1406676D03*
X83441Y1430500D03*
X81052Y1427410D03*
X81132Y1424195D03*
X79055Y1434000D03*
X73820Y1442893D03*
X81401Y1436105D03*
X73820Y1445945D03*
X73757Y1448500D03*
X81822Y1477075D03*
X77883Y1491440D03*
X80932D03*
X80852Y1488638D03*
X75245Y1491440D03*
X81822Y1480075D03*
Y1483075D03*
Y1486075D03*
X72396Y1491290D03*
X72390Y1499211D03*
X77883Y1499240D03*
X80833D03*
X77883Y1494040D03*
Y1496640D03*
X80932Y1494040D03*
Y1496640D03*
X75245Y1499240D03*
Y1494040D03*
Y1496640D03*
X72396Y1493890D03*
Y1496490D03*
X77920Y1538245D03*
X75796Y1545669D03*
X75396Y1542369D03*
X78796Y1545669D03*
X78096Y1542444D03*
X78372Y1556416D03*
Y1558916D03*
X78522Y1562641D03*
Y1565141D03*
Y1567888D03*
X78403Y1580311D03*
X81103D03*
X78522Y1570388D03*
X81468Y1570285D03*
X68133Y1587896D03*
X81006Y1593265D03*
X72660Y1587365D03*
X72375Y1604365D03*
X74133Y1610896D03*
X70567Y1625603D03*
X72255Y1616730D03*
X74134Y1621396D03*
X75380Y1627622D03*
X75764Y1636993D03*
X79164Y1636992D03*
X77427Y1644410D03*
X82127Y1687362D03*
X82500Y1698511D03*
Y1706511D03*
X82000Y1716331D03*
X82500Y1720331D03*
X82000Y1724331D03*
X85370Y19541D03*
X92438Y26477D03*
X89038D03*
X96143Y19541D03*
X94157Y75340D03*
X83157Y69340D03*
X97557Y75340D03*
X86557Y69340D03*
X92197Y143853D03*
X87137Y143663D03*
X93775Y197241D03*
Y212241D03*
Y207241D03*
Y202241D03*
X87520Y382219D03*
Y391391D03*
Y395865D03*
X90225Y610351D03*
X84057Y599372D03*
X84038Y602233D03*
X90225Y614351D03*
Y618351D03*
Y622351D03*
X94474Y766871D03*
X95790Y1278014D03*
X82953Y1307607D03*
X83023Y1311607D03*
X97546Y1385912D03*
X85736Y1391597D03*
X86827Y1404080D03*
X93000Y1417000D03*
Y1408000D03*
X93069Y1412500D03*
X85103Y1433051D03*
X93000Y1426000D03*
X97800Y1433000D03*
X93000Y1421500D03*
Y1444500D03*
Y1448500D03*
X84500Y1444500D03*
Y1448500D03*
X88722Y1476741D03*
X89092Y1491106D03*
X89042Y1488506D03*
X83991Y1491440D03*
X83892Y1488840D03*
X88722Y1479741D03*
Y1482741D03*
Y1485741D03*
X83892Y1499140D03*
X83991Y1494040D03*
Y1496540D03*
X84051Y1501690D03*
X83796Y1533746D03*
X83811Y1537296D03*
X91511Y1552296D03*
X93296Y1549142D03*
X97018Y1546331D03*
X88511Y1552296D03*
X83121Y1542294D03*
X94786Y1574205D03*
Y1576705D03*
X97486Y1574205D03*
Y1576705D03*
X83603Y1580311D03*
X84093Y1570285D03*
X90675Y1590783D03*
X96124Y1593458D03*
Y1595958D03*
X93424Y1593458D03*
X90675Y1593283D03*
X93424Y1595958D03*
X90675Y1595783D03*
X93537Y1598506D03*
X96237D03*
X90649Y1598507D03*
X84833Y1611896D03*
X90892Y1654749D03*
X85836Y1655143D03*
Y1658543D03*
X87891Y1671121D03*
Y1674521D03*
X90127Y1687362D03*
X96101Y1696469D03*
X82945Y1702511D03*
X95342Y1713741D03*
X96555Y1705508D03*
X95400Y1719741D03*
X95460Y1725241D03*
X99543Y19541D03*
X106611Y26477D03*
X103211D03*
X110316Y19541D03*
X105157Y69340D03*
X108557D03*
X101679Y151191D03*
X101675Y160694D03*
X100818Y165506D03*
Y168906D03*
X110616Y767400D03*
X110485Y771366D03*
X105165Y1300380D03*
Y1302880D03*
X107665D03*
Y1300380D03*
X102665Y1302880D03*
Y1300380D03*
X105165Y1305380D03*
X107665D03*
X102665D03*
Y1307880D03*
Y1310380D03*
Y1312880D03*
X105165Y1307880D03*
Y1310380D03*
Y1312880D03*
X107665D03*
Y1310380D03*
Y1307880D03*
X105165Y1315380D03*
X107665D03*
X105165Y1317880D03*
X107665D03*
X102665D03*
Y1315380D03*
X98101Y1369018D03*
Y1371559D03*
X104863Y1382593D03*
X99594Y1379933D03*
X104863Y1380085D03*
X112305Y1382130D03*
X108817Y1380530D03*
X111555Y1379562D03*
X101874Y1376408D03*
X111600Y1403100D03*
X113500Y1398600D03*
X110000Y1407425D03*
X110075Y1410500D03*
X101637Y1432938D03*
X102076Y1427833D03*
X101955Y1448660D03*
X101500Y1436000D03*
X102398Y1440000D03*
X113500Y1455600D03*
X112481Y1452424D03*
X112100Y1467500D03*
X103571Y1476485D03*
X103555Y1485128D03*
Y1479128D03*
Y1482128D03*
X109733Y1491367D03*
X110605Y1487896D03*
X104184Y1491292D03*
X106784D03*
X105453Y1487893D03*
X108053D03*
X102931Y1488097D03*
X101584Y1491292D03*
X106396Y1485113D03*
X108996D03*
X106371Y1482181D03*
X108971D03*
X107197Y1501756D03*
X109712Y1499196D03*
X104616Y1501811D03*
X107112Y1499196D03*
X109733Y1493967D03*
Y1496567D03*
X106784Y1493892D03*
Y1496492D03*
X101634D03*
X104512Y1499196D03*
X104184Y1496492D03*
Y1493892D03*
X101534Y1499244D03*
X101634Y1493992D03*
X101835Y1501863D03*
X109878Y1501879D03*
X102011Y1550242D03*
X99818Y1546296D03*
X111196Y1542569D03*
X111901Y1545543D03*
X112418Y1555680D03*
X112339Y1565015D03*
Y1562515D03*
X112418Y1558180D03*
X99986Y1574205D03*
Y1576705D03*
X108555Y1574657D03*
Y1577462D03*
X98824Y1593558D03*
X101524D03*
X98824Y1596058D03*
X101524D03*
X101637Y1598606D03*
X98937D03*
X112353Y1646612D03*
X110378Y1670313D03*
X99443Y1661931D03*
Y1658531D03*
X110378Y1674313D03*
X100443Y1684063D03*
Y1687463D03*
X107500Y1707450D03*
X113716Y19541D03*
X120785Y26477D03*
X117385D03*
X124490Y19541D03*
X116157Y75340D03*
X127153Y69343D03*
X119557Y75340D03*
X115016Y300281D03*
Y320715D03*
X118407Y526766D03*
X113042Y686285D03*
X113980Y717480D03*
X116480D03*
X118980D03*
X121480D03*
X123980D03*
X113980Y714980D03*
X116480D03*
X118980D03*
X121480D03*
X123980D03*
X116480Y722480D03*
X118980D03*
X121480D03*
X123980D03*
X113980Y719980D03*
X116480D03*
X118980D03*
X121480D03*
X123980D03*
X113980Y722480D03*
X124174Y766871D03*
X120965Y1307880D03*
Y1310380D03*
Y1312880D03*
X118465D03*
Y1310380D03*
Y1307880D03*
Y1300380D03*
X123465Y1302880D03*
Y1300380D03*
X120965Y1305380D03*
X118465D03*
X123465D03*
Y1307880D03*
Y1310380D03*
Y1312880D03*
X120965Y1300380D03*
Y1302880D03*
X118465D03*
X120965Y1315380D03*
X118465D03*
X120965Y1317880D03*
X118465D03*
X123465D03*
Y1315380D03*
X121207Y1363643D03*
X115321Y1372872D03*
X120181D03*
X117751D03*
X121241Y1367047D03*
Y1369947D03*
X127211Y1373177D03*
Y1378977D03*
X125111Y1377577D03*
X122945Y1379207D03*
X127211Y1376077D03*
X125011Y1374577D03*
X122945Y1376307D03*
X122050Y1403750D03*
X129200Y1401000D03*
X124700D03*
X126000Y1414000D03*
Y1418000D03*
X116700Y1415700D03*
Y1410500D03*
X120700Y1408100D03*
X116900Y1449000D03*
X113600Y1449100D03*
X116122Y1458000D03*
X119100Y1460300D03*
X124600Y1465100D03*
X121500Y1467400D03*
X113100Y1537346D03*
X114030Y1542419D03*
X114610Y1545543D03*
X121705Y1619460D03*
X114618Y1624541D03*
X117655Y1621766D03*
X118956Y1635244D03*
X124312Y1633488D03*
X126717Y1635893D03*
X126428Y1658587D03*
X126760Y1682383D03*
X123353Y1695941D03*
X127353Y1696062D03*
X127710Y1700166D03*
X127290Y1705666D03*
X125183Y1716741D03*
X127168Y1721695D03*
X129020Y1726741D03*
X127890Y19541D03*
X138157Y75340D03*
X141557D03*
X130553Y69343D03*
X140360Y430160D03*
X141642Y488684D03*
Y494147D03*
X139980Y507420D03*
X139890Y503440D03*
X140471Y670445D03*
X131752Y668506D03*
X134902D03*
X140600Y683029D03*
X131752Y686074D03*
X134902D03*
X131960Y679290D03*
X140317Y767400D03*
Y771200D03*
X140265Y1307880D03*
Y1310380D03*
Y1312880D03*
X137765D03*
Y1310380D03*
Y1307880D03*
X135265Y1312880D03*
Y1310380D03*
Y1307880D03*
Y1305380D03*
X140265D03*
X137765D03*
X135265Y1300380D03*
Y1302880D03*
X140265Y1300380D03*
Y1302880D03*
X137765D03*
Y1300380D03*
X140265Y1315380D03*
X137765D03*
X135265D03*
Y1317880D03*
X140265D03*
X137765D03*
X130701Y1369018D03*
Y1371559D03*
X137463Y1382593D03*
X132194Y1379933D03*
X137463Y1380085D03*
X141417Y1380530D03*
X134474Y1376408D03*
X138000Y1400600D03*
X134800Y1408100D03*
X142000Y1414500D03*
X136000Y1432000D03*
X141500Y1433500D03*
Y1429500D03*
X139500Y1446000D03*
X133100Y1444100D03*
X138013Y1440487D03*
X141514Y1436500D03*
X128661Y1464000D03*
X139802Y1556133D03*
X129070Y1608338D03*
X137386Y1626412D03*
X135543Y1637055D03*
X132353Y1646612D03*
X136353D03*
X142465Y1662493D03*
X143000Y1701011D03*
X142293Y1705166D03*
X129493Y1711846D03*
X143000Y1709166D03*
X135722Y1715672D03*
X156651Y26477D03*
X153251D03*
X147920Y28261D03*
X148780Y48720D03*
X149153Y69343D03*
X152553D03*
X149231Y224204D03*
X148228Y216118D03*
X158380Y419760D03*
X147450Y423860D03*
X154770Y441830D03*
X147810Y475710D03*
X146982Y521997D03*
Y530997D03*
X159513Y674855D03*
X152822Y665500D03*
X153875Y766871D03*
X151065Y1307880D03*
Y1310380D03*
Y1312880D03*
X153565D03*
Y1310380D03*
Y1307880D03*
X156065Y1312880D03*
Y1310380D03*
Y1307880D03*
Y1305380D03*
X151065D03*
X153565D03*
X156065Y1300380D03*
Y1302880D03*
X151065Y1300380D03*
Y1302880D03*
X153565D03*
Y1300380D03*
X151065Y1315380D03*
X153565D03*
X156065D03*
Y1317880D03*
X151065D03*
X153565D03*
X152781Y1372872D03*
X150351D03*
X147921D03*
X153741Y1369977D03*
Y1367077D03*
X144905Y1382130D03*
X144155Y1379562D03*
X155545Y1379207D03*
Y1376307D03*
X145000Y1414425D03*
X150900Y1425500D03*
X154443Y1441195D03*
X156174Y1435396D03*
X156477Y1447733D03*
X154083Y1456007D03*
X148340Y1454674D03*
X154671Y1450019D03*
X154305Y1453101D03*
X159000Y1525480D03*
X155618Y1549331D03*
X155071Y1543604D03*
X152843Y1559146D03*
Y1562666D03*
X146453Y1614879D03*
X149171Y1616759D03*
X142576Y1640163D03*
X152353Y1646612D03*
X142576Y1643563D03*
X154111Y1663933D03*
X154010Y1676811D03*
X157410D03*
X143778Y1685087D03*
X147253Y1696343D03*
X155353Y1687843D03*
X159427Y1696652D03*
X152605Y1715941D03*
X149338Y1705603D03*
X156825Y1705510D03*
X146000Y1718241D03*
X146086Y1705603D03*
X145267Y1722241D03*
X152496Y1722941D03*
X146483Y1725636D03*
X155260Y1723682D03*
X170824Y26477D03*
X163756Y19541D03*
X167424Y26477D03*
X160356Y19541D03*
X161361Y75340D03*
X164761D03*
X162830Y396930D03*
X172120Y412350D03*
X172010Y474900D03*
X166760Y506880D03*
X166670Y502900D03*
X163372Y670863D03*
X172725Y667898D03*
X162482Y679319D03*
X161735Y684456D03*
X172725Y679230D03*
X169987Y767666D03*
Y771266D03*
X170265Y1312880D03*
Y1310380D03*
Y1307880D03*
X167765Y1312880D03*
Y1310380D03*
Y1307880D03*
Y1305380D03*
X170265D03*
X167765Y1300380D03*
Y1302880D03*
X170265D03*
Y1300380D03*
Y1315380D03*
X167765D03*
Y1317880D03*
X170265D03*
X163401Y1369018D03*
Y1371559D03*
X159811Y1373177D03*
X170163Y1382593D03*
X164894Y1379933D03*
X170163Y1380085D03*
X167174Y1376408D03*
X159811Y1378977D03*
Y1376077D03*
X157711Y1377577D03*
X157611Y1374577D03*
X163099Y1414400D03*
X162873Y1411611D03*
X163061Y1409048D03*
Y1406548D03*
X160684Y1441046D03*
X158704Y1439411D03*
X161210Y1443542D03*
X163271Y1441588D03*
X169351Y1462595D03*
X163148Y1474504D03*
X163113Y1483590D03*
Y1480190D03*
X172180Y1490210D03*
X172070Y1495550D03*
X163460Y1491010D03*
X163113Y1501990D03*
Y1505390D03*
X163320Y1494340D03*
X161188Y1510800D03*
X162188Y1518040D03*
X162531Y1523331D03*
Y1526731D03*
X167666Y1550751D03*
X165166D03*
X162666D03*
X170166D03*
X170230Y1542960D03*
X160150Y1553251D03*
Y1555751D03*
X162666D03*
X165166D03*
X167666D03*
X170166D03*
Y1553251D03*
X167666D03*
X165166D03*
X162666D03*
X170166Y1567621D03*
X167666D03*
X165166D03*
X162666D03*
X170166Y1565121D03*
X167666D03*
X165166D03*
X162666D03*
Y1562621D03*
X165166D03*
X167666D03*
X170166D03*
X162466Y1570121D03*
X164966D03*
X167466D03*
X169966D03*
X157511Y1663933D03*
X165491Y1665582D03*
Y1662182D03*
X165336Y1675077D03*
Y1678477D03*
X162740Y1713172D03*
Y1704885D03*
X166467Y1720973D03*
X171925Y1717984D03*
X171945Y1730693D03*
X162740Y1723886D03*
X177929Y19541D03*
X174529D03*
X183357Y75343D03*
X172361Y69340D03*
X186757Y75343D03*
X175761Y69340D03*
X184930Y125502D03*
X181025Y159123D03*
X183890Y388180D03*
X174320Y395040D03*
X189290Y396730D03*
X177675Y419260D03*
X185160Y419220D03*
X181550Y441290D03*
X182500Y672500D03*
X172500Y684799D03*
X183576Y766871D03*
X183565Y1310380D03*
Y1312880D03*
X186065D03*
Y1310380D03*
Y1307880D03*
X172765D03*
Y1310380D03*
Y1312880D03*
X183565Y1307880D03*
Y1305380D03*
X186065D03*
X183565Y1300380D03*
Y1302880D03*
X186065D03*
Y1300380D03*
X172765Y1305380D03*
Y1300380D03*
Y1302880D03*
Y1315380D03*
X183565D03*
X186065D03*
X183565Y1317880D03*
X186065D03*
X172765D03*
X185481Y1372872D03*
X183051D03*
X180621D03*
X186481Y1370147D03*
Y1367247D03*
X177605Y1382130D03*
X174117Y1380530D03*
X176855Y1379562D03*
X185558Y1418560D03*
Y1416060D03*
X183058Y1418560D03*
Y1416060D03*
X173164Y1406397D03*
Y1408897D03*
X172976Y1411460D03*
X173202Y1414249D03*
X185558Y1421060D03*
Y1423560D03*
Y1426060D03*
X183058Y1421060D03*
Y1426060D03*
Y1423560D03*
Y1428560D03*
X185558D03*
X172751Y1462595D03*
X179451Y1452895D03*
X176051D03*
X173490Y1542540D03*
X173050Y1555751D03*
Y1553251D03*
X178582Y1575390D03*
X181087Y1576135D03*
X178582Y1572490D03*
Y1569590D03*
X180292Y1582589D03*
X177792D03*
X177509Y1653825D03*
X177666Y1649223D03*
X183974Y1656804D03*
X183920Y1653973D03*
X184139Y1651088D03*
X180103Y1668921D03*
X177672Y1657538D03*
X183986Y1659548D03*
X182533Y1676854D03*
X185124Y1701851D03*
X185084Y1691988D03*
X179999Y1699156D03*
X185173Y1695138D03*
X178385Y1715441D03*
X183813Y1705404D03*
X178376Y1720559D03*
X185760Y1731666D03*
X200785Y26477D03*
X197385D03*
X194361Y69340D03*
X197761D03*
X204088Y138912D03*
X200577Y125502D03*
X190000Y143000D03*
X191264Y147768D03*
X193610Y153951D03*
X192592Y353072D03*
X188055Y731734D03*
X199718Y767400D03*
X197651Y769241D03*
X200365Y1312880D03*
Y1310380D03*
Y1307880D03*
Y1305380D03*
Y1300380D03*
Y1302880D03*
X188565Y1312880D03*
Y1310380D03*
Y1307880D03*
Y1305380D03*
Y1300380D03*
Y1302880D03*
X200365Y1315380D03*
Y1317880D03*
X188565Y1315380D03*
Y1317880D03*
X196301Y1369018D03*
Y1371559D03*
X192511Y1373177D03*
X197794Y1379933D03*
X200074Y1376408D03*
X188245Y1379207D03*
X190411Y1377577D03*
X192511Y1378977D03*
X190311Y1374577D03*
X188245Y1376307D03*
X192511Y1376077D03*
X200408Y1416249D03*
Y1418749D03*
X192983Y1417568D03*
X188058Y1416060D03*
Y1418560D03*
X190483Y1417568D03*
X197983D03*
X195483D03*
X188695Y1404813D03*
Y1407313D03*
X191995Y1404813D03*
Y1407313D03*
X194495Y1404813D03*
Y1407313D03*
X196995Y1404813D03*
Y1407313D03*
X199495Y1404813D03*
Y1407313D03*
X188507Y1409876D03*
X191807D03*
X194307D03*
X196807D03*
X199307D03*
X200558Y1421551D03*
X195483Y1420068D03*
X192983D03*
X195483Y1422568D03*
X197983D03*
X192983D03*
X188058Y1421060D03*
Y1423560D03*
X190483Y1420068D03*
Y1422568D03*
X197983Y1420068D03*
X188058Y1426060D03*
X199551Y1462595D03*
X196151D03*
X192851Y1472295D03*
X189451D03*
X193679Y1640052D03*
Y1643452D03*
X198698Y1662215D03*
X199747Y1675603D03*
X200424Y1686870D03*
X197780Y1696973D03*
X200478Y1701758D03*
X200448Y1690771D03*
X202076Y1717845D03*
X189760Y1713061D03*
X193274Y1709769D03*
X199843Y1709837D03*
X203510Y1712441D03*
X196763Y1710444D03*
X189760Y1723041D03*
Y1731564D03*
X194000Y1720551D03*
X203655Y1723000D03*
X198760Y1719991D03*
X207890Y19541D03*
X214958Y26477D03*
X204490Y19541D03*
X211558Y26477D03*
X216491Y69343D03*
X205495Y75340D03*
X208895D03*
X217687Y522453D03*
X214999Y585668D03*
X211254Y595145D03*
X208254D03*
X211009Y610001D03*
X208009D03*
X214202Y606943D03*
X208254Y603245D03*
X211254D03*
X214202Y609681D03*
X208326Y606918D03*
X211326D03*
X210199Y714074D03*
X206199D03*
X206254Y732537D03*
X206933Y737277D03*
X208818Y766871D03*
X205365Y1307880D03*
Y1310380D03*
Y1312880D03*
X202865D03*
Y1310380D03*
Y1307880D03*
X216165D03*
Y1310380D03*
Y1312880D03*
Y1305380D03*
Y1300380D03*
Y1302880D03*
X205365Y1305380D03*
X202865D03*
X205365Y1300380D03*
Y1302880D03*
X202865D03*
Y1300380D03*
X205365Y1315380D03*
X202865D03*
X216165D03*
Y1317880D03*
X205365D03*
X202865D03*
X213521Y1372872D03*
X215951D03*
X203063Y1382593D03*
Y1380085D03*
X210505Y1382130D03*
X207017Y1380530D03*
X209755Y1379562D03*
X205558Y1418560D03*
Y1416060D03*
X202945Y1415910D03*
Y1418410D03*
X208058Y1416060D03*
X208061Y1418605D03*
X206251Y1452895D03*
X202851D03*
X216251Y1472295D03*
X205479Y1652130D03*
Y1648730D03*
X206788Y1660960D03*
X210833Y1660867D03*
X210217Y1668603D03*
X207807Y1681302D03*
Y1696409D03*
X211862Y1701100D03*
X212365Y1705403D03*
X211000Y1717675D03*
X222063Y19541D03*
X218663D03*
X229131Y26477D03*
X225731D03*
X229127Y50649D03*
X225727D03*
X227495Y75340D03*
X230895D03*
X219891Y69343D03*
X233284Y137195D03*
X221051Y153167D03*
X223687Y522453D03*
X229687D03*
X226599Y570970D03*
X217999Y585668D03*
X223999D03*
X220999D03*
X217202Y606943D03*
X220202D03*
X223202D03*
X223111Y603782D03*
X225895Y609691D03*
X228895D03*
X220111Y603782D03*
X217202Y609681D03*
X220202D03*
X223202D03*
X218024Y622385D03*
X221024D03*
X224024D03*
X227024D03*
X221024Y632385D03*
X218024D03*
X224024D03*
X227024D03*
X224157Y715915D03*
Y712915D03*
X229263Y765863D03*
X229275Y769292D03*
X218665Y1312880D03*
Y1310380D03*
Y1307880D03*
X221165Y1312880D03*
Y1310380D03*
Y1307880D03*
Y1305380D03*
X218665D03*
X221165Y1300380D03*
Y1302880D03*
X218665D03*
Y1300380D03*
Y1315380D03*
X221165D03*
Y1317880D03*
X218665D03*
X229101Y1369018D03*
Y1371559D03*
X218381Y1372872D03*
X219401Y1370067D03*
Y1367167D03*
X225411Y1373177D03*
X230594Y1379933D03*
X225411Y1378977D03*
Y1376077D03*
X221145Y1379207D03*
X223311Y1377577D03*
X223211Y1374577D03*
X221145Y1376307D03*
X226351Y1462595D03*
X222951D03*
X229651Y1452895D03*
X219651Y1472295D03*
X238059Y26235D03*
X233335Y17665D03*
X235697Y21585D03*
X241306Y20325D03*
X246356Y26855D03*
X246506Y20365D03*
X242216Y39365D03*
X246216D03*
X238059Y37165D03*
X235697Y39755D03*
X248816Y48965D03*
X239816Y54365D03*
X248487Y68690D03*
X242920Y67915D03*
X238846Y72977D03*
X235186Y98067D03*
X234331Y103286D03*
X232529Y114830D03*
X238297Y121555D03*
X244818Y111546D03*
Y115546D03*
X235460Y115790D03*
X235186Y112022D03*
X238600Y130400D03*
X235147Y124435D03*
X243813Y132383D03*
X241271Y130719D03*
X234000Y148000D03*
X239988Y141986D03*
X236104Y151996D03*
X245486Y159705D03*
X234628Y166735D03*
X240413Y360867D03*
X233413D03*
X235913D03*
X243845Y656940D03*
X246045Y655540D03*
X243845Y651140D03*
Y654040D03*
X245945Y652540D03*
X232981Y743983D03*
X240200Y766300D03*
X246371Y772388D03*
X232965Y1297880D03*
X237965D03*
X235465D03*
Y1300380D03*
Y1302880D03*
X237965D03*
Y1300380D03*
X235465Y1305380D03*
X237965D03*
X232965Y1302880D03*
Y1300380D03*
Y1305380D03*
Y1307880D03*
Y1310380D03*
Y1312880D03*
X237965Y1307880D03*
Y1310380D03*
Y1312880D03*
X235465D03*
Y1310380D03*
Y1307880D03*
X237965Y1315380D03*
X235465D03*
X232965D03*
X246321Y1372872D03*
X235863Y1380085D03*
X243305Y1382130D03*
X239817Y1380530D03*
X242555Y1379562D03*
X235863Y1382593D03*
X232874Y1376408D03*
X233051Y1452895D03*
X246451Y1472295D03*
X243051D03*
X255106Y16615D03*
X251106Y12615D03*
X250216Y39365D03*
X254046Y39425D03*
X259316Y48965D03*
X261016Y51565D03*
X252316Y48965D03*
X255816D03*
X254016Y51565D03*
X250516D03*
X257516D03*
X247893Y100546D03*
X248093Y92146D03*
X261416Y100665D03*
X253874Y111774D03*
X252800Y114800D03*
X256586Y138373D03*
X260596Y151065D03*
X248350Y165700D03*
X257252Y156730D03*
X258439Y214000D03*
X247859Y375389D03*
X250359D03*
X254859D03*
X247694Y378523D03*
X250194D03*
X254694D03*
X258751Y647987D03*
X262239Y649587D03*
X259501Y650555D03*
X255735Y657245D03*
X253305D03*
X250875D03*
X248111Y653810D03*
Y650910D03*
X250312Y663080D03*
Y660180D03*
X247587Y714760D03*
Y717260D03*
X252591Y714737D03*
Y717237D03*
X250091D03*
Y714737D03*
X247587Y712237D03*
X250087D03*
X252587D03*
X247587Y719760D03*
X252591Y719737D03*
X250091D03*
X247587Y724760D03*
X252587D03*
X250087D03*
X247587Y722260D03*
Y727260D03*
X250087Y729760D03*
X247587D03*
X250087Y727260D03*
X252587D03*
Y729760D03*
X252591Y722237D03*
X250091D03*
X254671Y776388D03*
X257071Y772770D03*
X260971Y777988D03*
X248765Y1297880D03*
X251265D03*
X248765Y1292880D03*
Y1295380D03*
X251265D03*
Y1292880D03*
X248765Y1307880D03*
Y1310380D03*
Y1312880D03*
X251265D03*
Y1310380D03*
Y1307880D03*
X248765Y1305380D03*
X251265D03*
X248765Y1300380D03*
Y1302880D03*
X251265D03*
Y1300380D03*
X248765Y1315380D03*
X251265D03*
Y1317880D03*
X248765D03*
X248751Y1372872D03*
X251181D03*
X252211Y1370232D03*
Y1367332D03*
X258211Y1373177D03*
X256111Y1377577D03*
X258211Y1378977D03*
X256011Y1374577D03*
X258211Y1376077D03*
X253945Y1379207D03*
Y1376307D03*
X253151Y1462595D03*
X259851Y1452895D03*
X249751Y1462595D03*
X256451Y1452895D03*
X261530Y1550300D03*
X275116Y28565D03*
X275896Y48875D03*
X266420Y39120D03*
X265365Y49171D03*
X263516Y51565D03*
X261816Y48965D03*
X263182Y73396D03*
X269860Y72741D03*
X262893Y77529D03*
Y80029D03*
X263316Y87665D03*
X275238Y83024D03*
X264916Y100665D03*
X268416D03*
X262916Y97965D03*
X266416D03*
X269916D03*
X273616Y96665D03*
X264293Y120972D03*
X269487Y121095D03*
X275793Y120248D03*
X266000Y125800D03*
X275793Y129595D03*
X266971Y140110D03*
X264574Y151206D03*
X276821Y140465D03*
X270178Y140322D03*
X262500Y161100D03*
X273500Y207500D03*
X266360Y203070D03*
X269925Y217700D03*
X274993Y522052D03*
X269568Y522366D03*
X266327Y522456D03*
X274096Y574698D03*
X273208Y588237D03*
X267601Y608378D03*
X271462Y650184D03*
X266193Y650032D03*
X272955Y658558D03*
X266193Y647524D03*
X269182Y653709D03*
X272955Y661099D03*
X276575Y685381D03*
Y688281D03*
Y691181D03*
X265891Y714737D03*
Y717237D03*
X263391D03*
Y714737D03*
X263387Y712237D03*
X265887D03*
X265891Y719737D03*
X263391D03*
X265787Y724760D03*
X263287D03*
X265787Y727260D03*
X263287D03*
X265787Y729760D03*
X263287D03*
X265787Y732260D03*
X263287D03*
X265891Y722237D03*
X263391D03*
X265787Y737260D03*
X263287D03*
X265787Y734760D03*
X263287D03*
X271161Y780588D03*
X268991Y783248D03*
X271245Y785474D03*
X274282Y786741D03*
X272054Y801112D03*
X270850Y797605D03*
X272165Y1256716D03*
X269665Y1259216D03*
X272165D03*
X269765Y1269234D03*
X272265D03*
X269765Y1261734D03*
Y1264234D03*
Y1266734D03*
X272265D03*
Y1264234D03*
Y1261734D03*
X267179Y1269273D03*
Y1266773D03*
Y1264273D03*
Y1261773D03*
Y1271773D03*
X269679D03*
X272179D03*
X262701Y1322872D03*
Y1325413D03*
X264194Y1333787D03*
X269463Y1333939D03*
X273417Y1334384D03*
X276155Y1333416D03*
X269463Y1336447D03*
X266474Y1330262D03*
X269851Y1452895D03*
X273251D03*
X269829Y1521436D03*
X273597Y1519845D03*
X269144Y1511953D03*
X273474Y1516120D03*
Y1512220D03*
X269144Y1514453D03*
Y1516953D03*
X267322Y1519250D03*
X276624Y1516120D03*
Y1512220D03*
X276637Y1521436D03*
X274546Y1549295D03*
Y1546795D03*
X267297Y1546119D03*
X286996Y20365D03*
X290795Y28365D03*
X284228Y25935D03*
X280828D03*
X282716Y40020D03*
X290716D03*
X287988Y54893D03*
X291379Y55746D03*
X293157Y50525D03*
X284226Y50649D03*
X280826D03*
X278638Y83024D03*
X288553Y105006D03*
X285353D03*
X280853Y109906D03*
X282853Y115606D03*
X285853D03*
X280853Y107306D03*
X286996Y139865D03*
X283049Y139731D03*
X288000Y209000D03*
X290000Y222575D03*
X289163Y212503D03*
X278425Y230925D03*
X289393Y498960D03*
X278547Y523041D03*
X284018Y522300D03*
X287723Y548499D03*
X289421Y575098D03*
X291481Y682228D03*
X280841Y688051D03*
X278675Y686781D03*
X280841Y685151D03*
X288465Y691493D03*
X283605D03*
X286035D03*
X278775Y689781D03*
X283042Y697280D03*
Y694380D03*
X285317Y746478D03*
X282817D03*
X280317D03*
Y759110D03*
X285317D03*
X282817D03*
X285317Y761610D03*
X285321Y748978D03*
Y751478D03*
Y753978D03*
X282821D03*
Y751478D03*
Y748978D03*
X285321Y756478D03*
X282821D03*
X280317Y756610D03*
Y751610D03*
Y754110D03*
Y749110D03*
Y761610D03*
X282817D03*
X284035Y796850D03*
X285258Y799314D03*
X282323Y794867D03*
X281449Y809609D03*
X283987Y811342D03*
X285565Y1246716D03*
X288065D03*
X283065D03*
X288065Y1251716D03*
X285565D03*
X283065D03*
X288065Y1249216D03*
X285565D03*
X283065D03*
Y1254216D03*
X288065D03*
X285565D03*
X283065Y1269234D03*
X285565D03*
X283065Y1261734D03*
Y1264234D03*
Y1266734D03*
X285565D03*
Y1264234D03*
Y1261734D03*
X283065Y1256716D03*
X285565D03*
X288065D03*
X283065Y1259216D03*
X285565D03*
X288065D03*
Y1266716D03*
Y1264216D03*
Y1261716D03*
Y1269216D03*
X285479Y1271773D03*
X282979D03*
X287979D03*
X284781Y1326726D03*
X282351D03*
X279921D03*
X285891Y1320942D03*
Y1323842D03*
X289611Y1328431D03*
X276905Y1335984D03*
X289711Y1331431D03*
X287545Y1330161D03*
Y1333061D03*
X280621Y1484082D03*
Y1480682D03*
X291175Y1483590D03*
Y1480190D03*
X280621Y1497482D03*
Y1494082D03*
X291175Y1501990D03*
Y1505390D03*
X280088Y1509469D03*
X282588D03*
X279774Y1512220D03*
Y1516120D03*
X284024Y1514576D03*
X279499Y1519845D03*
X284024Y1512076D03*
X290593Y1523331D03*
Y1526731D03*
X291416Y1541795D03*
Y1549295D03*
Y1546795D03*
Y1544295D03*
X285586Y1551844D03*
X288004Y1551099D03*
X290509Y1551844D03*
X288004Y1548199D03*
X284014Y1538682D03*
X286514D03*
X284546Y1549295D03*
Y1546795D03*
Y1541795D03*
Y1544295D03*
X287046D03*
Y1541795D03*
X277046Y1546795D03*
Y1549295D03*
X282046D03*
Y1546795D03*
Y1544295D03*
X279546Y1549295D03*
Y1546795D03*
X282046Y1541795D03*
X300230Y14820D03*
X302606Y26365D03*
X292056Y24475D03*
X295516Y26365D03*
X300244Y28365D03*
X299496Y22865D03*
X304923Y24657D03*
X304968Y28365D03*
X303252Y38199D03*
X298716Y40020D03*
X296337Y55855D03*
X301306Y52485D03*
X298542Y51088D03*
X303711Y50860D03*
X295755Y72800D03*
X301107Y75676D03*
X305820Y73693D03*
X303852Y65042D03*
X306470Y65160D03*
X301780Y82900D03*
X299002Y88700D03*
X307816Y95727D03*
X301179Y112806D03*
Y110006D03*
Y107106D03*
X296478Y149203D03*
X296474Y158706D03*
X292811Y213242D03*
X296283Y242391D03*
X306528Y256528D03*
X297815Y580384D03*
X294299Y577188D03*
X302130Y584160D03*
X304192Y684425D03*
X298923Y684273D03*
X294969Y683828D03*
X292231Y684796D03*
X298923Y681765D03*
X301912Y687950D03*
X305685Y695340D03*
Y692799D03*
X298617Y746478D03*
X296117D03*
X301117D03*
X298621Y753978D03*
X296121D03*
Y751478D03*
Y748978D03*
X298621Y756478D03*
X296121D03*
X301121Y748996D03*
Y751496D03*
Y753996D03*
Y756496D03*
X296117Y759110D03*
Y761610D03*
X301117Y759110D03*
X298617D03*
X301117Y761610D03*
X298617D03*
X298621Y748978D03*
Y751478D03*
X301117Y766610D03*
X296117D03*
Y764110D03*
X301117Y771610D03*
X298617D03*
Y769110D03*
X301117D03*
X296117Y771610D03*
Y769110D03*
X298617Y766610D03*
Y764110D03*
X301117D03*
X305061Y1254131D03*
X300061D03*
X302561D03*
X305061Y1249131D03*
Y1251631D03*
X300061D03*
X302561D03*
X300061Y1249131D03*
X302561D03*
X305061Y1246631D03*
X300061D03*
X302561D03*
X302661Y1269149D03*
X305161D03*
X302661Y1261649D03*
Y1264149D03*
Y1266649D03*
X305161D03*
Y1264149D03*
Y1261649D03*
X300061Y1269131D03*
Y1266631D03*
X305061Y1259131D03*
Y1256631D03*
X300061D03*
Y1259131D03*
Y1261631D03*
Y1264131D03*
X302561Y1256631D03*
Y1259131D03*
X305075Y1271688D03*
X302575D03*
X300075D03*
X295597Y1322844D03*
Y1325385D03*
X291811Y1327031D03*
X297090Y1333759D03*
X302359Y1333911D03*
X306313Y1334356D03*
X302359Y1336419D03*
X299370Y1330234D03*
X291811Y1332831D03*
Y1329931D03*
X294725Y1381612D03*
X294533Y1384401D03*
X305204Y1381461D03*
X305012Y1384250D03*
X294684Y1387040D03*
X305163Y1386889D03*
X294683Y1390281D03*
X305163Y1389678D03*
X300813Y1462595D03*
X297413D03*
X304113Y1452895D03*
X295042Y1530596D03*
X296416Y1549295D03*
X293916D03*
Y1546795D03*
X296416D03*
Y1544295D03*
X293916D03*
X296416Y1541795D03*
X293916D03*
X298916D03*
Y1549295D03*
Y1546795D03*
Y1544295D03*
X303041Y1544299D03*
X310396Y50365D03*
X306566Y50225D03*
X323036Y73125D03*
X310455Y75895D03*
X320190Y77648D03*
X314653Y71806D03*
Y68906D03*
X312410Y89060D03*
X322871Y84321D03*
X316982Y89003D03*
X311053Y112806D03*
Y110006D03*
Y107106D03*
X323646Y147120D03*
Y152120D03*
X308240Y148100D03*
X317472Y222262D03*
Y225217D03*
X319970Y228167D03*
X320095Y231810D03*
X319075Y260075D03*
X311749Y440921D03*
X314780Y545716D03*
X322955Y556148D03*
X310445Y700931D03*
X312611Y702301D03*
X321235Y711636D03*
X316375D03*
X318805D03*
X311545Y709931D03*
X310445Y703931D03*
X311445Y706931D03*
X313611Y708201D03*
Y705301D03*
X315912Y717400D03*
Y714500D03*
X313087Y769160D03*
Y771660D03*
Y774160D03*
Y776660D03*
X318091Y769128D03*
Y771628D03*
Y774128D03*
X315591D03*
Y771628D03*
Y769128D03*
X318091Y776628D03*
X315591D03*
X313087Y766628D03*
X315587D03*
X318087D03*
Y791660D03*
X313087D03*
X315587D03*
X318087Y789160D03*
X313087D03*
X315587D03*
Y779160D03*
X313087Y784160D03*
X315587D03*
X313087Y786660D03*
X315587D03*
X313087Y781660D03*
X315587D03*
X313087Y779160D03*
X318087Y786660D03*
Y784160D03*
Y779160D03*
Y781660D03*
X313284Y1218522D03*
Y1215122D03*
X318461Y1254131D03*
X320961D03*
X315961D03*
Y1249131D03*
X318461D03*
X320961D03*
X315961Y1251631D03*
X318461D03*
X320961D03*
X315961Y1246631D03*
X318461D03*
X320961D03*
X315961Y1269149D03*
X318461D03*
X315961Y1261649D03*
Y1264149D03*
Y1266649D03*
X318461D03*
Y1264149D03*
Y1261649D03*
X320961Y1269131D03*
Y1256631D03*
Y1259131D03*
Y1261631D03*
X318461Y1256631D03*
Y1259131D03*
X320961Y1264131D03*
Y1266631D03*
X315961Y1256631D03*
Y1259131D03*
X320875Y1271688D03*
X315875D03*
X318375D03*
X312817Y1326698D03*
X315247D03*
X317677D03*
X318811Y1320902D03*
Y1323802D03*
X309801Y1335956D03*
X309051Y1333388D03*
X320441Y1330133D03*
Y1333033D03*
X307513Y1452895D03*
X320913Y1472295D03*
X317513D03*
X323113Y76941D03*
X334339Y162580D03*
X323646Y160120D03*
Y156120D03*
X331780Y182900D03*
X336000Y284000D03*
X324406Y367744D03*
X325816Y543012D03*
X324647Y566086D03*
X334031Y613498D03*
Y610498D03*
X331391D03*
Y613498D03*
X333502Y600019D03*
Y603019D03*
X330109Y602883D03*
Y605883D03*
X334031Y619398D03*
Y616498D03*
X331391D03*
Y619398D03*
X324251Y702378D03*
X331693Y701915D03*
Y704423D03*
X327739Y703978D03*
X325001Y704946D03*
X334682Y708100D03*
X331391Y769128D03*
Y771628D03*
Y774128D03*
X328891D03*
Y771628D03*
Y769128D03*
X331391Y776628D03*
X328891D03*
X333887Y766628D03*
X328887D03*
X331387D03*
X333891Y776646D03*
Y774146D03*
Y771646D03*
Y769146D03*
X333887Y791660D03*
X328887D03*
X331387D03*
X333887Y789160D03*
X328887D03*
X331387D03*
X333887Y779160D03*
Y781660D03*
X331387Y779160D03*
X328887D03*
Y781660D03*
X331387D03*
X333887Y786660D03*
X328887D03*
X331387D03*
X333887Y784160D03*
X328887D03*
X331387D03*
X335465Y1246631D03*
X332965D03*
X335465Y1249131D03*
X332965D03*
X335465Y1251631D03*
X332965D03*
X335465Y1254131D03*
X332965D03*
X335465Y1259131D03*
Y1256631D03*
X332965Y1259131D03*
Y1256631D03*
X335565Y1269149D03*
Y1261649D03*
Y1264149D03*
Y1266649D03*
X332961Y1269188D03*
Y1266688D03*
Y1261688D03*
Y1264188D03*
Y1271688D03*
X335461D03*
X328501Y1322787D03*
Y1325328D03*
X324707Y1327003D03*
X322507Y1328403D03*
X329994Y1333702D03*
X335263Y1333854D03*
Y1336362D03*
X332274Y1330177D03*
X324707Y1332803D03*
X322607Y1331403D03*
X324707Y1329903D03*
X334038Y1373469D03*
X334230Y1370680D03*
X323559Y1373620D03*
X323751Y1370831D03*
X334189Y1376108D03*
X323710Y1376259D03*
X334189Y1378897D03*
X323709Y1379500D03*
X327613Y1462595D03*
X334313Y1452895D03*
X324213Y1462595D03*
X330913Y1452895D03*
X341082Y56308D03*
X340436Y120555D03*
X343446Y131170D03*
X338244Y192264D03*
X344984Y199299D03*
X344106Y222659D03*
X348107Y220420D03*
X341895Y233980D03*
X348645Y229180D03*
X352000Y230643D03*
Y235643D03*
X344034Y282609D03*
X348890Y409120D03*
Y411620D03*
X340337Y496462D03*
X346751Y515376D03*
X351157Y550415D03*
X350566Y541882D03*
X351018Y554896D03*
X351157Y566936D03*
X345521Y564388D03*
X349397Y564459D03*
X351157Y570415D03*
X341500Y574500D03*
X342500Y582500D03*
Y578500D03*
X338420Y574500D03*
X351157Y590415D03*
Y586415D03*
X337031Y607498D03*
Y613498D03*
Y610498D03*
X346031Y607498D03*
X343031D03*
X349031D03*
X346031Y610498D03*
X343031D03*
X349031D03*
X340031Y607498D03*
Y610498D03*
Y613498D03*
X346031Y604498D03*
X343031D03*
X349031D03*
X340031D03*
X343691Y614018D03*
X346191D03*
X348691D03*
X343721Y618348D03*
X346221D03*
X348721D03*
X351191Y614018D03*
X351221Y618348D03*
X340031Y619398D03*
Y616498D03*
X337031Y619398D03*
Y616498D03*
X342675Y640994D03*
X345175D03*
X347675D03*
X350175D03*
X342675Y643494D03*
X345175D03*
X347675D03*
X350175D03*
X342595Y646054D03*
X345095D03*
X347595D03*
X350095D03*
X336962Y704575D03*
X338455Y715490D03*
Y712949D03*
X349435Y711368D03*
X346671Y705033D03*
X344505Y706663D03*
X346671Y707933D03*
X344605Y709663D03*
X342405Y705263D03*
Y708163D03*
Y711063D03*
X348395Y717060D03*
Y714160D03*
X346051Y769058D03*
Y771558D03*
Y774058D03*
Y776558D03*
X351151Y769040D03*
Y771540D03*
Y774040D03*
X348651D03*
Y771540D03*
Y769040D03*
X351151Y776540D03*
X348651D03*
X351147Y766540D03*
X348647D03*
X346147D03*
X346051Y791558D03*
X348551D03*
X351051D03*
X346051Y789058D03*
X348551D03*
X346051Y784058D03*
X348551D03*
X346051Y786558D03*
X348551D03*
X346051Y779058D03*
X348551D03*
X346051Y781558D03*
X348551D03*
X351051Y789058D03*
Y784058D03*
Y786558D03*
Y779058D03*
Y781558D03*
X347107Y1174343D03*
X339278Y1192112D03*
X336778D03*
X347885Y1206426D03*
X339532Y1218605D03*
X349938Y1214563D03*
X337965Y1251631D03*
Y1249131D03*
Y1254131D03*
X348865Y1246631D03*
Y1251631D03*
Y1249131D03*
Y1254131D03*
X337965Y1246631D03*
X348865Y1269149D03*
Y1261649D03*
Y1264149D03*
Y1266649D03*
X338065Y1269149D03*
Y1266649D03*
Y1264149D03*
Y1261649D03*
X337965Y1256631D03*
Y1259131D03*
X348865D03*
Y1256631D03*
X337961Y1271688D03*
X348861D03*
X348151Y1326641D03*
X350581D03*
X345721D03*
X342705Y1335899D03*
X339217Y1334299D03*
X341955Y1333331D03*
X346464Y1380102D03*
X343964D03*
X348964D03*
Y1387602D03*
Y1385102D03*
Y1382602D03*
X343964Y1385102D03*
Y1387602D03*
X346464Y1385102D03*
Y1387602D03*
X343964Y1382602D03*
X346464D03*
X348964Y1390102D03*
X343964D03*
Y1392602D03*
X346464D03*
Y1390102D03*
X343777Y1395166D03*
X346302Y1395242D03*
X348828Y1395392D03*
X349032Y1392675D03*
X351013Y1462595D03*
X347713Y1472295D03*
X344313D03*
X361744Y120713D03*
X363621Y127665D03*
X361171Y223114D03*
X358618Y223129D03*
X361171Y220614D03*
X358671D03*
X355910Y223847D03*
X365739Y221871D03*
X365559Y238896D03*
X357925Y304082D03*
X351390Y409120D03*
X353890D03*
Y411620D03*
X351390D03*
X365852Y516466D03*
X365071Y551038D03*
X355100Y544390D03*
X362200Y566750D03*
X364047Y556773D03*
X359200Y566990D03*
X360261Y561044D03*
X359657Y570702D03*
X359157Y574415D03*
X365158Y597546D03*
Y593580D03*
X352031Y607498D03*
Y610498D03*
X355031Y607498D03*
Y613498D03*
Y610498D03*
X352031Y604498D03*
X355031D03*
X361031Y607498D03*
Y613498D03*
Y610498D03*
X358031Y607498D03*
Y613498D03*
Y610498D03*
Y604498D03*
Y619398D03*
Y616498D03*
X355031Y619398D03*
Y616498D03*
X361031Y619398D03*
Y616498D03*
X352675Y640994D03*
Y643494D03*
X355275Y641034D03*
Y643534D03*
X355195Y646094D03*
X352595Y646054D03*
X357311Y702110D03*
X364753Y701647D03*
Y704155D03*
X360799Y703710D03*
X358061Y704678D03*
X351865Y711368D03*
X354295D03*
X364451Y769040D03*
Y771540D03*
Y774040D03*
X361951D03*
Y771540D03*
Y769040D03*
X364451Y776540D03*
X361951D03*
X364447Y766540D03*
X361947D03*
X364451Y791558D03*
X361951D03*
X364451Y786558D03*
Y789058D03*
X361951D03*
Y786558D03*
X364451Y784058D03*
X361951Y781558D03*
X364451Y779058D03*
Y781558D03*
X361951Y779058D03*
Y784058D03*
X361671Y803588D03*
X356671D03*
X351671D03*
X363313Y812088D03*
X359813Y812188D03*
X356313D03*
X352813D03*
X356535Y849708D03*
X364897Y852564D03*
X364821Y861852D03*
X357400Y855982D03*
X356895Y859791D03*
X353281Y859620D03*
X363236Y1199632D03*
X361922Y1206891D03*
X357271Y1208988D03*
X351413Y1210052D03*
X365461Y1254188D03*
Y1251688D03*
Y1249188D03*
Y1246688D03*
X351365Y1246631D03*
X353865D03*
Y1251631D03*
X351365D03*
X353865Y1249131D03*
X351365D03*
X353865Y1254131D03*
X351365D03*
Y1269149D03*
Y1266649D03*
Y1264149D03*
Y1261649D03*
X365461Y1256688D03*
Y1259188D03*
X353865Y1266631D03*
Y1264131D03*
Y1261631D03*
Y1269131D03*
X351365Y1259131D03*
Y1256631D03*
X353865Y1259131D03*
Y1256631D03*
X365561Y1269288D03*
Y1264288D03*
Y1266788D03*
Y1261788D03*
Y1271788D03*
X351361Y1271688D03*
X353861D03*
X361301Y1322987D03*
Y1325528D03*
X351651Y1320942D03*
Y1323842D03*
X357611Y1326946D03*
X355411Y1328346D03*
X362794Y1333902D03*
X365074Y1330377D03*
X353345Y1332976D03*
X357611Y1329846D03*
X353345Y1330076D03*
X355511Y1331346D03*
X357611Y1332746D03*
X356764Y1359296D03*
X354264D03*
X364764D03*
X362264D03*
X359764D03*
X351632Y1359203D03*
X351923Y1364724D03*
X354423D03*
X356923D03*
X359423D03*
X362223D03*
X364723D03*
X351772Y1362085D03*
X354272D03*
X356772D03*
X359272D03*
X362072D03*
X364572D03*
X363964Y1385102D03*
X356464Y1380102D03*
X358964D03*
X361464D03*
X353964D03*
X351464D03*
X363964D03*
Y1382602D03*
X351464Y1385102D03*
X353964D03*
X361464D03*
X356464D03*
X358964D03*
X351464Y1382602D03*
X361464D03*
X358964D03*
X356464D03*
X353964D03*
X352067Y1387665D03*
X354567D03*
X357067D03*
X359567D03*
X363190Y1387527D03*
X365979Y1387641D03*
X352332Y1391886D03*
X354832D03*
X357332D03*
X359832D03*
X363191Y1390292D03*
Y1392792D03*
X365980Y1392906D03*
Y1390406D03*
X363003Y1395393D03*
X365792Y1395507D03*
X352313Y1395223D03*
X359859D03*
X357208D03*
X354413Y1462595D03*
X361113Y1452895D03*
X357713D03*
X365493Y1655107D03*
X370888Y155250D03*
X377118Y222229D03*
X380012Y239615D03*
X370327Y228951D03*
X370352Y235455D03*
X366671Y297114D03*
X369171D03*
X369671Y292114D03*
Y294614D03*
X380935Y443386D03*
X375935D03*
X378435D03*
X382184Y466351D03*
X378976Y479226D03*
X379633Y493942D03*
X371962Y524954D03*
X368371Y553038D03*
X371971Y553138D03*
X375410Y552254D03*
X377502Y554193D03*
X380157Y553090D03*
X375271Y542191D03*
X379114Y544866D03*
X368647Y550422D03*
X370271Y555038D03*
X379689Y586040D03*
X368798Y587938D03*
X369271Y600138D03*
X373477Y593338D03*
X378577Y593026D03*
X377577Y590126D03*
X370022Y704307D03*
X371515Y715222D03*
Y712681D03*
X367742Y707832D03*
X379711Y708001D03*
Y705101D03*
X375445Y708231D03*
X377545Y706731D03*
X375445Y705331D03*
X377645Y709731D03*
X375445Y711131D03*
X366951Y769058D03*
Y771558D03*
Y774058D03*
Y776558D03*
X379187Y766428D03*
Y768960D03*
Y771460D03*
Y773960D03*
Y776460D03*
X366947Y766540D03*
X366951Y781558D03*
Y786558D03*
Y789058D03*
Y784058D03*
X379187Y786460D03*
Y783960D03*
Y788960D03*
Y778960D03*
Y781460D03*
X366951Y791558D03*
X379187Y791460D03*
X366951Y779058D03*
X376671Y803588D03*
X371671D03*
X366671D03*
X371999Y819527D03*
X372000Y831797D03*
Y835197D03*
X371999Y822927D03*
X372000Y846427D03*
Y843027D03*
X366864Y857274D03*
X369626Y860717D03*
X370316Y1204673D03*
X367931Y1196981D03*
X376271Y1207488D03*
X380718Y1221906D03*
X379223Y1219527D03*
X372126Y1214455D03*
X368726D03*
X367961Y1254188D03*
Y1251688D03*
Y1249188D03*
Y1246688D03*
X370461Y1254188D03*
Y1249188D03*
Y1251688D03*
Y1246688D03*
X367961Y1256688D03*
Y1259188D03*
X370461D03*
Y1256688D03*
X368061Y1269206D03*
X370561D03*
X368061Y1261706D03*
Y1264206D03*
Y1266706D03*
X370561D03*
Y1264206D03*
Y1261706D03*
Y1271788D03*
X368061D03*
X380951Y1326841D03*
X378521D03*
X368063Y1334054D03*
X375505Y1336099D03*
X372017Y1334499D03*
X374755Y1333531D03*
X368063Y1336562D03*
X368964Y1382602D03*
Y1385102D03*
X366464D03*
X368964Y1380102D03*
X366464D03*
Y1382602D03*
X368542Y1387639D03*
X368543Y1390404D03*
Y1392904D03*
X368355Y1395505D03*
X377813Y1462595D03*
X374513Y1472295D03*
X371113D03*
X374432Y1582600D03*
X375050Y1639400D03*
X371823Y1644516D03*
X370533Y1658605D03*
X374962Y1648511D03*
X372953Y1653197D03*
X373330Y1668539D03*
X370369Y1661817D03*
X372449Y1680520D03*
X372395Y1677449D03*
X395048Y121178D03*
X384375Y147365D03*
X386350Y138980D03*
X395590Y147010D03*
X391310Y227871D03*
X389912Y280345D03*
X390881Y284156D03*
X395053Y318125D03*
X383525Y443386D03*
X389784Y476070D03*
X384827Y507057D03*
X397184Y507101D03*
X382184D03*
X388985Y554870D03*
X383071Y553738D03*
X382705Y546433D03*
X395171Y559463D03*
X395669Y563328D03*
X385318Y555238D03*
X394168Y568482D03*
X395157Y573815D03*
X393481Y571239D03*
X387103Y584506D03*
X392471Y596988D03*
X391021Y588788D03*
X390351Y702178D03*
X393839Y703778D03*
X391101Y704746D03*
X382475Y711436D03*
X387335D03*
X384905D03*
X381812Y717060D03*
Y714160D03*
X394987Y766428D03*
X381687D03*
X384187D03*
X394991Y773928D03*
Y771428D03*
Y768928D03*
Y776428D03*
X384191Y768928D03*
Y771428D03*
Y773928D03*
X381691D03*
Y771428D03*
Y768928D03*
X384191Y776428D03*
X381691D03*
X381687Y791460D03*
X384187D03*
X394987Y784060D03*
Y779060D03*
Y781560D03*
Y789060D03*
Y786560D03*
X381687Y778960D03*
Y786460D03*
Y783960D03*
Y788960D03*
Y781460D03*
X384187Y788960D03*
Y786460D03*
Y783960D03*
Y778960D03*
Y781460D03*
X385001Y816927D03*
Y813527D03*
X386381Y1015474D03*
X393861D03*
X386381Y1022560D03*
Y1019017D03*
X393861Y1022560D03*
Y1019017D03*
X390974Y1222849D03*
Y1219449D03*
X388630Y1236747D03*
X381361Y1254188D03*
Y1249188D03*
Y1251688D03*
Y1246688D03*
X383861Y1254188D03*
X386361D03*
X383861Y1249188D03*
X386361D03*
X383861Y1251688D03*
X386361D03*
X383861Y1246688D03*
X386361D03*
X388630Y1240147D03*
X381361Y1269206D03*
X383861D03*
X381361Y1261706D03*
Y1264206D03*
Y1266706D03*
X383861D03*
Y1264206D03*
Y1261706D03*
X381361Y1256688D03*
Y1259188D03*
X386361Y1256688D03*
Y1259188D03*
X383861Y1256688D03*
Y1259188D03*
X386361Y1269288D03*
Y1261788D03*
Y1266788D03*
Y1264288D03*
X381361Y1271788D03*
X386361D03*
X383861D03*
X383381Y1326841D03*
X384481Y1321192D03*
Y1324092D03*
X388211Y1328546D03*
X393883Y1342318D03*
X388311Y1331546D03*
X386145Y1333176D03*
Y1330276D03*
X386611Y1336056D03*
X388771Y1337546D03*
Y1334546D03*
X395376Y1353233D03*
X393883Y1344859D03*
X381213Y1462595D03*
X387913Y1452895D03*
X384513D03*
X395384Y1519250D03*
X395359Y1546519D03*
X389290Y1561250D03*
X387939Y1565534D03*
X389276Y1568413D03*
X391526Y1582373D03*
X394521Y1575891D03*
X388784Y1581801D03*
X393005Y1592304D03*
X381711Y1593842D03*
X381607Y1590393D03*
X388445Y1585898D03*
X389333Y1598816D03*
X387805Y1617302D03*
Y1614802D03*
X394824Y1629713D03*
X394000Y1621500D03*
X389824Y1629713D03*
X389000Y1621500D03*
X384824Y1629713D03*
X381350Y1649000D03*
Y1642900D03*
Y1645800D03*
X382115Y1661545D03*
X387324Y1680495D03*
X392324D03*
X382642Y1680979D03*
X385068Y1683502D03*
X410500Y104883D03*
X410400Y107383D03*
X399264Y121144D03*
X400426Y112815D03*
Y116215D03*
X405606Y125815D03*
Y129715D03*
X403141Y148300D03*
X410678Y159140D03*
X408603Y152278D03*
X411299Y212096D03*
X400000Y220300D03*
X411940Y240501D03*
X410000Y304000D03*
X402184Y466469D03*
X410984Y496649D03*
X406184Y507900D03*
X403657Y546915D03*
X408550Y557850D03*
X404871Y567338D03*
X403381Y573516D03*
X410111Y572608D03*
X407543Y577415D03*
Y580490D03*
X408445Y687531D03*
X397793Y701715D03*
X410645Y691931D03*
X410545Y688931D03*
X408445Y690431D03*
Y693331D03*
X403062Y704375D03*
X397793Y704223D03*
X404555Y715290D03*
Y712749D03*
X400782Y707900D03*
X399991Y776560D03*
X397491Y768928D03*
Y771428D03*
Y773928D03*
Y776428D03*
X397487Y766428D03*
X399991Y771560D03*
Y769060D03*
X399987Y766428D03*
X399991Y774060D03*
X397487Y779060D03*
Y781560D03*
Y786560D03*
Y784060D03*
X399991D03*
Y779060D03*
Y781560D03*
X401341Y1015474D03*
Y1019017D03*
Y1022560D03*
X403347Y1266162D03*
Y1268662D03*
X400847Y1266162D03*
X398347D03*
X400847Y1268662D03*
X398347D03*
X403347Y1271162D03*
Y1273662D03*
X400847Y1271162D03*
X398347D03*
X400847Y1273662D03*
X398347D03*
X403347Y1276162D03*
Y1278662D03*
X400847D03*
Y1276162D03*
X398347Y1278662D03*
Y1276162D03*
X398447Y1281262D03*
Y1283762D03*
X400947Y1281180D03*
Y1283680D03*
X403447D03*
Y1281180D03*
X400947Y1288680D03*
X403447D03*
X400947Y1286180D03*
X403447D03*
X398447Y1286262D03*
Y1288762D03*
X398461Y1291319D03*
X403461D03*
X400961D03*
X400645Y1353385D03*
X408087Y1355430D03*
X404599Y1353830D03*
X407337Y1352862D03*
X400645Y1355893D03*
X397656Y1349708D03*
X401313Y1452895D03*
X397913D03*
X408683Y1480682D03*
Y1484082D03*
Y1497482D03*
Y1494082D03*
X401536Y1516120D03*
Y1512220D03*
X397206Y1516953D03*
Y1511953D03*
Y1514453D03*
X397891Y1521436D03*
X401659Y1519845D03*
X404686Y1516120D03*
Y1512220D03*
X410650Y1509469D03*
X408150D03*
X407836Y1512220D03*
Y1516120D03*
X407561Y1519845D03*
X404699Y1521436D03*
X410108Y1535680D03*
X408895Y1553644D03*
X405331Y1548928D03*
X410851Y1557434D03*
X407198Y1564990D03*
X401249Y1564422D03*
X405758Y1557900D03*
X402912Y1558011D03*
X396452Y1577738D03*
X403163Y1579357D03*
X403004Y1582457D03*
X408925Y1573805D03*
Y1576805D03*
X404669Y1594317D03*
X403837Y1609056D03*
Y1612456D03*
X399447Y1612609D03*
X399801Y1606376D03*
X406697Y1604207D03*
X408856Y1623435D03*
X400380Y1621500D03*
X405436Y1620268D03*
X406343Y1613847D03*
X405747Y1623350D03*
X404640Y1637425D03*
X397822Y1629615D03*
X409552Y1633606D03*
X405342Y1628611D03*
X404661Y1634139D03*
X412000Y1647177D03*
X403844Y1665769D03*
X405000Y1675000D03*
X397324Y1680495D03*
X409000Y1683500D03*
X424975Y54762D03*
X417025D03*
X416549Y66365D03*
Y71665D03*
X427300Y71300D03*
X419900Y96620D03*
X414100D03*
X424084Y110839D03*
X417486Y124179D03*
Y127579D03*
X424086Y123023D03*
X422890Y136700D03*
X424086Y133265D03*
X412370Y188210D03*
X411610Y223140D03*
X424815Y217646D03*
X422936Y223501D03*
X419299Y212096D03*
X423299D03*
X420115Y230323D03*
Y240501D03*
Y235442D03*
Y226323D03*
X411940Y235442D03*
X412715Y251165D03*
Y258165D03*
Y266165D03*
X419617Y308000D03*
X424151Y453174D03*
X415984Y466392D03*
X424784Y496572D03*
X419984Y508000D03*
X411500Y510800D03*
X412771Y524820D03*
X414402Y544690D03*
X423351Y684378D03*
X424101Y686946D03*
X412711Y687301D03*
X420335Y693636D03*
X415475D03*
X417905D03*
X412711Y690201D03*
X414712Y699440D03*
Y696540D03*
X420158Y748643D03*
X415158Y756175D03*
Y751175D03*
Y753675D03*
X417658Y748643D03*
X415158D03*
Y761175D03*
X420158D03*
X417658D03*
X415158Y758675D03*
X420162Y751143D03*
Y753643D03*
Y756143D03*
X417662D03*
Y753643D03*
Y751143D03*
X420162Y758643D03*
X417662D03*
X415158Y771175D03*
X420158Y763675D03*
Y766175D03*
X417658Y768675D03*
X415158D03*
X417658Y763675D03*
Y766175D03*
X415158Y763675D03*
Y766175D03*
X415318Y1009765D03*
Y1006025D03*
X424873Y1014745D03*
X423811Y1005800D03*
X415318Y1013505D03*
X424873Y1023013D03*
Y1018879D03*
X415318Y1028466D03*
Y1020986D03*
Y1024726D03*
Y1017245D03*
X418918Y1032206D03*
X423811Y1032431D03*
X424024Y1267144D03*
X414247Y1268662D03*
X416747D03*
X419247D03*
X424024Y1269644D03*
Y1272144D03*
X414247Y1281180D03*
Y1283680D03*
X416747D03*
Y1281180D03*
Y1271162D03*
X414247D03*
X416747Y1278662D03*
Y1276162D03*
X419247Y1278662D03*
Y1276162D03*
Y1273662D03*
X416747D03*
X414247Y1278662D03*
Y1276162D03*
Y1273662D03*
X419361Y1283719D03*
Y1281219D03*
X419247Y1271162D03*
X424024Y1274644D03*
X414247Y1288680D03*
X416747D03*
X414247Y1286180D03*
X416747D03*
X419361Y1288719D03*
Y1291219D03*
X414361D03*
X416861D03*
X419361Y1286219D03*
X417063Y1340523D03*
Y1343423D03*
X415963Y1346172D03*
X413533D03*
X411103D03*
X421315Y1354276D03*
Y1351376D03*
X421205Y1348586D03*
Y1345686D03*
X418675Y1352166D03*
Y1349266D03*
X425631Y1517138D03*
X425087Y1510708D03*
X422587D03*
X423131Y1517138D03*
X412086Y1512076D03*
Y1514576D03*
X422557Y1537595D03*
X420057D03*
X417098Y1536411D03*
X418157Y1549295D03*
X423157Y1541795D03*
Y1544295D03*
X415657Y1541795D03*
X418157Y1546795D03*
Y1544295D03*
Y1541795D03*
X415657Y1549295D03*
Y1546795D03*
Y1544295D03*
X420657Y1541795D03*
Y1544295D03*
Y1546795D03*
Y1549295D03*
X417098Y1538911D03*
X424115Y1548199D03*
Y1551099D03*
X421697Y1551844D03*
X421683Y1565312D03*
X421108Y1560235D03*
X424488Y1565400D03*
X413540Y1556646D03*
X424616Y1560086D03*
X414202Y1559396D03*
X421294Y1557729D03*
X419254Y1566828D03*
X427081Y1581620D03*
X421277Y1571923D03*
X413396Y1594597D03*
X410991Y1597002D03*
X425469Y1595433D03*
X422069D03*
X419277Y1600725D03*
X414500Y1639075D03*
X417365Y1627695D03*
X420765D03*
X423500Y1652500D03*
X411448Y1650598D03*
X420000Y1664925D03*
X411500Y1657500D03*
X417000Y1675000D03*
X413000Y1683500D03*
X415500Y1672500D03*
X433673Y73960D03*
X428149Y65016D03*
X431359Y82589D03*
X433997Y166400D03*
X437997D03*
X436103Y158594D03*
X437997Y170701D03*
X433997D03*
X438200Y212096D03*
X431299Y212095D03*
X437440Y237270D03*
X442710Y237990D03*
X435710Y250340D03*
X440710D03*
X426947Y320749D03*
X433277Y471970D03*
X429784Y466315D03*
X426208Y468977D03*
X436226Y475526D03*
X437084Y501865D03*
X429784Y506947D03*
X442084Y511870D03*
X427500Y510553D03*
X426011Y524888D03*
X436062Y686575D03*
X430793Y686423D03*
X426839Y685978D03*
X430793Y683915D03*
X437555Y697490D03*
Y694949D03*
X433782Y690100D03*
X430958Y748643D03*
X433458D03*
X433462Y751143D03*
Y753643D03*
Y756143D03*
X430962D03*
Y753643D03*
Y751143D03*
Y758643D03*
X440159Y970341D03*
Y977841D03*
Y985341D03*
X438359Y993766D03*
X438434Y989766D03*
X438359Y997766D03*
X427551Y1005800D03*
X434716Y1014745D03*
X431291Y1005800D03*
X435031D03*
X438771D03*
X438359Y1001766D03*
X434716Y1018879D03*
Y1023013D03*
X431291Y1032431D03*
X435031D03*
X438771D03*
X427551D03*
X427615Y1282917D03*
Y1275417D03*
Y1280417D03*
Y1277917D03*
X436903Y1285694D03*
Y1289694D03*
X436924Y1462595D03*
X433524D03*
X440224Y1452895D03*
X427286Y1483590D03*
Y1480190D03*
Y1501990D03*
Y1505390D03*
X426704Y1523331D03*
Y1526731D03*
X439935Y1532600D03*
X430027Y1546795D03*
Y1544295D03*
X432527Y1541795D03*
Y1549295D03*
Y1546795D03*
Y1544295D03*
X430027Y1541795D03*
Y1549295D03*
X435027D03*
Y1546795D03*
Y1544295D03*
Y1541795D03*
X427527Y1549295D03*
Y1546795D03*
Y1544295D03*
Y1541795D03*
X426620Y1551844D03*
X437736Y1544392D03*
X431923Y1565790D03*
X432051Y1560635D03*
X437910Y1553910D03*
X433440Y1581700D03*
X429947Y1594398D03*
X436776Y1610394D03*
X430500Y1605835D03*
X431664Y1624342D03*
X436776Y1613794D03*
X433012Y1621612D03*
X430500Y1613709D03*
X434500Y1641500D03*
X431000Y1640500D03*
X432000Y1650000D03*
X436925Y1649500D03*
X441182Y77125D03*
X445267Y82124D03*
X448414Y94684D03*
X445014D03*
X452948Y104003D03*
X445997Y166400D03*
X453997D03*
X449997D03*
X448038Y158659D03*
X441997Y170701D03*
X449997D03*
X448499Y212036D03*
X443299Y212095D03*
X456231Y227764D03*
X443299Y220046D03*
X447299D03*
X456231Y232883D03*
X455422Y244103D03*
X444310Y243370D03*
X446710Y249340D03*
X454518Y280793D03*
X447840Y275970D03*
X441320Y295170D03*
Y301170D03*
Y307170D03*
Y313170D03*
Y316170D03*
X442297Y474442D03*
X453269Y478388D03*
X449496Y474009D03*
X446547Y480123D03*
X443683Y502256D03*
X448024Y505345D03*
X452084Y511870D03*
X447084D03*
X457084D03*
X453723Y526558D03*
X444441Y565549D03*
X450305Y669036D03*
X452735D03*
X447875D03*
X440845Y668731D03*
Y665831D03*
X445111Y662701D03*
X442945Y664331D03*
X440845Y662931D03*
X443045Y667331D03*
X445111Y665601D03*
X447212Y671640D03*
Y674540D03*
X446686Y726660D03*
Y729160D03*
Y731660D03*
X449190Y726528D03*
Y729028D03*
Y731528D03*
X451690D03*
Y729028D03*
Y726528D03*
X446686Y724028D03*
X449186D03*
X451686D03*
Y741660D03*
X449186D03*
Y739160D03*
Y736660D03*
X451686Y739160D03*
Y736660D03*
X446686Y741660D03*
Y736660D03*
Y739160D03*
Y734160D03*
X449190Y734028D03*
X451690D03*
X453810Y1014745D03*
X449992Y1005800D03*
X453732D03*
X443574Y1014745D03*
X446252Y1005800D03*
X442511D03*
X453810Y1023013D03*
X443574D03*
X453810Y1018879D03*
X443574D03*
X453732Y1032431D03*
X442884Y1038766D03*
X442511Y1032431D03*
X442884Y1042766D03*
X446252Y1032431D03*
X449992D03*
X441159Y1051541D03*
X443764Y1179395D03*
X443624Y1452895D03*
X453624Y1472295D03*
X446810Y1565020D03*
X446910Y1562098D03*
X446653Y1573264D03*
X441931Y1581662D03*
X443590Y1593880D03*
X441460Y1596020D03*
X450500Y1612450D03*
X446182Y1625555D03*
X450180Y1614950D03*
X445800Y1633200D03*
Y1636000D03*
X446000Y1650000D03*
X462653Y72525D03*
X462456Y95101D03*
X459056D03*
X470010Y141070D03*
X461997Y166400D03*
X471371Y227764D03*
X461931Y212703D03*
X468574Y213104D03*
X471371Y222764D03*
X464440Y218253D03*
X460567Y225205D03*
Y235442D03*
X460624Y240953D03*
Y230323D03*
X463240Y244980D03*
X456720Y285158D03*
X457248Y280143D03*
Y282643D03*
X470243Y285693D03*
X467545Y356864D03*
X460441Y499842D03*
X457424Y497978D03*
X468638Y514096D03*
X465766Y524991D03*
X458725Y524480D03*
X470331Y566632D03*
X465331D03*
X467831D03*
X462831D03*
X467831Y569132D03*
X470331D03*
X459931Y566632D03*
X457431D03*
X462831Y569132D03*
X457431D03*
X459931D03*
X465331D03*
X470331Y576132D03*
X467831Y571632D03*
X465331D03*
X467831Y576132D03*
X465331D03*
X470331Y571632D03*
X462831D03*
Y576132D03*
X457431Y571632D03*
Y574132D03*
X459931Y571632D03*
Y574132D03*
X457431Y576632D03*
X459931D03*
X462831Y598514D03*
X467831D03*
X470331D03*
X465331D03*
X457711D03*
X460211D03*
X462831Y601014D03*
X467831D03*
X470331D03*
X465331D03*
X457711D03*
X460211D03*
X469955Y672890D03*
X463193Y659315D03*
X468462Y661975D03*
X463193Y661823D03*
X455751Y659778D03*
X459239Y661378D03*
X469955Y670349D03*
X456501Y662346D03*
X466182Y665500D03*
X462490Y731528D03*
Y726528D03*
Y729028D03*
X464990D03*
Y726528D03*
X467486Y724028D03*
X464986D03*
X462486D03*
X467490Y726660D03*
X457472Y1005800D03*
X465965Y1009765D03*
Y1006025D03*
Y1013505D03*
Y1020986D03*
Y1024726D03*
Y1028466D03*
Y1017245D03*
Y1032206D03*
X457472Y1032431D03*
X463724Y1462595D03*
X470424Y1452895D03*
X460324Y1462595D03*
X467024Y1452895D03*
X457024Y1472295D03*
X462215Y1581510D03*
X462753Y1641289D03*
X459500Y1659000D03*
X467500Y1651500D03*
X457000Y1650000D03*
X468075Y1662500D03*
X470463Y1670038D03*
X464925Y1662500D03*
X467500Y1678500D03*
X468575Y1704000D03*
X462500Y1697000D03*
X466000Y1714575D03*
X468575Y1731000D03*
X479400Y90574D03*
Y94574D03*
Y97574D03*
Y110930D03*
X479465Y119644D03*
Y115644D03*
X482255Y133222D03*
Y129822D03*
X479465Y123644D03*
X482380Y141942D03*
X483800Y189400D03*
X480200Y191900D03*
X480700Y208200D03*
X480715Y211099D03*
X471371Y235764D03*
X483227Y233000D03*
X487620Y270400D03*
X479870D03*
X483823Y285893D03*
X474808Y291492D03*
X482893Y291293D03*
X479148Y315502D03*
X484063Y305669D03*
X480773Y307153D03*
X471015Y527283D03*
X475731Y566632D03*
X473231D03*
Y569132D03*
X475731D03*
Y574132D03*
Y571632D03*
X473231Y574132D03*
Y571632D03*
X475731Y576632D03*
X473231D03*
X485335Y642536D03*
X480475D03*
X482905D03*
X473445Y642231D03*
X477711Y639101D03*
X475645Y640831D03*
X473445Y639331D03*
X475545Y637831D03*
X473445Y636431D03*
X477711Y636201D03*
X479812Y645240D03*
Y648140D03*
X479058Y702660D03*
Y700160D03*
X484062Y700028D03*
Y702528D03*
X481562D03*
Y700028D03*
X479058Y697528D03*
X481558D03*
X484058D03*
X479058Y717660D03*
Y707660D03*
Y712660D03*
Y710160D03*
Y715160D03*
X484058Y710160D03*
Y712660D03*
X481558Y710160D03*
Y712660D03*
X484058Y715160D03*
X481558D03*
X484062Y707528D03*
X481562D03*
X479058Y705160D03*
X484062Y705028D03*
X481562D03*
X480803Y1015474D03*
Y1022560D03*
Y1019017D03*
X483824Y1472295D03*
X480424D03*
X483500Y1658500D03*
X479500Y1666500D03*
X473500Y1662500D03*
X477538Y1661463D03*
X474000Y1704000D03*
X478500Y1697000D03*
Y1710500D03*
Y1733500D03*
X491849Y55095D03*
Y60105D03*
X497885Y51315D03*
X491849Y64965D03*
X500674Y116261D03*
X490380Y131442D03*
X493780D03*
X485780Y141942D03*
X500136Y141058D03*
X495500Y161386D03*
X497700Y157200D03*
X492685Y160994D03*
X486682Y193516D03*
X495232D03*
Y185516D03*
X486682Y189516D03*
X496831Y205030D03*
X499380Y222510D03*
X491635Y225970D03*
X494144Y221370D03*
X487442Y223377D03*
X500209Y227881D03*
X491635Y215652D03*
X500209Y233000D03*
X491859D03*
X500119Y243173D03*
X500209Y238119D03*
X491577Y238120D03*
Y243240D03*
X485962Y290679D03*
X487827Y354017D03*
X490419Y362138D03*
X498500Y419425D03*
X495793Y632815D03*
X495839Y635323D03*
X488351Y633278D03*
X491839Y634878D03*
X489101Y635846D03*
X498782Y639000D03*
X497362Y700028D03*
Y702528D03*
X494862D03*
Y700028D03*
X499858Y697528D03*
X497358D03*
X494858D03*
X499862Y700160D03*
Y702660D03*
X494862Y705028D03*
X497362D03*
X499862Y705160D03*
X488384Y1015474D03*
X495884D03*
X488384Y1022560D03*
Y1019017D03*
X495884Y1022560D03*
Y1019017D03*
X490524Y1462595D03*
X497224Y1452895D03*
X487124Y1462595D03*
X493824Y1452895D03*
X512658Y46613D03*
X504796Y86320D03*
X516020Y105370D03*
Y109270D03*
X514240Y97146D03*
X513772Y121220D03*
X502750Y111276D03*
X503000Y135600D03*
X509346Y125842D03*
X507945Y160919D03*
X503161Y154620D03*
X500600Y157100D03*
X505315Y196944D03*
X503507Y185516D03*
X504351Y202776D03*
X508238Y199506D03*
X512076Y206404D03*
X511684Y221219D03*
X504351Y215901D03*
X508001Y220166D03*
X515223Y289035D03*
Y313200D03*
Y305145D03*
X513775Y608436D03*
X506745Y608131D03*
X508945Y606731D03*
X506745Y602331D03*
Y605231D03*
X508845Y603731D03*
X511011Y602101D03*
Y605001D03*
X513012Y611040D03*
Y613940D03*
X501062Y635475D03*
X502555Y646390D03*
Y643849D03*
X514162Y673428D03*
Y665928D03*
Y668428D03*
Y670928D03*
X514158Y663428D03*
Y678460D03*
Y683460D03*
Y680960D03*
Y675960D03*
X509572Y865327D03*
X513572D03*
X513924Y1462595D03*
X510624Y1472295D03*
X507224D03*
X524713Y33346D03*
X529713D03*
X516058Y46613D03*
X519765Y40328D03*
X523165D03*
X519743Y71436D03*
X523143D03*
X526460Y100895D03*
Y97495D03*
X517640Y97146D03*
X524993Y125914D03*
X521618Y165428D03*
X519268Y167428D03*
X519601Y196117D03*
X518691Y191846D03*
X517314Y200449D03*
X519248Y280721D03*
X516723D03*
X521773D03*
X520273Y289035D03*
X517748D03*
X522798D03*
X520273Y313200D03*
X517748D03*
X520273Y305145D03*
X517748D03*
X515523Y335613D03*
X529317Y403784D03*
X524680Y417602D03*
X529095Y452049D03*
X529153Y598735D03*
X529235Y601543D03*
X521651Y599178D03*
X525139Y600778D03*
X522401Y601746D03*
X516205Y608436D03*
X518635D03*
X529962Y673428D03*
Y670928D03*
Y668428D03*
Y665928D03*
X516662Y673428D03*
Y670928D03*
Y668428D03*
Y665928D03*
X527462Y673428D03*
Y665928D03*
Y668428D03*
Y670928D03*
X516658Y663428D03*
X527458D03*
X529958D03*
X516658Y678460D03*
Y683460D03*
Y680960D03*
X527458Y678460D03*
X516658Y675960D03*
X527458D03*
X529958D03*
Y678460D03*
X526474Y851934D03*
Y849434D03*
X517009Y856494D03*
X523074Y853439D03*
Y855939D03*
X528220Y1167366D03*
X517118D03*
X520818D03*
X517324Y1462595D03*
X524024Y1452895D03*
X520624D03*
X539120Y31340D03*
X535117D03*
X544721Y42892D03*
X539721Y42862D03*
X533918Y47067D03*
X537318D03*
X541003Y71436D03*
X544403D03*
X538210Y90618D03*
X540615Y88213D03*
X535170Y111230D03*
Y115130D03*
X530567Y125914D03*
X543408Y133912D03*
X538166Y130698D03*
X541675Y146874D03*
Y151470D03*
Y142021D03*
Y137169D03*
Y156195D03*
X533442Y164428D03*
X532222Y207849D03*
X540695Y217874D03*
X534277Y224930D03*
X538613Y227882D03*
X537051Y211959D03*
X538613Y238119D03*
X534277Y230441D03*
Y235560D03*
X538613Y233000D03*
X539217Y245270D03*
X543780Y294168D03*
X541808Y289743D03*
X544628Y291633D03*
Y289133D03*
X542983Y334531D03*
X533211Y350838D03*
X533543Y404130D03*
X530729Y398634D03*
X543170Y434737D03*
X534455Y428561D03*
X531753Y453232D03*
X540616Y463486D03*
X538067Y592652D03*
X542071Y593089D03*
X535855Y612290D03*
X539657Y607658D03*
X534362Y601375D03*
X535855Y609749D03*
X532082Y604900D03*
X534962Y670960D03*
Y665960D03*
Y668460D03*
X532462D03*
Y665960D03*
Y670960D03*
Y673460D03*
Y663460D03*
X534962D03*
Y673460D03*
Y675960D03*
X532462D03*
X531921Y1167366D03*
X537424Y1452895D03*
X534024D03*
X544794Y1480682D03*
Y1484082D03*
Y1497482D03*
Y1494082D03*
X543947Y1516120D03*
Y1512220D03*
X543672Y1519845D03*
X540810Y1521436D03*
X533317Y1511953D03*
Y1514453D03*
Y1516953D03*
X531495Y1519250D03*
X537770Y1519845D03*
X537647Y1516120D03*
Y1512220D03*
X534002Y1521436D03*
X540797Y1516120D03*
Y1512220D03*
X543719Y1549295D03*
Y1546795D03*
X541219D03*
Y1549295D03*
X538719D03*
Y1546795D03*
X531339Y1546481D03*
X553620Y31048D03*
X549919D03*
X554984Y45312D03*
X553651Y48842D03*
X546350Y39562D03*
X550972Y42902D03*
X561721Y41024D03*
X556351Y41538D03*
X548610Y48082D03*
X547821Y79372D03*
X551721D03*
X555176Y71436D03*
X558576D03*
X559069Y105385D03*
Y101985D03*
X552105Y112203D03*
X555505D03*
X553780Y121240D03*
Y124640D03*
X559484Y156667D03*
X553757Y160075D03*
X547196Y190256D03*
X550196D03*
X554196D03*
X553578Y193541D03*
X547196Y199256D03*
X550553Y200304D03*
Y197778D03*
X548963Y218441D03*
X549248Y237652D03*
Y230441D03*
X555567Y236970D03*
X549248Y234152D03*
X559774Y243176D03*
X557243Y294693D03*
X561808Y300492D03*
X562030Y372872D03*
X551044Y373085D03*
X562208Y383668D03*
Y404717D03*
X550573Y399586D03*
Y403586D03*
X562208Y397599D03*
X550573Y414274D03*
X549854Y406298D03*
X547529Y425411D03*
X551591Y443665D03*
X552510Y446490D03*
X547751Y472678D03*
X550925Y475178D03*
X553360Y477822D03*
X555727Y479968D03*
X558379Y482096D03*
X549957Y658478D03*
Y661478D03*
X558690Y1226149D03*
X558876Y1454905D03*
Y1458305D03*
X546253Y1454107D03*
Y1457507D03*
X555348Y1483590D03*
Y1480190D03*
Y1501990D03*
Y1505390D03*
X548197Y1514641D03*
X550471Y1513584D03*
Y1511031D03*
X548197Y1512088D03*
X554766Y1523331D03*
Y1526731D03*
X550939Y1536646D03*
X559215Y1530596D03*
X546219Y1549295D03*
Y1541795D03*
Y1546795D03*
Y1544295D03*
X548719Y1549295D03*
Y1546795D03*
Y1541795D03*
Y1544295D03*
X551219D03*
Y1541795D03*
X549674Y1538890D03*
X558089Y1541795D03*
Y1544295D03*
Y1546795D03*
Y1549295D03*
X555589Y1541795D03*
Y1549295D03*
Y1546795D03*
Y1544295D03*
X549759Y1551844D03*
X552177Y1551099D03*
X554682Y1551844D03*
X552177Y1548199D03*
X565185Y47982D03*
X575331Y47672D03*
X573191Y42912D03*
X570209Y47982D03*
X566771Y41133D03*
X564794Y58911D03*
X567997Y58992D03*
X573763Y58688D03*
X562331Y48438D03*
X570860Y121310D03*
Y124710D03*
X563951Y153640D03*
Y148640D03*
Y157494D03*
X572003Y164356D03*
Y169415D03*
X568804Y221926D03*
X571427Y217771D03*
X569004Y225496D03*
X568736Y235821D03*
X565093Y242640D03*
X570823Y294893D03*
X572447Y299470D03*
X569893Y300293D03*
X571063Y314669D03*
X566148Y324502D03*
X567773Y316153D03*
X575913Y413287D03*
X570863Y410728D03*
X572121Y437038D03*
X564407Y431638D03*
X568709Y434227D03*
X563763Y486350D03*
X567297Y487551D03*
X560890Y484664D03*
X569923Y490726D03*
X561346Y1228547D03*
X564669Y1238907D03*
X564283Y1231192D03*
X565537Y1235456D03*
X574200Y1229900D03*
X567127Y1249536D03*
X570775Y1263008D03*
X564986Y1462595D03*
X571686Y1452895D03*
X561586Y1462595D03*
X568286Y1452895D03*
X560589Y1541795D03*
Y1544295D03*
Y1546795D03*
Y1549295D03*
X563089Y1541795D03*
Y1549295D03*
Y1546795D03*
Y1544295D03*
X567214Y1544299D03*
X591938Y46308D03*
X576478Y58563D03*
X591070Y60201D03*
X586953Y63441D03*
X583685Y70678D03*
X586390Y69291D03*
X579561Y73090D03*
X585000Y82500D03*
X584752Y86248D03*
X590501Y86909D03*
X578454Y88926D03*
X586394Y95948D03*
X591811Y97421D03*
X580485Y133056D03*
Y130530D03*
X583485D03*
Y133056D03*
X589203Y164356D03*
X581203D03*
X589203Y169415D03*
X585685Y174975D03*
X581203Y169415D03*
X575425Y189835D03*
X582124Y194150D03*
X588244Y208991D03*
X575440Y200785D03*
X582002Y197481D03*
X582766Y225496D03*
Y221421D03*
X588554Y217277D03*
Y225277D03*
X580343Y217771D03*
X588215Y214079D03*
X588968Y240112D03*
X582816Y228696D03*
X581099Y263680D03*
X586157Y366827D03*
X585585Y372052D03*
X577482Y383668D03*
X581985Y387227D03*
Y376427D03*
X587710Y399287D03*
X581985Y401158D03*
X587710Y404287D03*
X588723Y415846D03*
X588798Y435949D03*
X588723Y427949D03*
X588742Y431976D03*
X577845Y437151D03*
X587829Y445138D03*
X575345Y437151D03*
X580523Y435949D03*
X575075Y451263D03*
X582390Y464701D03*
X589507Y462559D03*
X583116Y476745D03*
X587500Y470308D03*
X587795Y479631D03*
X581335Y472100D03*
X581421Y813078D03*
X588500Y812093D03*
X584271Y1263988D03*
X588386Y1462595D03*
X585086Y1472295D03*
X581686D03*
X602837Y32910D03*
X603064Y48023D03*
X599284Y42481D03*
X597956Y48047D03*
X606585Y43529D03*
X601073Y60301D03*
X603350Y73642D03*
X599295Y100747D03*
X606183Y95873D03*
X597275Y94922D03*
X596068Y106798D03*
X591385Y109165D03*
X602328Y109062D03*
X597769Y153640D03*
Y148640D03*
X603344Y139131D03*
X598552Y159066D03*
X600161Y188776D03*
X593661D03*
X604293Y193185D03*
X597293Y193186D03*
X602294Y203786D03*
X598968Y238878D03*
X603526Y229995D03*
X597050Y281950D03*
X602223Y298035D03*
X603723Y289721D03*
X602223Y314145D03*
Y322200D03*
X598414Y372357D03*
X598208Y383668D03*
X599884Y412000D03*
X593758Y415850D03*
X603326Y429530D03*
X590326Y445015D03*
X592529Y461563D03*
X598496Y451421D03*
X597500Y483500D03*
X602833Y791746D03*
X590710Y804192D03*
X603743Y794963D03*
X595619Y806084D03*
X600337Y800649D03*
X596821Y802688D03*
X592572Y809088D03*
X596621Y1240366D03*
X595253Y1266668D03*
X596944Y1270115D03*
X595532Y1262668D03*
X605771Y1263098D03*
X598112Y1264365D03*
X594991Y1285582D03*
Y1289582D03*
X591786Y1462595D03*
X598486Y1452895D03*
X595086D03*
X613025Y42725D03*
X612608Y35961D03*
X618732Y39913D03*
X619563Y49193D03*
X615587Y45611D03*
X606263Y60301D03*
X616815Y60277D03*
X611579D03*
X615190Y74533D03*
X615772Y106645D03*
X618182Y100786D03*
X610009Y100748D03*
X614282Y95873D03*
X617420Y119640D03*
X619240Y123232D03*
X605853Y149640D03*
Y145640D03*
Y152140D03*
Y155131D03*
X618801Y165356D03*
Y175534D03*
Y170415D03*
X616357Y182229D03*
X608794Y203786D03*
X607868Y257562D03*
X618705Y285305D03*
X608773Y289721D03*
X609798Y298035D03*
X607273D03*
X606248Y289721D03*
X604748Y298035D03*
X609798Y314145D03*
X607273D03*
X604748D03*
X621585Y331358D03*
X609798Y322200D03*
X607273D03*
X604748D03*
X611118Y359462D03*
X613565Y350819D03*
X619035Y369542D03*
X613482Y383668D03*
X617985Y387227D03*
Y376427D03*
Y401728D03*
X606032Y418968D03*
X617985Y407346D03*
X617998Y415546D03*
X606811Y429528D03*
X611925Y437000D03*
X605769Y442593D03*
X615903Y493474D03*
X608886Y494400D03*
X618680Y511302D03*
X618957Y502306D03*
X616457D03*
X611896Y535178D03*
Y538178D03*
X607091Y528168D03*
X618645Y783582D03*
X609402Y788678D03*
X615571Y788448D03*
X608940Y1265991D03*
X610551Y1262988D03*
X618761Y1266988D03*
X615591Y1282038D03*
X618761Y1278668D03*
X606619Y1278302D03*
X610551Y1269888D03*
X616037Y1367166D03*
X608148Y1373890D03*
X616615Y1386232D03*
X616629Y1375082D03*
X618586Y1462595D03*
X615186D03*
X611886Y1472295D03*
X608486D03*
X613948Y1641600D03*
X624634Y48104D03*
X628410Y45381D03*
X624689Y58262D03*
X627881Y57120D03*
X622207Y60573D03*
X627496Y74977D03*
X626642Y71365D03*
X622156Y95948D03*
X626208Y100861D03*
X628885Y127057D03*
X630810Y122089D03*
X625532Y146982D03*
X625553Y152683D03*
X625755Y168917D03*
X626372Y193431D03*
X626824Y182080D03*
X620455Y219277D03*
Y228777D03*
X631505Y284355D03*
X626705Y285305D03*
X622705D03*
X626473Y305338D03*
X626388Y330536D03*
X631694Y341300D03*
X626555Y343929D03*
X624133Y346520D03*
X626596Y360196D03*
X636500Y360362D03*
X634105Y404652D03*
X635058Y399700D03*
X627925Y421966D03*
X631075Y429888D03*
X632281Y441904D03*
X622174Y438925D03*
X622197Y436116D03*
X622800Y461348D03*
X627880Y455310D03*
X620800Y474700D03*
X627364Y478823D03*
X632984Y471462D03*
X630758Y505874D03*
X633406Y497964D03*
X624381Y503765D03*
X631510Y510613D03*
X624718Y553428D03*
X634794Y590504D03*
X635567Y671774D03*
X631557Y773359D03*
X631741Y770318D03*
X633406Y1358576D03*
X634776Y1353739D03*
X630477Y1350109D03*
Y1353109D03*
X624795Y1373257D03*
X624976Y1378313D03*
X630195Y1384263D03*
X625195Y1383457D03*
X622352Y1393285D03*
X630523Y1392554D03*
X635849Y1393376D03*
X625286Y1452895D03*
X621886D03*
X629808Y1668863D03*
X633422Y1673488D03*
X631643Y1670946D03*
X635491Y1696845D03*
X635472Y1711808D03*
X644963Y29143D03*
X638490Y33340D03*
X642157Y44695D03*
X639876Y49193D03*
X651042Y41545D03*
X647987Y47606D03*
X646042Y41545D03*
X640653Y58274D03*
X640670Y74369D03*
X650846Y74074D03*
X647938Y83795D03*
X644202Y84604D03*
X642607Y94116D03*
X645752Y134988D03*
X643800Y166053D03*
X641111Y158300D03*
X641006Y161829D03*
X643800Y161862D03*
X640923Y169388D03*
X649871Y181942D03*
X641276Y187557D03*
X637804Y235371D03*
X640804D03*
X637804Y239371D03*
X640804D03*
X640084Y227113D03*
X637804Y243371D03*
X640804D03*
X642171Y311280D03*
X641013Y324459D03*
X640922Y360342D03*
X639000Y364862D03*
X642128Y363279D03*
X636579Y366941D03*
X642617Y389299D03*
X637314Y393680D03*
X640784Y395957D03*
X651279Y404458D03*
X637160Y405449D03*
X635243Y433518D03*
X637432Y428935D03*
X642406Y427614D03*
X639211Y433862D03*
Y438191D03*
X635449Y449797D03*
X639002Y449862D03*
X639500Y442362D03*
X639313Y452361D03*
X635690Y461441D03*
X648500Y453862D03*
X635640Y464257D03*
X644849Y495582D03*
X647576Y497964D03*
X643053Y502891D03*
X640076Y497964D03*
X635906D03*
X642310Y535773D03*
X649592Y540078D03*
X639757Y533440D03*
X636055Y528605D03*
X646151Y535227D03*
X648314Y571169D03*
X644414D03*
X638694Y590504D03*
X650258Y590316D03*
X646358D03*
X650228Y674761D03*
X638967Y671774D03*
X646446Y674643D03*
X640271Y763488D03*
X636551Y767900D03*
X642804Y766871D03*
X636247Y771179D03*
X635092Y1277102D03*
X634995Y1384457D03*
X638053Y1384491D03*
X647401Y1384160D03*
X645386Y1462595D03*
X641986D03*
X648686Y1452895D03*
X638686Y1472295D03*
X635286D03*
X639907Y1570443D03*
X639132Y1573127D03*
X645180Y1597800D03*
X645190Y1595050D03*
X649153Y1625726D03*
X649297Y1623185D03*
X640242Y1639951D03*
X647630Y1641522D03*
X643128Y1639803D03*
X642716Y1653939D03*
X637218Y1654131D03*
X644905Y1646491D03*
X639800Y1646650D03*
X643074Y1668505D03*
X647574D03*
X647460Y1662952D03*
X640846Y1665189D03*
X650158Y1687189D03*
X643041Y1682883D03*
X647500Y1674805D03*
X640600D03*
X643300D03*
X639391Y1700695D03*
X640690Y1703547D03*
X651143Y1706162D03*
X644975Y1725236D03*
X635210Y1718395D03*
X641825Y1730516D03*
X640865Y1719684D03*
X657921Y30864D03*
X654117Y29099D03*
X654582Y45448D03*
X660928Y60707D03*
X651014Y60820D03*
X656600Y60537D03*
X661601Y75562D03*
X656501Y69662D03*
X657166Y79131D03*
X656427Y75431D03*
X661588Y69662D03*
X658228Y88447D03*
X666200Y84862D03*
X654037Y93241D03*
Y96041D03*
X651950Y99890D03*
X658949Y139840D03*
X662881Y149912D03*
Y146912D03*
X654326Y174437D03*
X653700Y179962D03*
X659881Y208262D03*
Y205762D03*
Y210762D03*
X662781Y207862D03*
Y205362D03*
Y210362D03*
X663915Y234476D03*
X659918Y326503D03*
X658905Y341885D03*
X661019Y344831D03*
X663551Y346035D03*
X649500Y373500D03*
X652425Y385924D03*
X659095Y381020D03*
X649495Y385118D03*
X659354Y393938D03*
X653523Y399987D03*
X652954Y394284D03*
X661297Y409857D03*
X662016Y417897D03*
X652027Y415930D03*
X654273Y419251D03*
X662000Y433862D03*
X654248Y422500D03*
X657535Y422694D03*
X666000Y429844D03*
X651432Y433532D03*
X662000Y429844D03*
X652763Y427866D03*
X651384Y445252D03*
X661546Y444497D03*
X662000Y449862D03*
X654441Y449618D03*
X662000Y437844D03*
X657622Y437819D03*
X651853Y439518D03*
X653449Y458542D03*
X662570Y461547D03*
Y457755D03*
X662000Y473862D03*
X666000Y473844D03*
X651072Y465939D03*
X654000Y465824D03*
X654014Y473862D03*
X662000Y465862D03*
X651114Y473884D03*
X662000Y469862D03*
X653266Y479106D03*
X663374Y484295D03*
X652380Y482390D03*
X657520Y486330D03*
X649500Y490260D03*
X660215Y483109D03*
X658758Y497964D03*
X655917D03*
X661718Y498056D03*
X651406Y501178D03*
X650404Y496102D03*
X652576Y497964D03*
X659425Y521075D03*
X665689Y550294D03*
X649922Y545610D03*
X655967Y544375D03*
X658642Y573893D03*
X661718Y579932D03*
X653368Y581468D03*
X655572Y572603D03*
X656832Y577205D03*
X662992Y598660D03*
X658613Y599534D03*
X662628Y674761D03*
X660175Y679517D03*
X657428Y674761D03*
X663580Y731509D03*
X658947Y767300D03*
Y771100D03*
X662600Y1311502D03*
Y1308502D03*
X653376Y1365793D03*
X661719Y1363394D03*
X651973Y1363038D03*
X653149Y1372500D03*
X653101Y1369862D03*
X652651Y1375308D03*
X661813Y1370081D03*
X653117Y1378037D03*
X651877Y1391074D03*
X653999Y1426757D03*
Y1423357D03*
X652086Y1452895D03*
X662086D03*
X663160Y1511734D03*
Y1516734D03*
Y1519234D03*
Y1521734D03*
X660660Y1519234D03*
X661710Y1514148D03*
X663160Y1524234D03*
X666092Y1553650D03*
X660953Y1539998D03*
X663133Y1543744D03*
Y1541244D03*
Y1538744D03*
X660953Y1542498D03*
X657430Y1555228D03*
X659532Y1546519D03*
X664246Y1561009D03*
X661731Y1561083D03*
X661156Y1626532D03*
X650966Y1618934D03*
X651870Y1612986D03*
X650753Y1615912D03*
X653542Y1649059D03*
X660058Y1648889D03*
X660389Y1654481D03*
X663431Y1645780D03*
X654712Y1653813D03*
X664315Y1654484D03*
X650074Y1668505D03*
X658648Y1664169D03*
X655683Y1664212D03*
X653154Y1683265D03*
X664159Y1674844D03*
X661528Y1674865D03*
X650200Y1674805D03*
X658491Y1688965D03*
X649464Y1691180D03*
X659837Y1698400D03*
X659557Y1714672D03*
X658759Y1707147D03*
X659028Y1710047D03*
X660930Y1730277D03*
X662120Y1720404D03*
X670613Y42464D03*
X674013D03*
X677476Y33317D03*
X680864Y38190D03*
X666506Y32750D03*
X674647Y38190D03*
X677305Y57947D03*
X665469Y58525D03*
X674036Y74522D03*
X675509Y88173D03*
X667941Y80142D03*
X677561Y118409D03*
X677738Y115428D03*
X665651Y147692D03*
X673011Y169021D03*
X679035Y204181D03*
X678226Y215771D03*
X674348Y218580D03*
X666552Y346115D03*
X677111Y345662D03*
X672111D03*
X674611D03*
X676800Y369362D03*
X672800D03*
X680800Y380280D03*
X672800Y382362D03*
X676000Y378100D03*
X667090Y385150D03*
X671500Y390862D03*
X679940Y400933D03*
X675500Y398862D03*
Y390862D03*
X670018Y418690D03*
X669929Y407999D03*
X666000Y433862D03*
Y425862D03*
X670000Y429864D03*
Y433844D03*
Y425894D03*
X666000Y437844D03*
X670000Y442362D03*
Y437844D03*
X666000Y442362D03*
X670000Y446362D03*
X679062Y455140D03*
X666000Y453844D03*
Y457862D03*
X670000Y453844D03*
X666000Y461862D03*
X670000Y469824D03*
Y477862D03*
X678000D03*
X670000Y482862D03*
X678000D03*
X681213Y495658D03*
X672699Y506907D03*
X664741Y506865D03*
X680488Y504784D03*
X665425Y537000D03*
X664454Y574896D03*
X665774Y571762D03*
X666192Y598660D03*
X679047Y678733D03*
X673287Y733156D03*
X674123Y736083D03*
X667101Y736071D03*
X672505Y766871D03*
X674552Y1342488D03*
Y1344988D03*
X665167Y1380836D03*
Y1376836D03*
X673671Y1431922D03*
X675272Y1434525D03*
X665486Y1452895D03*
X672856Y1484082D03*
Y1480682D03*
Y1497482D03*
Y1494082D03*
X678386Y1507965D03*
X677871Y1522079D03*
X678345Y1516994D03*
X677871Y1519579D03*
X673174Y1515806D03*
X675505Y1512606D03*
X678339Y1510960D03*
X677871Y1524579D03*
X678121Y1528516D03*
X665832Y1527425D03*
X672715Y1526626D03*
Y1530526D03*
X678350Y1567400D03*
X669524Y1560850D03*
X672163Y1560899D03*
X673729Y1556768D03*
X666978Y1560945D03*
X672810Y1571560D03*
X666610Y1571580D03*
X668133Y1625828D03*
X670839Y1620863D03*
X673960Y1633042D03*
X669648Y1640917D03*
X670803Y1654606D03*
X671068Y1650818D03*
X674908Y1644481D03*
X667971Y1654404D03*
X669178Y1646627D03*
X673548Y1669550D03*
X678117Y1662787D03*
X675497Y1687253D03*
X673359Y1674409D03*
X671001Y1696017D03*
X671798Y1704542D03*
X673113Y1716599D03*
X667701Y1705043D03*
X668058Y1720092D03*
X673113Y1727261D03*
X684611Y41857D03*
X682291Y46822D03*
X690476Y32684D03*
X692390Y46939D03*
X692466Y35950D03*
X687835Y37850D03*
X687345Y46940D03*
X687018Y58357D03*
X683369Y58157D03*
X692390Y72692D03*
X690028Y70142D03*
X687665Y73202D03*
X685781Y70022D03*
X680580Y79230D03*
X681054Y104668D03*
X686891Y115868D03*
X687000Y119500D03*
X685500Y124000D03*
X679316Y209861D03*
X680576Y207105D03*
X681333Y212326D03*
X679737Y217763D03*
X693621Y346169D03*
X680828Y363500D03*
X684800Y369362D03*
X680800D03*
X691484Y360643D03*
X691500Y382462D03*
X685200Y377820D03*
X690105Y401775D03*
X687500Y390680D03*
X684794Y402268D03*
X683500Y390862D03*
X679500D03*
X692996Y418358D03*
X694299Y413108D03*
X689269Y410420D03*
X687612Y471850D03*
X691572Y465214D03*
X684800Y477862D03*
X687472Y486994D03*
X684680Y485942D03*
X684800Y481862D03*
X680187Y491243D03*
X690452Y486984D03*
X687310Y500453D03*
X682915Y500568D03*
X683000Y521500D03*
X687310Y522141D03*
X694111Y537881D03*
X690718Y578913D03*
X694996Y575081D03*
X689574Y572866D03*
X681352Y681305D03*
X691417Y680382D03*
X685786Y680936D03*
X686509Y677440D03*
X688648Y767300D03*
Y771100D03*
X687961Y1314308D03*
Y1320308D03*
Y1323308D03*
Y1317308D03*
X684868Y1327117D03*
X682348D03*
Y1339617D03*
X683052Y1342548D03*
X684868Y1329617D03*
X682348D03*
X684868Y1332117D03*
X682348D03*
X684868Y1334617D03*
X682348D03*
X684868Y1337117D03*
Y1339617D03*
X682348Y1337117D03*
X683052Y1345048D03*
X681289Y1418291D03*
X683391Y1420531D03*
X685448Y1423137D03*
X691587Y1429515D03*
X689538Y1427467D03*
X684350Y1448911D03*
X692376Y1438326D03*
X691943Y1441626D03*
X691276Y1455112D03*
X687040Y1452300D03*
X684280Y1452260D03*
X684603Y1507851D03*
X681517Y1508034D03*
X687529Y1508173D03*
X690683Y1508058D03*
X693395D03*
X693532Y1510755D03*
X690820D03*
X687666Y1510870D03*
X687711Y1513612D03*
X690751Y1513750D03*
X693655Y1513818D03*
X693587Y1516470D03*
X690752Y1516516D03*
X683666Y1515189D03*
X680717Y1513292D03*
X684557Y1510685D03*
X681563Y1510708D03*
X693495Y1519305D03*
X679854Y1551492D03*
X679413Y1548843D03*
X680107Y1554330D03*
X681780Y1574280D03*
X684080Y1576500D03*
X686949Y1625144D03*
X689897Y1621781D03*
X692209Y1620037D03*
X691036Y1625508D03*
X686994Y1629077D03*
X693451Y1628733D03*
X686808Y1643500D03*
X685578Y1637479D03*
X683067Y1641758D03*
X686075Y1657082D03*
X679413Y1653251D03*
X685719Y1672391D03*
X685747Y1669303D03*
X693608Y1671081D03*
X685635Y1675310D03*
X691560Y1682047D03*
X693480Y1673940D03*
X692390Y1687594D03*
X705666Y48010D03*
X697678Y47132D03*
X697893Y35950D03*
X702481Y48327D03*
X698462Y60683D03*
X695220Y60455D03*
X704201Y72112D03*
X699476Y69982D03*
X701081Y72450D03*
X694752Y70212D03*
X696701Y72462D03*
X698711Y86035D03*
X696371Y78512D03*
X696728Y81552D03*
Y84052D03*
X706721Y100462D03*
X702721Y102162D03*
X701221Y104862D03*
X697721D03*
X695721Y102162D03*
X694221Y104862D03*
X699221Y102162D03*
X699398Y123668D03*
X704709Y125586D03*
X704771Y171188D03*
Y167788D03*
X703486Y345507D03*
X699813Y344798D03*
X706139Y345597D03*
X695500Y374362D03*
X699500D03*
X703500D03*
X707500D03*
X707943Y360643D03*
X707500Y368862D03*
X696391Y368617D03*
X703477Y369409D03*
X695500Y382362D03*
X700300Y382502D03*
X707500Y382362D03*
X700000Y386790D03*
X707500Y386862D03*
X703700Y386832D03*
X695500Y386862D03*
X699500Y390862D03*
X695500D03*
X707500D03*
X703500Y401290D03*
Y390862D03*
X708584Y404868D03*
X699431Y513344D03*
X703774Y513463D03*
X707664Y513375D03*
X703788Y521817D03*
X696020Y521844D03*
X699800Y521760D03*
X708500Y517362D03*
X708210Y537816D03*
X708500Y529862D03*
X704500D03*
X700790Y537732D03*
X704500Y537862D03*
X708500Y533862D03*
X696829Y533604D03*
X702657Y533695D03*
X697018Y537577D03*
X704500Y545862D03*
X696283Y546530D03*
X710429Y545752D03*
X708500Y555451D03*
X698996Y575081D03*
X704056D03*
X708056D03*
X704056Y583081D03*
X698996D03*
X702806Y613264D03*
X696928Y613207D03*
X706387Y621686D03*
X705158Y645357D03*
X703781Y641805D03*
X704965Y638767D03*
X707833Y655325D03*
X704549Y655238D03*
X701233Y655355D03*
X708418Y650389D03*
X694812Y680188D03*
X698756Y676388D03*
X694837Y676412D03*
X701386Y679683D03*
X703584Y676544D03*
X708012Y676836D03*
X705697Y679533D03*
X697571Y730453D03*
X704598Y732288D03*
X700205Y733211D03*
X702553Y735811D03*
X702206Y766871D03*
X697461Y1314008D03*
Y1320008D03*
Y1323008D03*
X702388Y1327127D03*
X699868D03*
X697461Y1317008D03*
X701771Y1342488D03*
X702388Y1337127D03*
Y1339627D03*
X699868Y1337127D03*
Y1339627D03*
X702388Y1329627D03*
X699868D03*
X702388Y1332127D03*
X699868D03*
X702388Y1334627D03*
X699868D03*
X701771Y1344988D03*
X705657Y1387027D03*
X701689Y1399545D03*
X697731Y1397513D03*
X706351Y1397588D03*
X705657Y1389568D03*
X695162Y1441350D03*
X694676Y1455112D03*
X696237Y1508149D03*
X699247Y1508062D03*
X699049Y1510892D03*
X696374Y1510846D03*
X696329Y1513818D03*
X696330Y1516584D03*
X699140Y1513772D03*
X707050Y1531700D03*
X709150Y1536250D03*
X703290Y1551700D03*
X707050Y1548400D03*
Y1541800D03*
X703290Y1545100D03*
X708500Y1560500D03*
X708994Y1568507D03*
X699500Y1559000D03*
X699610Y1568523D03*
Y1572523D03*
Y1576523D03*
X708600Y1572523D03*
X710420Y1585173D03*
X710550Y1576523D03*
X710080Y1581683D03*
X699610Y1584523D03*
X699500Y1596500D03*
Y1588500D03*
X709836Y1594721D03*
X710360Y1589296D03*
X699000Y1604500D03*
X699500Y1599500D03*
X709382Y1601210D03*
X699500Y1608500D03*
X709020Y1609101D03*
X699424Y1616627D03*
X695933Y1623460D03*
X709260Y1617903D03*
X701114Y1640345D03*
X702683Y1633715D03*
X703563Y1644116D03*
X702402Y1650469D03*
X700528Y1661468D03*
X697503Y1661331D03*
X703102Y1665554D03*
X714471Y46670D03*
X724621Y40062D03*
X719821Y45862D03*
X714322Y56286D03*
X721163Y58588D03*
X714096Y73686D03*
X712717Y68541D03*
X719416Y68738D03*
Y74036D03*
X725016Y86952D03*
X720016D03*
X715745Y86300D03*
X712725Y84714D03*
X712291Y106722D03*
X715934Y117488D03*
Y114588D03*
X712734Y117488D03*
Y114588D03*
X720434Y135088D03*
X717434D03*
X719934Y124488D03*
X723134D03*
X712341Y128093D03*
X710284Y169826D03*
X716699Y177087D03*
Y173687D03*
Y189087D03*
Y185687D03*
Y200587D03*
Y197187D03*
Y209021D03*
X717021Y220862D03*
X716699Y212421D03*
X714867Y344943D03*
X717712Y346103D03*
X715500Y374362D03*
X719500D03*
X723531Y368862D03*
X723500Y360862D03*
X711500Y374362D03*
X715500Y360862D03*
X719500Y368862D03*
X715500D03*
X711363Y369274D03*
X711500Y382362D03*
X719640Y386862D03*
X723632D03*
X711500D03*
X715500D03*
X722500Y383162D03*
X723500Y390862D03*
X719500D03*
X715500D03*
X711500D03*
X716500Y521862D03*
X711617Y513531D03*
X724500Y517362D03*
X716500D03*
X720400Y517440D03*
X720452Y513362D03*
X716716Y513368D03*
X720499Y533474D03*
X719841Y537348D03*
X712113Y537797D03*
X720500Y555862D03*
Y546211D03*
X712115Y541872D03*
X712409Y555413D03*
X710464Y557036D03*
X722201Y579306D03*
X723483Y574890D03*
X714583Y590792D03*
X716181Y585562D03*
X715037Y606428D03*
X716313Y610134D03*
X719710Y612831D03*
X720787Y627907D03*
X716721D03*
X713343Y633842D03*
X724000Y633906D03*
X725812Y654713D03*
X715371Y654726D03*
X711702Y646533D03*
X711295Y665117D03*
X718129Y666725D03*
X722129D03*
X712164Y676912D03*
X712120Y680287D03*
X717515Y679833D03*
X720563Y679886D03*
X720613Y677040D03*
X723814Y736782D03*
X718349Y767300D03*
Y771100D03*
X721339Y1314048D03*
X711839Y1314348D03*
X721339Y1323048D03*
Y1320048D03*
Y1317048D03*
X715828Y1327277D03*
X710488Y1327177D03*
X713008D03*
X711839Y1323348D03*
Y1320348D03*
Y1317348D03*
X713008Y1329877D03*
Y1332377D03*
Y1334877D03*
X715828Y1332877D03*
Y1330377D03*
X713008Y1337377D03*
Y1339877D03*
X715828Y1335377D03*
X710288Y1339677D03*
Y1337177D03*
X710221Y1342488D03*
X710288Y1334677D03*
Y1332177D03*
Y1329677D03*
X710221Y1344988D03*
X712419Y1398094D03*
X719861Y1400139D03*
X716373Y1398539D03*
X719111Y1397571D03*
X712419Y1400602D03*
X709430Y1394417D03*
X722877Y1390881D03*
X712099Y1416973D03*
X714599D03*
X717099D03*
X712099Y1414473D03*
X714599D03*
X717099D03*
X709599Y1416973D03*
Y1414473D03*
X717099Y1432773D03*
X712099D03*
X714599D03*
X717099Y1430273D03*
X712099D03*
X714599D03*
X709599Y1432773D03*
Y1427373D03*
Y1424873D03*
Y1430273D03*
Y1419873D03*
Y1422373D03*
X714259Y1447483D03*
X719471Y1467422D03*
X711671D03*
X714271D03*
X716871D03*
X720217Y1472287D03*
X717617D03*
X715017D03*
X720926Y1469814D03*
X718326D03*
X715726D03*
X713126D03*
X716067Y1474792D03*
X718667D03*
X721267D03*
X717358Y1477038D03*
X719958D03*
X714474Y1566333D03*
X724110Y1561825D03*
X714110Y1581475D03*
X714900Y1571273D03*
X721963Y1576932D03*
X719963Y1578932D03*
X721440Y1570963D03*
X719963Y1585790D03*
X721963Y1587790D03*
X723590Y1595323D03*
X718892Y1597152D03*
X714372Y1594679D03*
X723408Y1608740D03*
X720106Y1609542D03*
X717798Y1607335D03*
X713718Y1610235D03*
X717229Y1612376D03*
X718129Y1624330D03*
X722104Y1626253D03*
X715744Y1622842D03*
X722889Y1622491D03*
X711298Y1632534D03*
X718122Y1636332D03*
X718116Y1639129D03*
X713771Y1654927D03*
X722480Y1657616D03*
X719117Y1682722D03*
X723181Y1688825D03*
X740101Y41162D03*
X736621Y45262D03*
X733315Y40862D03*
X728721Y43562D03*
X726789Y60562D03*
X738590Y59868D03*
X730785Y58068D03*
X728285Y58135D03*
X724645Y58362D03*
X734769Y60757D03*
X725769Y69737D03*
X736864Y74943D03*
X731864D03*
X727200Y73210D03*
X729918Y90998D03*
X739824Y91052D03*
X734380Y80518D03*
X729380D03*
X736650Y102350D03*
X735771Y94988D03*
X730660Y108484D03*
X728734Y132088D03*
Y129288D03*
Y126388D03*
X735500Y143000D03*
X724147Y345291D03*
X729211Y346379D03*
X726431Y346384D03*
X738773Y346716D03*
X734463Y346712D03*
X735500Y368862D03*
X734166Y360782D03*
X739500Y368862D03*
X727564D03*
X731500Y360862D03*
X731406Y374331D03*
X731500Y368862D03*
Y386862D03*
X739553Y388270D03*
X735500Y386862D03*
X727500D03*
X735500Y390862D03*
X727500D03*
X735500Y399330D03*
X738672Y494444D03*
X728938Y517520D03*
X724500Y513362D03*
X732500D03*
X739185Y521394D03*
X728500Y521862D03*
X724500D03*
X728500Y513362D03*
X736609Y518426D03*
X728500Y529862D03*
X728576Y537476D03*
X736500Y537862D03*
X724336Y537527D03*
X724433Y530870D03*
X732500Y529862D03*
X736647Y529772D03*
X732580Y537193D03*
X724697Y535053D03*
X728652Y545862D03*
X728695Y550943D03*
X736670Y545864D03*
X740500Y545862D03*
X724684Y545864D03*
X724281Y553438D03*
X728714Y554190D03*
X732520Y545988D03*
X736528Y576480D03*
Y579615D03*
X727253Y610689D03*
X724246Y627939D03*
X736362Y636854D03*
X730770Y644218D03*
X733382Y633574D03*
X729489Y666547D03*
X734442Y675695D03*
X730837Y678940D03*
X738486Y679139D03*
X724931Y678364D03*
X735316Y736742D03*
X725712Y734135D03*
X729391D03*
X727576Y736756D03*
X727448Y766871D03*
X735739Y1314048D03*
Y1320048D03*
Y1317048D03*
X724788Y1327277D03*
X727501Y1327230D03*
X730021D03*
X735739Y1323048D03*
X727401Y1332430D03*
Y1329930D03*
Y1334930D03*
X724788Y1330377D03*
Y1332877D03*
X727401Y1339930D03*
Y1337430D03*
X724788Y1335377D03*
X730021Y1337230D03*
Y1339730D03*
Y1334730D03*
Y1329730D03*
Y1332230D03*
X730795Y1342444D03*
Y1344944D03*
X738439Y1387127D03*
X728198Y1388026D03*
Y1385126D03*
X738439Y1389668D03*
X727737Y1390881D03*
X725307D03*
X734767Y1396986D03*
Y1394086D03*
X732567Y1392586D03*
X732667Y1395586D03*
X730501Y1397216D03*
Y1394316D03*
X734767Y1391186D03*
X735418Y1426122D03*
Y1423122D03*
Y1420122D03*
X732418Y1426122D03*
Y1423122D03*
Y1420122D03*
X735453Y1525368D03*
X737551Y1524008D03*
X727325Y1563400D03*
X727571Y1558353D03*
X736782Y1555496D03*
X730782D03*
X733782D03*
X727571Y1555353D03*
X733782Y1567496D03*
X736782D03*
X730782D03*
X733782Y1558496D03*
Y1561496D03*
X736782Y1558496D03*
Y1561496D03*
X733782Y1564496D03*
X736782D03*
X730782Y1558496D03*
Y1561496D03*
Y1564496D03*
X726475Y1571293D03*
X723963Y1578932D03*
X730782Y1570496D03*
X736782D03*
X733782D03*
X733380Y1577231D03*
X727780Y1582361D03*
Y1577231D03*
X723963Y1585790D03*
X726550Y1599358D03*
X733380Y1587491D03*
X727780D03*
X736998Y1597463D03*
X730998D03*
X733998D03*
X736998Y1594463D03*
X730998D03*
X733998D03*
X736998Y1600463D03*
X730998D03*
X733998D03*
Y1603663D03*
X736998D03*
X733998Y1606663D03*
X736998D03*
X730998Y1603663D03*
Y1606663D03*
X730647Y1623629D03*
X727320Y1623698D03*
X736723Y1623938D03*
X731119Y1647997D03*
X735642Y1648537D03*
X730347Y1682902D03*
X725638Y1682890D03*
X732852Y1695701D03*
X738030Y1723903D03*
Y1726903D03*
X738108Y1721157D03*
X738075Y1718082D03*
X746101Y46262D03*
X745901Y40362D03*
X749478Y59902D03*
X746588Y59754D03*
X740817Y58503D03*
X747488Y71429D03*
X740537Y73564D03*
X750034Y89988D03*
X750701Y106642D03*
X754783Y96553D03*
X750034Y92888D03*
X741309Y108742D03*
X748034Y116288D03*
X748261Y112552D03*
X743050Y139182D03*
X751221Y137864D03*
X743547Y147703D03*
X748915Y158608D03*
X745031Y161463D03*
X748125Y170618D03*
X751575Y184252D03*
X746522Y308804D03*
X750717Y319907D03*
X747594Y319106D03*
X747696Y332772D03*
X751337Y343849D03*
X748752Y343582D03*
X745132Y344964D03*
X752926Y361021D03*
X747500Y368862D03*
X751500D03*
X743500D03*
Y374362D03*
X749389Y360816D03*
X755135Y368907D03*
X754813Y374362D03*
X739500D03*
X747500D03*
X747454Y386817D03*
X751652Y386862D03*
X743500Y386962D03*
X739652Y390862D03*
X743500D03*
X747500D03*
X751500D03*
X747629Y406163D03*
X753252Y495234D03*
X748381Y495244D03*
X752652Y504106D03*
X752500Y517362D03*
X744500Y513362D03*
X748661Y517060D03*
X740500Y513362D03*
X752500D03*
X748500D03*
X753951Y521801D03*
X748077Y521789D03*
X740500Y537862D03*
X752965Y537678D03*
X748143Y530269D03*
X744916Y530268D03*
X752500Y529862D03*
X748000Y537862D03*
X741851Y553544D03*
X745645Y545880D03*
X752500Y545862D03*
X745091Y553563D03*
X748500Y545862D03*
X752195Y554761D03*
X748482Y557085D03*
X751731Y557714D03*
X739128Y566639D03*
X741624Y580707D03*
X741200Y577470D03*
X749131Y570340D03*
X750062Y655415D03*
X753309Y655515D03*
X750074Y648739D03*
X753483Y648749D03*
X751885Y666724D03*
X753231Y678679D03*
X742579Y676093D03*
X746665Y678879D03*
X750168Y675833D03*
X748049Y767300D03*
Y771100D03*
X745439Y1314048D03*
X748188Y1327317D03*
X745491Y1327124D03*
X742971D03*
X745439Y1323048D03*
Y1320048D03*
Y1317048D03*
X745691Y1332424D03*
Y1329924D03*
Y1334924D03*
X748188Y1333017D03*
Y1330517D03*
X745691Y1339924D03*
Y1337424D03*
X748188Y1335517D03*
X742971Y1337124D03*
Y1339624D03*
Y1334624D03*
Y1329624D03*
Y1332124D03*
X739501Y1342244D03*
Y1344744D03*
X739932Y1398042D03*
X745201Y1398194D03*
X752643Y1400239D03*
X749155Y1398639D03*
X751893Y1397671D03*
X745201Y1400702D03*
X742212Y1394517D03*
X739611Y1458211D03*
X750418Y1468893D03*
X750968Y1482349D03*
X746111Y1504125D03*
X745984Y1501052D03*
X745001Y1516471D03*
X750205Y1512307D03*
X750155Y1516451D03*
X739900Y1523152D03*
X748782Y1555496D03*
X742782D03*
X739782D03*
X745782D03*
X739782Y1558496D03*
Y1561496D03*
Y1564496D03*
X745782Y1558496D03*
X742782D03*
X745782Y1561496D03*
X742782D03*
X745782Y1564496D03*
X742782D03*
X739782Y1567496D03*
X742782D03*
X748782Y1558496D03*
Y1561496D03*
Y1564496D03*
X747110Y1575863D03*
X747150Y1583247D03*
X747110Y1579863D03*
X739782Y1570496D03*
X742782D03*
X738880Y1582361D03*
Y1577231D03*
X747160Y1587773D03*
X749167Y1591967D03*
X754635Y1592571D03*
X738880Y1587491D03*
X745998Y1597463D03*
X742998D03*
X745998Y1594463D03*
X742998D03*
X739998Y1597463D03*
Y1594463D03*
X745998Y1600463D03*
X742998D03*
X739998D03*
X745998Y1603663D03*
X742998D03*
X739998D03*
X745998Y1606663D03*
X742998D03*
X739998D03*
X743664Y1626945D03*
X753770Y1636083D03*
X751521Y1656008D03*
X739880Y1648046D03*
X742792Y1647982D03*
X745075Y1665675D03*
X754030Y1669256D03*
X748254Y1674771D03*
X752187Y1682994D03*
X748413Y1679367D03*
X746766Y1696036D03*
X740328Y1698376D03*
X747289Y1693063D03*
X752187Y1691058D03*
X741030Y1723903D03*
Y1726903D03*
X741160Y1721150D03*
X741025Y1718195D03*
X757721Y62132D03*
X760221D03*
X762721D03*
X755621Y51602D03*
X758621D03*
X757721Y64632D03*
X760221D03*
X763221Y65132D03*
X757188Y91829D03*
X757694Y98108D03*
Y100653D03*
X760193Y106500D03*
X757576Y112575D03*
X756000Y145500D03*
X754825Y163397D03*
X756303Y158417D03*
X765950Y190669D03*
X765000Y186500D03*
X754737Y185469D03*
X757629Y239295D03*
X761067Y280355D03*
X763384Y279231D03*
X763508Y284404D03*
X763463Y281840D03*
X760614Y284100D03*
X754759Y281007D03*
X758510Y298620D03*
X760462Y295662D03*
X757937Y303908D03*
X768130Y335363D03*
X758245Y343763D03*
X764331Y374401D03*
X756347Y360851D03*
X764983Y368052D03*
X766304Y372862D03*
X768304Y374362D03*
X759652D03*
X755500Y386862D03*
X759500D03*
X763500D03*
X767500D03*
X759500Y390791D03*
X755500Y390862D03*
X759500Y402098D03*
X767500Y401470D03*
Y390862D03*
X763500D03*
X757258Y408763D03*
X765975Y414414D03*
X769648Y430511D03*
X770530Y423460D03*
X768301Y438223D03*
X770918Y442510D03*
X770042Y446829D03*
X770590Y470940D03*
X762800Y493654D03*
X764500Y521862D03*
X756500Y513340D03*
X764500D03*
X756800Y517050D03*
X760500Y521189D03*
X764600Y517022D03*
X756186Y529888D03*
X764500Y529862D03*
X760500Y529845D03*
X757860Y537859D03*
X760660Y537862D03*
X756500Y545862D03*
X764500D03*
X759568Y545867D03*
X768340Y563678D03*
X765809Y563410D03*
X758103Y556873D03*
X765041Y565867D03*
X762530Y565340D03*
X757745Y655353D03*
X755765Y666904D03*
X762656Y667835D03*
X756936Y676319D03*
X768565Y677573D03*
X760529Y677715D03*
X764401Y676968D03*
X762396Y732915D03*
X754532Y735859D03*
X760425Y736233D03*
X764568Y736183D03*
X761608Y766871D03*
X759839Y1313948D03*
Y1319948D03*
X760204Y1327314D03*
X762754D03*
X759839Y1316948D03*
X757638Y1327317D03*
X759839Y1322948D03*
X760204Y1332514D03*
Y1330014D03*
Y1335014D03*
X757638Y1333017D03*
Y1330517D03*
X760194Y1340024D03*
Y1337524D03*
X757638Y1335517D03*
X762844Y1337324D03*
Y1339824D03*
X762754Y1334814D03*
Y1329814D03*
Y1332314D03*
X762261Y1343424D03*
Y1345924D03*
X760980Y1385146D03*
Y1388046D03*
X758089Y1390981D03*
X760519D03*
X755659D03*
X767549Y1391286D03*
Y1397086D03*
Y1394186D03*
X765349Y1392686D03*
X765449Y1395686D03*
X763283Y1397316D03*
Y1394416D03*
X758163Y1490789D03*
Y1498663D03*
Y1494726D03*
Y1502600D03*
Y1506538D03*
Y1522286D03*
Y1510474D03*
X757826Y1514412D03*
X758056Y1518349D03*
X760650Y1570633D03*
Y1578733D03*
Y1574733D03*
X757610Y1576023D03*
X766212Y1568043D03*
X757650Y1580023D03*
X766950Y1581233D03*
X757610Y1584023D03*
X767750Y1584108D03*
X757610Y1589023D03*
X760650Y1587733D03*
X760521Y1595500D03*
X759723Y1626161D03*
X755261Y1628208D03*
X758030Y1668583D03*
X754839Y1678069D03*
X768463Y1687769D03*
X757161Y1696424D03*
X768733Y1694485D03*
X781441Y118637D03*
X782819Y149471D03*
X780159Y146961D03*
X772270Y153728D03*
X771427Y158026D03*
X782712Y260466D03*
X777408Y256648D03*
X777421Y277962D03*
X779884Y281705D03*
X769790Y296231D03*
X777468Y296315D03*
X769861Y302462D03*
X782641Y310888D03*
X779681Y313053D03*
X770190Y312563D03*
X779121Y303410D03*
Y308755D03*
X780046Y328268D03*
X772119Y333537D03*
X771964Y339716D03*
X781812Y341863D03*
X779118Y341749D03*
X769000Y364000D03*
X776500Y371000D03*
X784500Y367500D03*
X771512Y386862D03*
X775388Y390862D03*
X770000Y380787D03*
X777612Y403505D03*
X771512Y390862D03*
X780295Y403538D03*
X784498Y396353D03*
X782700Y415284D03*
X773181Y415197D03*
X773233Y409154D03*
X783256Y409340D03*
X770159Y410257D03*
X783770Y422454D03*
X772610Y434690D03*
X780877Y427344D03*
X771718Y426804D03*
X780877Y423344D03*
X783821Y431534D03*
X780877Y431368D03*
X772677Y451374D03*
X780577Y435564D03*
X780877Y443344D03*
Y447344D03*
X780977Y459524D03*
X780877Y463344D03*
Y455344D03*
X783377Y451344D03*
X780877Y475344D03*
X780759Y479344D03*
X783877Y475344D03*
X772427D03*
X783759Y479344D03*
X780877Y483344D03*
X772390Y491047D03*
X772427Y487344D03*
X783358Y495344D03*
X783351Y499221D03*
X771039Y511292D03*
X775100Y502504D03*
X772427Y495344D03*
X777166Y504477D03*
X774998Y511306D03*
X774964Y514204D03*
X772100Y532700D03*
X777200Y530250D03*
X772000Y529862D03*
X781699Y536425D03*
X772000Y545862D03*
X776345Y545733D03*
X777754Y558740D03*
X773463Y563455D03*
X778747Y572269D03*
X779448Y632498D03*
X772459Y655290D03*
X771553Y677963D03*
X777750Y767300D03*
Y771100D03*
X783280Y1296009D03*
X778030Y1296259D03*
X780530D03*
X783280Y1298509D03*
X785520Y1292160D03*
X769439Y1313948D03*
X783280Y1301009D03*
X769439Y1319948D03*
Y1322948D03*
Y1316948D03*
X770881Y1343344D03*
X782115Y1334173D03*
X770881Y1345844D03*
X774646Y1516441D03*
X772906Y1522901D03*
X774616Y1520361D03*
X778850Y1556133D03*
X781850D03*
Y1559133D03*
Y1562133D03*
Y1565133D03*
X778850Y1559133D03*
Y1562133D03*
Y1565133D03*
X771450Y1577333D03*
X781850Y1568133D03*
Y1571133D03*
X778850Y1568133D03*
Y1571133D03*
X779977Y1577233D03*
Y1582363D03*
X771550Y1587133D03*
X774420Y1587284D03*
X779977Y1587493D03*
X779550Y1594533D03*
X782550D03*
X776550Y1597533D03*
Y1594533D03*
X779550Y1597533D03*
X782550D03*
Y1600533D03*
X776550D03*
X779550D03*
Y1606533D03*
X782550Y1603533D03*
X779550D03*
X776550Y1606533D03*
Y1603533D03*
X782550Y1606533D03*
X785181Y120947D03*
X792681D03*
X790181D03*
X787681D03*
X783941Y118637D03*
X786441D03*
X788941D03*
X785529Y270459D03*
X798205Y279146D03*
X794058Y301569D03*
X793221Y296062D03*
X793897Y309026D03*
X793855Y305316D03*
X798493Y301377D03*
X795921Y312662D03*
X787500Y328362D03*
X799226Y328467D03*
X791726D03*
X783726D03*
X785674Y342279D03*
X788806Y342236D03*
X791403Y342262D03*
X793951Y342224D03*
X795685Y357498D03*
X792302Y357537D03*
X798312Y372571D03*
X796021Y395924D03*
X797000Y404000D03*
X786571Y403455D03*
X785923Y419194D03*
X787000Y407500D03*
X796283Y415344D03*
Y419344D03*
X786877Y427344D03*
X796283Y423344D03*
Y431344D03*
X783877Y427344D03*
X796283D03*
X786999Y435476D03*
X797252Y443344D03*
X786877D03*
X796333Y435344D03*
X786203Y447054D03*
X783877Y435444D03*
X797197Y447344D03*
X786887Y451344D03*
X797252D03*
X797322Y463344D03*
X786825Y459518D03*
X786755Y455524D03*
X797252Y455344D03*
X797326Y479344D03*
X786877Y471344D03*
X797463Y476159D03*
X786877Y475344D03*
X786440Y480769D03*
X797405Y487464D03*
X797326Y483344D03*
X787092Y490681D03*
X786358Y483566D03*
X786102Y507536D03*
X787446Y495344D03*
X787279Y499238D03*
X790503Y501826D03*
X799450Y511801D03*
X800674Y504130D03*
X789125Y529425D03*
X800500Y540500D03*
X794357Y559996D03*
X785919Y559660D03*
X792782Y565323D03*
X791723Y574946D03*
X799742Y628983D03*
X789135Y617097D03*
X783653Y631671D03*
X787591Y631785D03*
X788537Y734410D03*
X793131Y734310D03*
X784543Y734510D03*
X791308Y766871D03*
X789020Y1292160D03*
X792520D03*
X796020D03*
X794273Y1354600D03*
Y1357600D03*
Y1364500D03*
Y1361500D03*
X784669Y1462178D03*
X796955Y1487468D03*
X788710Y1488821D03*
X784277Y1504569D03*
Y1500632D03*
Y1508506D03*
Y1512443D03*
X791867Y1524254D03*
X784850Y1556133D03*
X796850D03*
X790850D03*
X787850D03*
X793850D03*
X784850Y1559133D03*
Y1562133D03*
Y1565133D03*
X796850Y1559133D03*
Y1562133D03*
Y1565133D03*
X787850Y1559133D03*
Y1562133D03*
Y1565133D03*
X793850Y1559133D03*
X790850D03*
X793850Y1562133D03*
X790850D03*
X793850Y1565133D03*
X790850D03*
X799150Y1581379D03*
X784850Y1568133D03*
Y1571133D03*
X787850Y1568133D03*
Y1571133D03*
X793850Y1568133D03*
X790850D03*
X793850Y1571133D03*
X790850D03*
X791077Y1577233D03*
X785577D03*
X791077Y1582363D03*
X796650Y1583347D03*
X785577Y1587493D03*
X791077D03*
X791550Y1597533D03*
X785550Y1594533D03*
X788550D03*
X791550D03*
X785550Y1597533D03*
X788550D03*
X785550Y1600533D03*
X788550D03*
X791550D03*
Y1606533D03*
X788550D03*
X785550D03*
X791550Y1603533D03*
X788550D03*
X785550D03*
X803302Y265848D03*
X812867Y278860D03*
X810139Y274098D03*
X804330Y281380D03*
X801341Y279141D03*
X799935Y286823D03*
X799113Y297733D03*
X803893Y301969D03*
X805871Y304812D03*
X806461Y310610D03*
X808617Y330102D03*
X806117D03*
X812070Y341590D03*
X803410Y341572D03*
X803500Y366000D03*
X802660Y381020D03*
X802462Y387756D03*
X807564Y403805D03*
X811224Y395974D03*
X803412Y403978D03*
X813148Y403908D03*
X805425Y395502D03*
X813252Y427060D03*
X802270Y435372D03*
X802459Y443218D03*
X813208Y435344D03*
X812895Y449802D03*
X813114Y443344D03*
X802533Y449802D03*
X812983Y463578D03*
X813114Y459344D03*
X801552Y463318D03*
X802752Y459344D03*
X813114Y455344D03*
X812983Y471344D03*
Y476159D03*
X801874Y471344D03*
X802752Y480159D03*
X812983D03*
X813000Y484862D03*
X801762Y495344D03*
X802752Y487344D03*
X801753Y491344D03*
X813187Y498362D03*
X813114Y495344D03*
X802250Y500504D03*
X801857Y508031D03*
X805940Y534500D03*
X805341Y578059D03*
X805199Y620347D03*
X804863Y626789D03*
X805150Y623843D03*
X807451Y767299D03*
X807127Y770958D03*
X799280Y1296009D03*
X802030Y1296259D03*
X804530D03*
X807601Y1299241D03*
X799280Y1298509D03*
Y1301009D03*
X801614Y1339062D03*
X811771Y1355488D03*
X799071Y1350088D03*
X807866Y1369177D03*
X805366Y1367093D03*
X802866D03*
X807866Y1366677D03*
X808714Y1490376D03*
Y1487376D03*
Y1506784D03*
Y1519784D03*
Y1509784D03*
Y1516784D03*
X802150Y1570633D03*
Y1578633D03*
Y1582833D03*
X810150Y1574633D03*
X813150Y1579410D03*
Y1570633D03*
X810050Y1584033D03*
X802150Y1594633D03*
X810850Y1587733D03*
X810150Y1590633D03*
X813049D03*
X802700Y1587183D03*
X810150Y1602633D03*
Y1598633D03*
X802150Y1606633D03*
X819321Y56961D03*
X823115Y115223D03*
X820901Y147112D03*
X814571Y145952D03*
X814532Y139851D03*
X822635Y165468D03*
X825332Y166862D03*
X813676Y266065D03*
X823067Y273225D03*
X823038Y276301D03*
X819828Y288063D03*
X827621Y302962D03*
X822689Y305148D03*
X826915Y311842D03*
X822252Y309973D03*
X816232Y341584D03*
X818677Y356405D03*
X826765Y356334D03*
X817780Y366905D03*
X823778Y376378D03*
X818157Y381020D03*
X816991Y395337D03*
X820018Y403710D03*
X816281Y403814D03*
X828286Y401567D03*
X824653Y405347D03*
X817497Y415344D03*
X827341Y419344D03*
X817497D03*
X827341Y415344D03*
X817497Y427060D03*
X826474Y431344D03*
X816239Y435344D03*
X817497Y431060D03*
X826474Y435344D03*
X816117Y443552D03*
X816236Y439279D03*
X816109Y449802D03*
X822878Y446425D03*
X816109Y455344D03*
X816000Y463578D03*
X816170Y458524D03*
X826912Y475989D03*
X816109Y471344D03*
X816409Y467568D03*
X817393Y491594D03*
X830212Y483892D03*
X826472Y483896D03*
X827000Y489055D03*
X817996Y496219D03*
X828259Y501027D03*
X824380Y517595D03*
X827237Y550771D03*
X817849Y550871D03*
X820620Y550846D03*
X824366Y552444D03*
X827832Y554269D03*
X814489Y558082D03*
X825200Y580300D03*
X815287Y580401D03*
X820617Y641273D03*
X816732Y629198D03*
X815753Y644219D03*
X817900Y649012D03*
X822579Y760169D03*
X822218Y756979D03*
X822794Y767511D03*
X825390Y770020D03*
X822794Y777511D03*
X816550Y766871D03*
X822625Y763529D03*
X822794Y772511D03*
Y775011D03*
X825061Y764884D03*
X822864Y783262D03*
X822772Y788359D03*
X822790Y785838D03*
X822883Y780334D03*
X822982Y791245D03*
X822555Y807409D03*
X822794Y797511D03*
Y800011D03*
Y795011D03*
X822494Y802941D03*
X823927Y907676D03*
X823958Y936140D03*
X826958D03*
X823958Y939140D03*
X826958D03*
X827088Y933387D03*
X824036Y933394D03*
X826953Y930432D03*
X824003Y930319D03*
X828109Y1234504D03*
X826728Y1246315D03*
X824444Y1249420D03*
X828246Y1266501D03*
X814296Y1384045D03*
Y1387445D03*
X824714Y1490376D03*
Y1487376D03*
X816690Y1490376D03*
Y1487376D03*
X824714Y1500376D03*
Y1497376D03*
Y1506784D03*
X816717Y1500388D03*
X816729Y1497364D03*
X816693Y1506784D03*
X824714Y1519784D03*
Y1509784D03*
Y1516784D03*
X816706Y1519820D03*
X816693Y1516784D03*
X816694Y1509796D03*
X824714Y1529784D03*
Y1526784D03*
X816714Y1529784D03*
Y1526784D03*
X823850Y1556133D03*
X820850D03*
X826850D03*
X820850Y1565133D03*
Y1562133D03*
Y1559133D03*
X826850Y1565133D03*
X823850D03*
X826850Y1562133D03*
Y1559133D03*
X823850Y1562133D03*
Y1559133D03*
X820850Y1571133D03*
Y1568133D03*
X826850Y1571133D03*
Y1568133D03*
X823850Y1571133D03*
Y1568133D03*
X821977Y1577233D03*
X827577D03*
X821977Y1582363D03*
X816150Y1587284D03*
X821977Y1587493D03*
X827577D03*
X821550Y1594533D03*
X827550Y1597533D03*
Y1594533D03*
X824550Y1597533D03*
Y1594533D03*
X821550Y1597533D03*
Y1600533D03*
X827550D03*
X824550D03*
X815550Y1606533D03*
X818550D03*
X821550Y1603533D03*
X818550D03*
X827550Y1606533D03*
X824550D03*
X821550D03*
X827550Y1603533D03*
X824550D03*
X842320Y-21711D03*
Y-18311D03*
Y18289D03*
Y21689D03*
X828601Y61752D03*
X836780Y68008D03*
X839899Y87248D03*
X841585Y94181D03*
X837251Y93221D03*
X839361Y114862D03*
X835115Y115223D03*
X845221Y135862D03*
Y129362D03*
X829115Y147123D03*
X838221Y163862D03*
X835221D03*
X842721Y181362D03*
X837161Y213207D03*
X844527Y204968D03*
X838821Y206872D03*
X837161Y218212D03*
X837501Y229642D03*
X836305Y268624D03*
X836181Y275686D03*
X830418Y311865D03*
X837754Y335345D03*
X829800Y331013D03*
X840457Y335368D03*
X842257Y350376D03*
X829344Y356224D03*
X833219Y375992D03*
X840357Y382813D03*
X833097Y393000D03*
X837912Y401545D03*
X834426Y401504D03*
X833000Y409500D03*
X838500D03*
X837847Y405347D03*
X833807Y423257D03*
X841809Y423219D03*
X838000Y423362D03*
X829106Y439279D03*
X842825Y448739D03*
X828979Y449802D03*
X834106Y439279D03*
X828714Y443552D03*
X833800Y444700D03*
X828751Y455344D03*
Y463578D03*
X834251Y455578D03*
X828751Y459344D03*
X832224Y450328D03*
X831381Y455167D03*
X833751Y463578D03*
X842825Y452739D03*
X828751Y471344D03*
Y467568D03*
X838575Y477554D03*
X839200Y467900D03*
X830046Y476031D03*
X838561Y484071D03*
X841854Y504972D03*
X833000Y503500D03*
X831798Y515314D03*
X838342Y514610D03*
X839061Y555808D03*
X841660Y558200D03*
X835519Y580056D03*
X831018Y583076D03*
X835059Y660940D03*
X837391Y659820D03*
X831505Y897291D03*
X831582Y905153D03*
X832347Y1251703D03*
X844250Y1266759D03*
X832274Y1277301D03*
X832342Y1274626D03*
X833756Y1330156D03*
X834017Y1336252D03*
X833963Y1339464D03*
X838963Y1345974D03*
X833853Y1345833D03*
X841039Y1358082D03*
X839244Y1352094D03*
X841472Y1365050D03*
X835850Y1556133D03*
X829850D03*
X832850D03*
X838850D03*
X832850Y1565133D03*
X835850D03*
X832850Y1562133D03*
X835850D03*
X832850Y1559133D03*
X835850D03*
X829850Y1565133D03*
Y1562133D03*
Y1559133D03*
X838850Y1565133D03*
Y1562133D03*
Y1559133D03*
X841150Y1581379D03*
X832850Y1571133D03*
X835850D03*
X832850Y1568133D03*
X835850D03*
X829850Y1571133D03*
Y1568133D03*
X833077Y1577233D03*
Y1582363D03*
X838650Y1583347D03*
X833077Y1587493D03*
X830550Y1597533D03*
X833550D03*
X830550Y1594533D03*
X833550D03*
X830550Y1600533D03*
X833550D03*
X830550Y1603533D03*
X836550Y1606533D03*
Y1603533D03*
X833550D03*
X830550Y1606533D03*
X833550D03*
X850016Y87341D03*
X843856Y87711D03*
X847473Y94754D03*
X854221Y135862D03*
Y129362D03*
X854201Y143062D03*
X848745Y160137D03*
X845721Y181362D03*
X856213Y191545D03*
X855859Y212425D03*
X855934Y215375D03*
X847581Y232222D03*
X853621Y269057D03*
X853829Y262057D03*
X846189Y281419D03*
X856244Y286447D03*
X843504Y287602D03*
X855481Y299692D03*
X860071Y304850D03*
X843308Y335550D03*
X857187Y342210D03*
X848030Y338461D03*
X850155Y335042D03*
X852303Y337488D03*
X852177Y341882D03*
X848425Y378089D03*
X854552Y381000D03*
X854190Y404035D03*
X855722Y416606D03*
X846000Y418862D03*
X854239Y412911D03*
X851517Y411745D03*
X846000Y423362D03*
X845986Y429413D03*
X857942Y448575D03*
X845100Y440100D03*
X857887Y459847D03*
X848500Y452128D03*
X847686Y475915D03*
X847303Y485788D03*
X846104Y494661D03*
X847518Y490905D03*
X846411Y482128D03*
X849772Y494585D03*
X852209Y507211D03*
X855497Y507205D03*
X849351Y499070D03*
X848097Y503315D03*
X855837Y519713D03*
X847941Y538325D03*
X845094Y535110D03*
X844741Y543864D03*
X843655Y555683D03*
X847435Y555496D03*
X856647Y616786D03*
X854484Y647436D03*
X848999Y644995D03*
X846931Y1291468D03*
X846895Y1295981D03*
X845801Y1287776D03*
X851500Y1302000D03*
X851400Y1305499D03*
X852811Y1313450D03*
X850684Y1310000D03*
X852955Y1320320D03*
X856500Y1321500D03*
X853100Y1331688D03*
X856500Y1330500D03*
X852780Y1338365D03*
X856500Y1339500D03*
Y1348500D03*
X844150Y1578633D03*
Y1570633D03*
Y1582833D03*
X852150Y1574633D03*
X855150Y1579410D03*
Y1570633D03*
X852050Y1584033D03*
X844150Y1594633D03*
X852850Y1587733D03*
X852150Y1590633D03*
X855049D03*
X844700Y1587183D03*
X852150Y1602633D03*
Y1598633D03*
X844150Y1606633D03*
X857550Y1606533D03*
X858630Y60293D03*
X863343Y90021D03*
X865912Y89252D03*
X870892Y131868D03*
X871145Y163862D03*
X875170Y185113D03*
X867529Y231788D03*
X863104Y273103D03*
X868104D03*
X867701Y267537D03*
X863230Y280001D03*
X866619Y286801D03*
X870672Y295485D03*
X870008Y302273D03*
X872508D03*
X871099Y323000D03*
X864342Y330858D03*
X860942D03*
X860587Y342210D03*
X860372Y375195D03*
X866168Y374774D03*
X871190Y382230D03*
X858925Y398537D03*
X864826Y411557D03*
X870220Y430424D03*
X870826Y423423D03*
X870064Y427703D03*
X859500Y429362D03*
X863420D03*
X859469Y425293D03*
X860541Y446089D03*
X860328Y475162D03*
X858288Y467048D03*
X860280Y488636D03*
X860299Y491620D03*
X864361Y493001D03*
X860508Y497772D03*
X862987Y507305D03*
X860341Y503154D03*
X860658Y515961D03*
X867356Y558714D03*
X867733Y575522D03*
X864590Y642420D03*
X870590D03*
X866727Y650739D03*
X866549Y748027D03*
X869275Y750472D03*
X873175D03*
X868496Y776516D03*
X868539Y790882D03*
X870591Y785437D03*
X865466Y790581D03*
Y785581D03*
Y788081D03*
Y783081D03*
X865394Y801244D03*
X865466Y793081D03*
Y795581D03*
Y798081D03*
X865569Y806045D03*
Y808545D03*
X863369Y827461D03*
X863344Y824713D03*
X863372Y833469D03*
Y830718D03*
X867651Y836820D03*
X867646Y833388D03*
X863671Y839062D03*
X865601Y841219D03*
X865109Y850795D03*
X864768Y844815D03*
X864140Y856052D03*
X864020Y859972D03*
X864106Y863534D03*
X864003Y866609D03*
X866005Y941554D03*
X863055Y941441D03*
X863010Y947262D03*
X866010D03*
X863010Y950262D03*
X866010D03*
X866140Y944509D03*
X863088Y944516D03*
X862044Y1249687D03*
X866294Y1255903D03*
X874989Y1410441D03*
X863745Y1444560D03*
X871214Y1466542D03*
X865850Y1556133D03*
X871850D03*
X862850D03*
X868850D03*
X865850Y1565133D03*
Y1562133D03*
Y1559133D03*
X862850Y1565133D03*
Y1562133D03*
Y1559133D03*
X868850Y1565133D03*
X871850D03*
X868850Y1562133D03*
X871850D03*
X868850Y1559133D03*
X871850D03*
X865850Y1571133D03*
Y1568133D03*
X862850Y1571133D03*
Y1568133D03*
X868850Y1571133D03*
X871850D03*
X868850Y1568133D03*
X871850D03*
X863977Y1577233D03*
Y1582363D03*
X869577Y1577233D03*
X858150Y1587284D03*
X863977Y1587493D03*
X869577D03*
X863550Y1597533D03*
X866550Y1594533D03*
Y1597533D03*
X869550Y1594533D03*
Y1597533D03*
X863550Y1594533D03*
X872550D03*
Y1597533D03*
X866550Y1600533D03*
X869550D03*
X863550D03*
X872550D03*
Y1606533D03*
Y1603533D03*
X863550Y1606533D03*
X866550D03*
X869550D03*
X860550D03*
X869550Y1603533D03*
X866550D03*
X863550D03*
X860550D03*
X876696Y176862D03*
Y171362D03*
X887521D03*
Y176862D03*
X889351Y195489D03*
X878328Y183169D03*
X878221Y187449D03*
X887130Y183169D03*
X884986Y198829D03*
X881354Y267407D03*
X884004Y278712D03*
Y274482D03*
X885764Y284361D03*
X877448Y284825D03*
X884004Y271332D03*
X874244Y287047D03*
X873172Y295485D03*
X888000Y293000D03*
X877640Y315789D03*
X873884Y447991D03*
Y450491D03*
X885916Y653912D03*
X883731Y651690D03*
X884410Y794332D03*
X883633Y790336D03*
X883776Y786814D03*
X877459Y802356D03*
X875412Y797350D03*
X882582Y1075083D03*
X879582D03*
X876582D03*
X873582D03*
X882582Y1061983D03*
X879582D03*
X876582D03*
Y1071533D03*
Y1068533D03*
Y1065533D03*
X873582D03*
Y1068533D03*
Y1071533D03*
Y1061983D03*
X886707Y1229920D03*
Y1232920D03*
X881807Y1238920D03*
X876923Y1239520D03*
X886707Y1235920D03*
X881694Y1229763D03*
Y1232763D03*
Y1235763D03*
X876907Y1235586D03*
Y1232586D03*
Y1229586D03*
X881807Y1241920D03*
X877936Y1312336D03*
X883379Y1417881D03*
X875039Y1407246D03*
X886362Y1428973D03*
X884399Y1431507D03*
X879424Y1425001D03*
X883279Y1421726D03*
X883562Y1440356D03*
X881987Y1449608D03*
X887519Y1444625D03*
X877226Y1441585D03*
X887117Y1436735D03*
X877850Y1556133D03*
X874850D03*
X880850D03*
X874850Y1565133D03*
X877850D03*
X880850D03*
X874850Y1562133D03*
X877850D03*
X880850D03*
X874850Y1559133D03*
X877850D03*
X880850D03*
X886150Y1578633D03*
Y1570633D03*
Y1582833D03*
X883150Y1581379D03*
X874850Y1571133D03*
X877850D03*
X874850Y1568133D03*
X877850D03*
X875077Y1577233D03*
Y1582363D03*
X886150Y1594633D03*
X880650Y1583347D03*
X886700Y1587183D03*
X875077Y1587493D03*
X875550Y1597533D03*
Y1594533D03*
X886150Y1606633D03*
X875550Y1600533D03*
Y1606533D03*
X878550D03*
Y1603533D03*
X875550D03*
X891621Y207162D03*
X888930Y206823D03*
X891621Y209662D03*
X888930Y209323D03*
X896621Y207162D03*
X894121D03*
Y209662D03*
X896621D03*
X892376Y466430D03*
X899000Y481038D03*
X888372Y547518D03*
X902376Y590172D03*
X900323Y604377D03*
X900301Y828248D03*
Y831221D03*
X899500Y853000D03*
X901000Y909000D03*
X901842Y936863D03*
X903925Y948500D03*
X889273Y1134470D03*
X902382Y1137558D03*
X891996Y1149707D03*
X900280Y1150769D03*
X902482Y1140558D03*
X888247Y1219520D03*
Y1222520D03*
X891247D03*
Y1219520D03*
X888247Y1225520D03*
X896974Y1232869D03*
Y1235869D03*
X896907Y1238920D03*
X896974Y1229869D03*
X891247Y1225520D03*
X896907Y1241920D03*
X892000Y1307500D03*
X888854Y1337936D03*
X890620Y1342990D03*
X900885Y1435041D03*
X900808Y1437798D03*
X902377Y1456465D03*
X904850Y1556133D03*
X894150Y1574633D03*
X897150Y1579410D03*
Y1570633D03*
X894050Y1584033D03*
X894150Y1590633D03*
X894850Y1587733D03*
X897049Y1590633D03*
X900150Y1587284D03*
X894150Y1602633D03*
Y1598633D03*
X899550Y1606533D03*
X902550Y1603533D03*
Y1606533D03*
X917387Y184114D03*
X908621Y188899D03*
X910267Y242658D03*
X910093Y246015D03*
X916268Y269859D03*
X909023Y294734D03*
X910752Y286141D03*
X913512Y486743D03*
X903340Y505105D03*
X917582Y549564D03*
X909747Y579695D03*
X911980Y585280D03*
X910731Y590251D03*
X905526Y594657D03*
X910535Y619251D03*
X906706Y614062D03*
X909747Y628426D03*
X915334Y639166D03*
X908823Y655116D03*
X906274Y654921D03*
X909320Y663930D03*
X907207Y667646D03*
X906345Y742414D03*
X904535Y744639D03*
X906387Y821221D03*
Y815721D03*
X906313Y825095D03*
X903149Y825094D03*
X917000Y853000D03*
X907000Y899777D03*
X913000Y909000D03*
X917000D03*
Y918500D03*
X905000D03*
X915575Y948500D03*
X910000Y954500D03*
X912425Y948500D03*
X907075D03*
X910000Y957500D03*
X912500Y963309D03*
X907500D03*
X909000Y974000D03*
Y982000D03*
X911041Y979459D03*
X909000Y977491D03*
X919779Y1155658D03*
X915053Y1219520D03*
Y1222520D03*
X912053D03*
Y1219520D03*
Y1225520D03*
X915053D03*
X910707Y1229920D03*
Y1232920D03*
X905007Y1238920D03*
X910707Y1235920D03*
X905008Y1229940D03*
Y1232940D03*
Y1235940D03*
X905007Y1241920D03*
X917112Y1266300D03*
X917127Y1275251D03*
X917396Y1271025D03*
X917158Y1279451D03*
X917341Y1283775D03*
X916895Y1292330D03*
X916945Y1296713D03*
X917034Y1288235D03*
X912500Y1310000D03*
X914333Y1322700D03*
X914462Y1329351D03*
X914355Y1340726D03*
X914276Y1347550D03*
X913270Y1440429D03*
X910041Y1440536D03*
X907031Y1457231D03*
X909473Y1448779D03*
X910850Y1556133D03*
X907850D03*
X916850D03*
X913850D03*
X907850Y1559133D03*
Y1562133D03*
X910850Y1559133D03*
Y1562133D03*
X907850Y1565133D03*
X910850D03*
X904850Y1559133D03*
Y1562133D03*
Y1565133D03*
X913850Y1559133D03*
Y1562133D03*
Y1565133D03*
X916850Y1559133D03*
Y1562133D03*
Y1565133D03*
X907850Y1568133D03*
Y1571133D03*
X910850Y1568133D03*
Y1571133D03*
X904850Y1568133D03*
Y1571133D03*
X913850Y1568133D03*
Y1571133D03*
X916850Y1568133D03*
Y1571133D03*
X905977Y1577233D03*
Y1582363D03*
X911577Y1577233D03*
X917077D03*
Y1582363D03*
X905977Y1587493D03*
X911577D03*
X917077D03*
X914550Y1597533D03*
Y1594533D03*
X905550D03*
X911550Y1597533D03*
Y1594533D03*
X908550Y1597533D03*
Y1594533D03*
X905550Y1597533D03*
X917550D03*
Y1594533D03*
X914550Y1600533D03*
X905550D03*
X911550D03*
X908550D03*
X917550D03*
X914550Y1603533D03*
Y1606533D03*
X905550Y1603533D03*
X908550D03*
X911550D03*
Y1606533D03*
X908550D03*
X905550D03*
X917550Y1603533D03*
Y1606533D03*
X915991Y1667328D03*
X922128Y182486D03*
X923386Y193563D03*
X932129Y244103D03*
X922341Y263875D03*
X923103Y362852D03*
X924724Y372211D03*
X919294Y374503D03*
X921318Y372475D03*
X920018Y362877D03*
X921430Y507156D03*
X921367Y503407D03*
X924430Y507156D03*
X924367Y503407D03*
X922591Y496671D03*
X926730Y540897D03*
X921318Y549357D03*
X920031Y577846D03*
X926449Y577806D03*
X930406Y577308D03*
X923747Y584945D03*
X920989Y614132D03*
X925643Y616620D03*
X920989Y617692D03*
X924987Y622523D03*
X932000Y850500D03*
X920234Y843349D03*
X927777Y843416D03*
X930575Y864075D03*
X918500Y860075D03*
X920897Y881879D03*
X929603Y879000D03*
X920000Y895500D03*
X923000D03*
X925500Y907500D03*
X921000Y921925D03*
X925500Y916500D03*
X929500D03*
X932500Y941500D03*
X919500D03*
X928500D03*
X923500D03*
X926000Y949500D03*
Y946500D03*
X919272Y986782D03*
X920107Y1235920D03*
Y1232920D03*
Y1238920D03*
Y1229920D03*
Y1241920D03*
X924500Y1306000D03*
Y1302000D03*
X918000Y1312500D03*
Y1321500D03*
X925459Y1315352D03*
X925500Y1319000D03*
X922000Y1324000D03*
Y1328000D03*
X931326Y1328467D03*
X931216Y1323050D03*
X918000Y1330500D03*
Y1339500D03*
X922000Y1342000D03*
X925500Y1333000D03*
Y1337000D03*
X922000Y1346000D03*
X922850Y1556133D03*
X919850D03*
X922850Y1559133D03*
Y1562133D03*
Y1565133D03*
X919850Y1559133D03*
Y1562133D03*
Y1565133D03*
X925650Y1581379D03*
X919850Y1568133D03*
Y1571133D03*
X922650Y1583347D03*
X920550Y1603533D03*
Y1606533D03*
X921289Y1666337D03*
X927798Y1660762D03*
X945721Y173389D03*
X943221D03*
Y176389D03*
X945721D03*
X935551Y173329D03*
X938161Y173389D03*
Y176389D03*
X935591Y176049D03*
X940721Y173389D03*
Y176389D03*
X939271Y191419D03*
X935771D03*
X944520Y182094D03*
X936454Y184015D03*
X937267Y189010D03*
X945120Y193264D03*
X938570Y233152D03*
X945380Y233962D03*
X949181Y280131D03*
X939938Y386423D03*
X933390Y386405D03*
X944112Y386593D03*
X941764Y420403D03*
X944264D03*
X933390Y559943D03*
X939613Y562031D03*
X937310Y580755D03*
X941764Y587884D03*
X944264D03*
X935766Y587692D03*
X939511Y597073D03*
X935746Y611573D03*
X935783Y631192D03*
X937580Y655946D03*
X945602Y664653D03*
X934539Y664648D03*
X934339Y668533D03*
X941478Y668648D03*
X939216Y664767D03*
X948644Y811190D03*
X938000Y862620D03*
X943000Y862823D03*
X934925Y891425D03*
X945075Y891500D03*
X938500Y907500D03*
X946500Y915988D03*
X938500Y916500D03*
X934500D03*
X942500Y916340D03*
X942631Y943162D03*
X936960Y942898D03*
X935368Y939182D03*
X944515Y939850D03*
X940000Y973500D03*
Y986500D03*
Y982500D03*
Y977500D03*
X937148Y1134343D03*
X933234Y1145058D03*
X936393Y1148087D03*
X947305Y1150769D03*
X943101Y1219520D03*
Y1222520D03*
X946101D03*
Y1219520D03*
X943101Y1225520D03*
X946101D03*
X945691Y1229920D03*
Y1232920D03*
X940791Y1238920D03*
X935907Y1239520D03*
X945691Y1235920D03*
X940678Y1229763D03*
Y1232763D03*
Y1235763D03*
X935891Y1235586D03*
Y1232586D03*
Y1229586D03*
X940791Y1241920D03*
X940994Y1265636D03*
X941011Y1269499D03*
X941500Y1278059D03*
X941033Y1282115D03*
X946730Y1293219D03*
Y1290719D03*
X940919Y1290152D03*
X940937Y1294191D03*
X941083Y1286156D03*
X947135Y1287403D03*
X945872Y1304541D03*
Y1301500D03*
X945617Y1309500D03*
X935028Y1313769D03*
X935300Y1317525D03*
X939071Y1448219D03*
X949216Y1448337D03*
X944105Y1448317D03*
X946402Y1491204D03*
X943902D03*
X936402D03*
X938902D03*
X941402D03*
X933778D03*
X946402Y1501204D03*
Y1498704D03*
Y1496204D03*
Y1493704D03*
X943902D03*
Y1496204D03*
Y1498704D03*
Y1501204D03*
X936402Y1493704D03*
Y1496204D03*
Y1498704D03*
Y1501204D03*
X938902Y1493704D03*
Y1496204D03*
Y1498704D03*
Y1501204D03*
X941402Y1493704D03*
Y1496204D03*
Y1498704D03*
Y1501204D03*
X933778Y1493704D03*
Y1496204D03*
Y1498704D03*
Y1501204D03*
X944406Y1532791D03*
X936150Y1582233D03*
Y1578233D03*
Y1590233D03*
Y1586233D03*
X943798Y1660762D03*
X948401Y176499D03*
X961407Y205125D03*
X950950Y284662D03*
X947821Y386567D03*
X958158Y449020D03*
X958049Y453912D03*
X958101Y457846D03*
X958255Y465811D03*
X959033Y487289D03*
X957380Y515233D03*
X960054Y516982D03*
X962035Y518988D03*
X954757Y593045D03*
X948156Y593912D03*
X952497Y614080D03*
X951102Y628662D03*
X954362Y633314D03*
Y630061D03*
X954259Y657371D03*
X958299Y659886D03*
X954361Y660215D03*
X957462Y668700D03*
X951886Y804495D03*
X951895Y808163D03*
X951466Y816400D03*
X961592Y821737D03*
X949000Y850500D03*
X951000Y855425D03*
X958000Y865500D03*
Y862000D03*
X949500Y870500D03*
Y886500D03*
X953925Y900500D03*
X951169Y910425D03*
X957075Y906500D03*
X960925D03*
X954500Y915988D03*
X950500Y916150D03*
X948500Y937000D03*
X949407Y1137558D03*
X949507Y1140558D03*
X955958Y1232869D03*
Y1235869D03*
X955891Y1238920D03*
X955958Y1229869D03*
X955891Y1241920D03*
X964669Y1271000D03*
X963500Y1275000D03*
X955000Y1283000D03*
Y1287000D03*
X947650Y1314500D03*
Y1319000D03*
Y1323500D03*
Y1328000D03*
Y1337000D03*
Y1332500D03*
Y1341500D03*
Y1346000D03*
X960313Y1362654D03*
X958306Y1448056D03*
X954541Y1448307D03*
X961566Y1448341D03*
X953902Y1491204D03*
X951402D03*
X948902D03*
X956402D03*
X958902D03*
X961402D03*
X953902Y1501204D03*
Y1498704D03*
Y1496204D03*
Y1493704D03*
X951402Y1501204D03*
Y1498704D03*
Y1496204D03*
Y1493704D03*
X948902Y1501204D03*
Y1498704D03*
Y1496204D03*
Y1493704D03*
X956402D03*
X958902D03*
X961402D03*
X963402Y1501204D03*
X958402D03*
X955350Y1532760D03*
X961350D03*
X958350D03*
X959584Y1550824D03*
X949195Y1655145D03*
X951798Y1660762D03*
X975691Y161220D03*
X962673Y170263D03*
Y167763D03*
X967943Y204813D03*
X971943D03*
X975749Y202049D03*
X977221Y205399D03*
X964807Y205125D03*
X973997Y320848D03*
X966278Y556736D03*
X964114Y554704D03*
X976528Y801041D03*
Y803541D03*
Y806041D03*
Y808541D03*
X963500Y854719D03*
X973562Y859767D03*
X964075Y900500D03*
X966804Y1155658D03*
X969907Y1219520D03*
Y1222520D03*
X966907D03*
Y1219520D03*
Y1225520D03*
X969907D03*
X969691Y1229920D03*
Y1232920D03*
X963991Y1238920D03*
X969691Y1235920D03*
X963992Y1229940D03*
Y1232940D03*
Y1235940D03*
X979091Y1229920D03*
X963991Y1241920D03*
X964000Y1267000D03*
X966441Y1278145D03*
X972408Y1312557D03*
X973650Y1431424D03*
X969785Y1447987D03*
X967002Y1448013D03*
X964503Y1448097D03*
X969519Y1452784D03*
X973255Y1456714D03*
X975703Y1451367D03*
X967268Y1491204D03*
X969768D03*
X972268D03*
X974768D03*
X977268D03*
X963902D03*
X967268Y1501204D03*
Y1498704D03*
Y1496204D03*
Y1493704D03*
X969768D03*
Y1496204D03*
Y1498704D03*
Y1501204D03*
X972268Y1493704D03*
Y1496204D03*
Y1498704D03*
Y1501204D03*
X974768Y1493704D03*
Y1496204D03*
Y1498704D03*
Y1501204D03*
X977268Y1493704D03*
Y1496204D03*
Y1498704D03*
Y1501204D03*
X963902Y1493704D03*
X963120Y1520080D03*
Y1523080D03*
X967350Y1532760D03*
X964350D03*
X963120Y1526080D03*
X962584Y1550824D03*
X990579Y155248D03*
X981112Y161204D03*
X988751Y167541D03*
X986447Y158209D03*
X989605Y175400D03*
X985922Y171861D03*
X985445Y185389D03*
X986021Y195099D03*
X979849Y202049D03*
X983879Y202162D03*
X990221Y199699D03*
X987321Y198599D03*
Y202099D03*
X990221Y206699D03*
Y203199D03*
X987321Y205599D03*
X980406Y218283D03*
X980377Y215740D03*
X978269Y264929D03*
X982455Y260781D03*
Y271443D03*
X978827Y303412D03*
X984509Y303623D03*
X989582Y303563D03*
X988460Y358405D03*
X993460D03*
X984272Y349293D03*
X980346Y353527D03*
X981019Y349387D03*
X992460Y370659D03*
X985668Y389311D03*
X980690Y387784D03*
X984605Y408480D03*
X987581Y408332D03*
X988190Y424626D03*
X983358Y449026D03*
X991664Y446372D03*
X993650Y465315D03*
X988650D03*
X991270Y470212D03*
X990292Y494420D03*
X988125Y485193D03*
X986790Y480140D03*
X987440Y504742D03*
X982806Y498606D03*
X986056Y516014D03*
X994056Y521014D03*
Y516014D03*
Y526074D03*
Y531074D03*
X992125Y1061434D03*
X989125D03*
X986125D03*
X983125D03*
X992125Y1064984D03*
Y1067984D03*
X989125D03*
Y1064984D03*
X992125Y1074534D03*
Y1070984D03*
X989125D03*
Y1074534D03*
X986125D03*
X983125D03*
X979091Y1235920D03*
Y1232920D03*
Y1238920D03*
Y1241920D03*
X985396Y1268154D03*
X982665Y1265474D03*
X978318Y1263128D03*
X988242Y1273193D03*
X979228Y1297918D03*
X982000Y1307500D03*
X978026Y1459998D03*
X980779Y1451545D03*
X990634Y1491204D03*
X979768D03*
X982268D03*
X984768D03*
X987268D03*
X990634Y1493704D03*
Y1496204D03*
Y1498704D03*
Y1501204D03*
X979768Y1493704D03*
X982268D03*
X984768D03*
X987268D03*
X986768Y1501204D03*
X981768D03*
X986486Y1523080D03*
Y1520080D03*
Y1526080D03*
X991280Y1532760D03*
X988280D03*
X991196Y1550840D03*
X1006221Y164799D03*
X1002721D03*
X1005307Y155043D03*
X995181Y157689D03*
X999580Y154895D03*
X994257D03*
X996416Y176579D03*
X1002921Y178799D03*
X1002827Y172479D03*
X999221Y189299D03*
X1002721D03*
X1006161Y189019D03*
X1008918Y192994D03*
X1008121Y203525D03*
X1000611Y215039D03*
X1005641Y214969D03*
X1001196Y223898D03*
X1008707Y230423D03*
X997300Y234876D03*
X1006468Y301857D03*
X1003460Y358405D03*
X998460D03*
X994409Y349813D03*
X1000460Y369535D03*
X996889Y374156D03*
X1007080Y367087D03*
X999320Y394480D03*
X1006763Y396206D03*
X1003651Y433426D03*
X998859Y437141D03*
X998359Y451675D03*
X994900Y446192D03*
X998359Y462675D03*
Y457175D03*
X1003909Y454662D03*
Y460162D03*
X998359Y479175D03*
Y468175D03*
Y473675D03*
X996320Y470364D03*
X998359Y484675D03*
X1007077Y484937D03*
X998326Y499675D03*
X995530Y500034D03*
X1006206Y510304D03*
X1002056Y521014D03*
Y516014D03*
Y526074D03*
Y531074D03*
X1004527Y541924D03*
Y553224D03*
X1005270Y625710D03*
X1003090Y1037329D03*
X999350Y1310500D03*
Y1315000D03*
Y1319420D03*
Y1323840D03*
Y1328260D03*
Y1332740D03*
Y1341580D03*
Y1337160D03*
Y1346000D03*
X995500Y1368000D03*
X998000Y1365500D03*
X995000Y1362000D03*
X1000634Y1491204D03*
X998134D03*
X995634D03*
X993134D03*
X1003134D03*
X1005634D03*
X993134Y1496204D03*
Y1493704D03*
X1003134D03*
X1005634D03*
X1000634Y1501204D03*
Y1498704D03*
Y1496204D03*
Y1493704D03*
X998134Y1501204D03*
Y1498704D03*
Y1496204D03*
Y1493704D03*
X995634Y1501204D03*
Y1498704D03*
Y1496204D03*
Y1493704D03*
X993134Y1501204D03*
Y1498704D03*
X1005134Y1501204D03*
X994280Y1532760D03*
X997280D03*
X1000280D03*
X994196Y1550840D03*
X1009721Y164799D03*
X1013221D03*
X1014301Y179699D03*
X1017201D03*
X1019901Y179799D03*
X1011991Y189019D03*
X1014901Y189299D03*
X1017701Y189059D03*
X1011120Y198114D03*
X1020521Y194499D03*
X1011068Y207667D03*
X1021440Y226423D03*
X1019356Y222423D03*
X1010909Y213708D03*
X1011721Y233699D03*
X1019531Y230423D03*
X1018220Y243638D03*
X1015220D03*
X1009220D03*
X1014828Y268427D03*
Y258970D03*
X1013396Y280806D03*
X1011423Y282889D03*
X1023110Y287311D03*
X1017835Y291236D03*
X1023000Y298311D03*
X1016764Y350082D03*
X1010252Y363440D03*
X1009815Y404896D03*
X1020748Y420902D03*
Y425902D03*
X1023420Y462921D03*
X1017220Y464155D03*
X1023515Y454397D03*
X1019205Y457687D03*
X1023420Y468039D03*
X1017350Y472155D03*
X1022874Y474545D03*
X1019210Y480155D03*
X1013306Y518146D03*
Y532501D03*
X1017718Y541201D03*
X1019161Y554757D03*
X1024161D03*
X1017961Y545074D03*
X1009611Y550074D03*
Y545074D03*
X1021425Y568614D03*
X1012925Y558000D03*
X1011602Y568473D03*
X1016000Y563107D03*
X1019261Y571324D03*
X1007587Y761546D03*
Y772480D03*
Y775880D03*
Y764946D03*
Y783482D03*
Y786882D03*
Y794484D03*
Y797884D03*
X1016000Y1303000D03*
X1009905Y1305500D03*
X1009896Y1301500D03*
X1013605Y1316050D03*
X1013529Y1318950D03*
X1012500Y1322500D03*
Y1328500D03*
Y1341580D03*
X1013500Y1332740D03*
Y1337160D03*
X1016000Y1361000D03*
X1012500Y1347500D03*
X1021500Y1491204D03*
X1019000D03*
X1016500D03*
X1014000D03*
X1008134D03*
X1010634D03*
X1021500Y1501204D03*
Y1498704D03*
Y1496204D03*
Y1493704D03*
X1019000Y1501204D03*
Y1498704D03*
Y1496204D03*
Y1493704D03*
X1016500Y1501204D03*
Y1498704D03*
Y1496204D03*
Y1493704D03*
X1014000D03*
Y1496204D03*
Y1498704D03*
Y1501204D03*
X1008134Y1493704D03*
X1010634D03*
X1010134Y1501204D03*
X1009852Y1523080D03*
Y1520080D03*
Y1526080D03*
X1019440Y1532930D03*
X1022796Y1550840D03*
X1022801Y179799D03*
X1027690Y237902D03*
X1024220Y243638D03*
X1033590Y298311D03*
Y287311D03*
X1029200Y351614D03*
X1022674Y357848D03*
X1028146Y355960D03*
X1034214Y351601D03*
X1029601Y394387D03*
X1034855Y411704D03*
X1034409Y429618D03*
X1024443Y424051D03*
X1039015Y444404D03*
X1034899D03*
X1025830Y449022D03*
X1023320Y451112D03*
X1035860Y485976D03*
X1027504Y485637D03*
X1024509Y500168D03*
X1024546Y511254D03*
X1037254Y521014D03*
X1036708Y514883D03*
X1037254Y526074D03*
X1025631Y540104D03*
X1036021Y534990D03*
X1030000Y554500D03*
X1034412Y567416D03*
X1031000Y568500D03*
X1028500Y563000D03*
X1024000D03*
X1029431Y587342D03*
X1032055Y587260D03*
X1028540Y621000D03*
X1035269Y735474D03*
X1032736Y735320D03*
X1030190Y735023D03*
X1025493Y761819D03*
X1035026Y756009D03*
X1036427Y770532D03*
X1038867Y774960D03*
X1025493Y765719D03*
X1033236Y1279287D03*
X1033184Y1275996D03*
X1036411Y1275658D03*
X1036463Y1278949D03*
X1024000Y1491204D03*
X1026500D03*
X1029000D03*
X1031500D03*
X1034000D03*
X1024000Y1501204D03*
Y1498704D03*
Y1496204D03*
Y1493704D03*
X1026500D03*
X1029000D03*
X1031500D03*
X1034000D03*
X1033500Y1501204D03*
X1028500D03*
X1033218Y1523080D03*
Y1520080D03*
X1025440Y1532930D03*
X1022440D03*
X1033218Y1526080D03*
X1031440Y1532930D03*
X1028440D03*
X1025796Y1550840D03*
X1046384Y269814D03*
X1049451Y266747D03*
X1040060Y313528D03*
X1051873Y305482D03*
X1049573Y406586D03*
X1042015Y444404D03*
X1047515D03*
X1043377Y452740D03*
X1040836Y510894D03*
X1045254Y516014D03*
Y534074D03*
Y526074D03*
X1043991Y540979D03*
X1047335Y549574D03*
X1047200Y543090D03*
X1037301Y539685D03*
X1039407Y547723D03*
X1039000Y555000D03*
X1039718Y563268D03*
X1042628Y556845D03*
X1050956Y591090D03*
X1040626Y668441D03*
X1042389Y733426D03*
X1044056Y736188D03*
X1040915Y766870D03*
X1037566Y1047135D03*
X1037895Y1251517D03*
X1039546Y1275474D03*
X1039598Y1278765D03*
X1042855Y1275552D03*
X1042649Y1279152D03*
X1047366Y1491204D03*
X1044866D03*
X1037366D03*
X1042366D03*
X1039866D03*
X1049866D03*
X1047366Y1498704D03*
Y1496204D03*
Y1493704D03*
X1044866Y1496204D03*
Y1493704D03*
X1037366D03*
Y1496204D03*
Y1498704D03*
X1047366Y1501204D03*
X1044866D03*
Y1498704D03*
X1042366Y1501204D03*
Y1498704D03*
Y1496204D03*
Y1493704D03*
X1039866Y1501204D03*
Y1498704D03*
Y1496204D03*
Y1493704D03*
X1037366Y1501204D03*
X1049866Y1493704D03*
X1051866Y1501204D03*
X1051110Y1532850D03*
X1053290Y1652082D03*
X1045545Y1663089D03*
X1066231Y165078D03*
Y167578D03*
X1062704Y270875D03*
X1056941Y259176D03*
X1054613Y261586D03*
X1062923Y295053D03*
X1063356Y318297D03*
X1055934Y388988D03*
X1068143Y380188D03*
X1055934Y381988D03*
X1052505Y406576D03*
X1057798Y427059D03*
Y429618D03*
X1062642Y444859D03*
X1062640Y449155D03*
X1062741Y457959D03*
X1057276Y458155D03*
X1062173Y479655D03*
X1062873Y490180D03*
X1055905Y492537D03*
X1062250Y484672D03*
X1056960Y482262D03*
X1057450Y509242D03*
X1058231Y523238D03*
X1060719Y512359D03*
Y516059D03*
X1061817Y736362D03*
X1065154Y736282D03*
X1057057Y767299D03*
Y771099D03*
X1055171Y1307203D03*
Y1311203D03*
X1058143Y1433809D03*
X1065732Y1491204D03*
X1063232D03*
X1060732D03*
X1052366D03*
X1054866D03*
X1057366D03*
X1065732Y1501204D03*
Y1498704D03*
Y1496204D03*
Y1493704D03*
X1063232Y1501204D03*
Y1498704D03*
Y1496204D03*
Y1493704D03*
X1060732D03*
Y1496204D03*
Y1498704D03*
Y1501204D03*
X1052366Y1493704D03*
X1054866D03*
X1057366D03*
X1056866Y1501204D03*
X1056584Y1523080D03*
Y1520080D03*
X1057110Y1532850D03*
X1054110D03*
X1056584Y1526080D03*
X1063110Y1532850D03*
X1060110D03*
X1057396Y1550840D03*
X1054396D03*
X1071698Y270702D03*
X1078823Y269400D03*
X1071656Y366726D03*
X1078400Y391226D03*
X1074654Y380188D03*
X1078400Y383226D03*
X1074249Y387795D03*
X1082866Y403068D03*
X1074736Y396929D03*
X1072135Y396908D03*
X1072738Y411322D03*
Y416763D03*
Y421922D03*
X1072673Y428791D03*
X1077873Y463444D03*
X1080453Y457959D03*
X1071470Y475525D03*
X1080640Y467000D03*
X1080574Y471500D03*
X1071667D03*
Y467000D03*
X1080416Y482772D03*
X1080420Y487782D03*
X1071710Y483655D03*
Y488782D03*
X1081730Y509172D03*
X1078499Y648202D03*
X1072232Y667749D03*
X1068378Y736795D03*
X1070616Y766870D03*
X1076903Y1300361D03*
Y1302861D03*
X1079403D03*
Y1300361D03*
X1074403Y1302861D03*
Y1300361D03*
X1076903Y1305361D03*
X1079403D03*
X1074403D03*
Y1307861D03*
Y1310361D03*
Y1312861D03*
X1079403Y1307861D03*
Y1310361D03*
Y1312861D03*
X1076903D03*
Y1310361D03*
Y1307861D03*
X1079403Y1315361D03*
X1076903D03*
Y1317861D03*
X1079403D03*
X1074403D03*
Y1315361D03*
X1069839Y1368999D03*
Y1371540D03*
X1076601Y1382574D03*
X1071332Y1379914D03*
X1076601Y1380066D03*
X1080555Y1380511D03*
X1073612Y1376389D03*
X1081005Y1425458D03*
X1071117Y1445005D03*
X1077031Y1451498D03*
X1070312Y1452028D03*
X1073307Y1451931D03*
X1070732Y1491204D03*
X1068232D03*
X1073232D03*
X1075732D03*
X1078232D03*
X1080732D03*
X1070732Y1501204D03*
Y1498704D03*
Y1496204D03*
Y1493704D03*
X1068232Y1501204D03*
Y1498704D03*
Y1496204D03*
Y1493704D03*
X1073232D03*
X1075732D03*
X1078232D03*
X1080732D03*
X1080232Y1501204D03*
X1075232D03*
X1072134Y1647920D03*
X1081011Y1685499D03*
X1078011D03*
X1081011Y1682499D03*
X1078011D03*
X1077172Y1676686D03*
X1077881Y1688252D03*
X1080933Y1688245D03*
X1078016Y1691207D03*
X1080966Y1691320D03*
X1087421Y149716D03*
X1086714Y353515D03*
X1090086Y370417D03*
X1090061Y428019D03*
X1087963Y440605D03*
Y446105D03*
X1084840Y438234D03*
Y443515D03*
X1087963Y462605D03*
Y457105D03*
X1087940Y452110D03*
X1084840Y460005D03*
X1085851Y465978D03*
X1087963Y468105D03*
X1095448Y479426D03*
X1084000Y477500D03*
X1090000D03*
X1087963Y484605D03*
Y494641D03*
Y489641D03*
X1083434Y481500D03*
X1085730Y509362D03*
X1091730D03*
X1095730D03*
X1082622Y520652D03*
X1082438Y524033D03*
X1085438D03*
X1085622Y520652D03*
X1083281Y651601D03*
X1091270Y668286D03*
X1086758Y767299D03*
Y771099D03*
X1090203Y1307861D03*
Y1310361D03*
Y1312861D03*
X1092703D03*
Y1310361D03*
Y1307861D03*
Y1300361D03*
Y1302861D03*
X1090203D03*
Y1300361D03*
X1095203Y1302861D03*
Y1300361D03*
X1092703Y1305361D03*
X1090203D03*
X1095203D03*
Y1307861D03*
Y1310361D03*
Y1312861D03*
X1090203Y1315361D03*
X1092703D03*
Y1317861D03*
X1090203D03*
X1095203D03*
Y1315361D03*
X1087059Y1372853D03*
X1089489D03*
X1091919D03*
X1092889Y1367278D03*
Y1370178D03*
X1084043Y1382111D03*
X1083293Y1379543D03*
X1094683Y1379188D03*
Y1376288D03*
X1091598Y1491204D03*
X1089098D03*
X1086598D03*
X1084098D03*
X1091598Y1501204D03*
Y1498704D03*
Y1496204D03*
Y1493704D03*
X1089098Y1501204D03*
Y1498704D03*
Y1496204D03*
Y1493704D03*
X1086598Y1501204D03*
Y1498704D03*
Y1496204D03*
Y1493704D03*
X1084098D03*
Y1498704D03*
Y1501204D03*
Y1496204D03*
X1090300Y1532660D03*
X1087300D03*
X1096300D03*
X1093300D03*
X1089934Y1550784D03*
X1092934D03*
X1097000Y1629500D03*
X1096500Y1639000D03*
X1096768Y1635080D03*
X1090958Y1646528D03*
Y1649928D03*
X1084629Y1673002D03*
X1087141Y1688914D03*
X1092980Y1699179D03*
X1089030Y1717841D03*
Y1722841D03*
X1099500Y318000D03*
X1111001Y361272D03*
X1107300Y456944D03*
X1111076Y464388D03*
X1108076Y646774D03*
X1104443Y646983D03*
X1100316Y766870D03*
X1109503Y1302861D03*
X1107003D03*
Y1300361D03*
X1109503Y1305361D03*
X1107003D03*
Y1307861D03*
Y1310361D03*
Y1312861D03*
X1109503Y1307861D03*
Y1310361D03*
Y1312861D03*
Y1300361D03*
Y1315361D03*
Y1317861D03*
X1107003D03*
Y1315361D03*
X1102439Y1368999D03*
Y1371540D03*
X1098949Y1373158D03*
X1109201Y1382574D03*
X1103932Y1379914D03*
X1109201Y1380066D03*
X1106212Y1376389D03*
X1098949Y1378958D03*
X1096849Y1377558D03*
X1098949Y1376058D03*
X1096749Y1374558D03*
X1099098Y1501204D03*
X1102248Y1496186D03*
X1106700Y1526591D03*
X1112529Y1547661D03*
X1111701Y1558640D03*
X1107181Y1615917D03*
X1109811D03*
X1098549Y1625749D03*
X1100961Y1622543D03*
X1109000Y1671107D03*
X1105148Y1696029D03*
X1099108Y1691229D03*
X1100998Y1715841D03*
Y1725991D03*
X1119676Y54132D03*
X1124834Y56805D03*
X1124270Y404640D03*
X1121628Y401915D03*
X1121077Y511498D03*
X1125077D03*
X1126387Y615658D03*
X1118435Y625307D03*
X1114467Y640802D03*
X1120321Y635832D03*
X1116540Y651070D03*
X1112190Y651962D03*
X1116459Y767299D03*
Y771099D03*
X1112003Y1302861D03*
Y1300361D03*
Y1305361D03*
X1122803Y1307861D03*
X1125303D03*
Y1310361D03*
Y1312861D03*
X1122803D03*
Y1310361D03*
X1112003Y1312861D03*
Y1310361D03*
Y1307861D03*
X1125303Y1300361D03*
Y1302861D03*
X1122803D03*
Y1300361D03*
X1125303Y1305361D03*
X1122803D03*
X1125303Y1315361D03*
X1122803D03*
X1112003D03*
Y1317861D03*
X1125303D03*
X1122803D03*
X1124519Y1372853D03*
X1119659D03*
X1122089D03*
X1125469Y1367108D03*
Y1370008D03*
X1116643Y1382111D03*
X1113155Y1380511D03*
X1115893Y1379543D03*
X1124375Y1423488D03*
X1124415Y1426168D03*
Y1428668D03*
Y1431168D03*
Y1433668D03*
X1115098Y1468871D03*
Y1472271D03*
X1124875Y1490042D03*
X1125498Y1487292D03*
X1116917Y1506823D03*
X1119912Y1506936D03*
X1116917Y1509898D03*
X1119912Y1509891D03*
Y1515644D03*
X1116917D03*
X1119912Y1512644D03*
X1116917D03*
X1114617Y1526318D03*
X1113887Y1543447D03*
X1119459Y1556343D03*
X1118133Y1587998D03*
Y1591398D03*
X1115027Y1598788D03*
X1117247Y1604554D03*
X1113847D03*
X1124532Y1634915D03*
X1114286Y1630507D03*
X1117136Y1630441D03*
X1113490Y1651862D03*
X1112500Y1671107D03*
X1125784Y1662705D03*
X1124394Y1658967D03*
X1120595D03*
X1126000Y1672419D03*
X1122610Y1677976D03*
X1124091Y1683983D03*
X1114414Y1698859D03*
X1114394Y1695936D03*
X1119361Y1713734D03*
X1113948Y1711244D03*
X1126902Y60805D03*
X1142144Y63186D03*
X1132340Y468202D03*
Y471702D03*
X1141267Y500296D03*
X1134567Y513870D03*
X1139360Y516031D03*
X1129387Y615658D03*
X1138387D03*
X1132855Y609373D03*
X1135387Y615658D03*
X1130017Y766870D03*
X1127803Y1302861D03*
Y1300361D03*
Y1305361D03*
Y1307861D03*
Y1310361D03*
Y1312861D03*
X1139703Y1302861D03*
Y1300361D03*
Y1305361D03*
Y1307861D03*
Y1310361D03*
Y1312861D03*
X1127803Y1317861D03*
Y1315361D03*
X1139703Y1317861D03*
Y1315361D03*
X1135139Y1368999D03*
Y1371540D03*
X1131549Y1373158D03*
X1136632Y1379914D03*
X1138912Y1376389D03*
X1127283Y1379188D03*
X1129449Y1377558D03*
X1127283Y1376288D03*
X1129349Y1374558D03*
X1131549Y1378958D03*
Y1376058D03*
X1129965Y1403877D03*
X1127465D03*
X1129965Y1401377D03*
X1127465D03*
X1132465Y1403877D03*
Y1401377D03*
X1129925Y1398737D03*
X1127425D03*
X1134925D03*
X1132425D03*
X1137425D03*
X1137465Y1401377D03*
X1134965D03*
Y1403877D03*
X1137465D03*
X1137275Y1424138D03*
X1134775D03*
X1132275D03*
X1126875Y1423488D03*
X1129775Y1424138D03*
X1140175Y1423488D03*
X1140215Y1428668D03*
Y1426168D03*
X1134815Y1433668D03*
X1137315D03*
X1140215D03*
Y1431168D03*
X1132315Y1433668D03*
X1137315Y1426818D03*
X1134815D03*
X1137345Y1431058D03*
X1134845D03*
X1132315Y1426818D03*
X1132345Y1431058D03*
X1126915Y1428668D03*
Y1426168D03*
X1129815Y1433668D03*
X1126915D03*
Y1431168D03*
X1129815Y1426818D03*
X1129845Y1431058D03*
X1131478Y1485427D03*
X1134183Y1483926D03*
X1126951Y1484646D03*
X1140960Y1489434D03*
Y1491934D03*
X1141045Y1534952D03*
Y1537452D03*
Y1544952D03*
Y1542452D03*
Y1539952D03*
X1135033Y1556112D03*
X1142639Y1562789D03*
X1133765Y1568952D03*
X1140655Y1569256D03*
X1137755Y1569543D03*
X1138480Y1576364D03*
X1140422Y1595455D03*
X1139037Y1611383D03*
X1131824Y1600593D03*
Y1603993D03*
X1140325Y1598697D03*
X1139037Y1614153D03*
X1139142Y1618859D03*
X1139188Y1621603D03*
X1132981Y1634531D03*
X1141084Y1646672D03*
Y1643272D03*
X1137542Y1647925D03*
X1134207Y1669230D03*
X1129184Y1662705D03*
X1132406Y1658967D03*
X1136575Y1676239D03*
X1141356Y1676542D03*
X1133206Y1675383D03*
X1132176Y1690038D03*
X1142643Y74738D03*
X1151679Y72258D03*
X1150118Y207344D03*
X1155268D03*
Y212344D03*
X1150118D03*
X1155890Y478812D03*
X1150577Y478840D03*
X1144663Y492319D03*
Y500319D03*
X1151036Y501627D03*
X1143060Y516476D03*
X1154145Y583339D03*
Y586339D03*
X1146160Y767299D03*
Y771099D03*
X1155282Y766806D03*
X1142203Y1300361D03*
Y1302861D03*
X1144703D03*
Y1300361D03*
X1142203Y1305361D03*
X1144703D03*
X1155503Y1312861D03*
Y1310361D03*
Y1307861D03*
X1142203D03*
Y1310361D03*
Y1312861D03*
X1144703D03*
Y1310361D03*
Y1307861D03*
X1155503Y1302861D03*
Y1300361D03*
Y1305361D03*
Y1315361D03*
X1142203D03*
X1144703D03*
X1142203Y1317861D03*
X1144703D03*
X1155503D03*
X1152359Y1372853D03*
X1154789D03*
X1141901Y1382574D03*
Y1380066D03*
X1149343Y1382111D03*
X1145855Y1380511D03*
X1148593Y1379543D03*
X1142675Y1423488D03*
X1145715Y1423555D03*
X1145755Y1426235D03*
Y1428735D03*
Y1431235D03*
Y1433735D03*
X1142715Y1426168D03*
Y1428668D03*
Y1431168D03*
Y1433668D03*
X1150718Y1462792D03*
X1153724Y1462695D03*
X1154824Y1471134D03*
X1145960Y1491934D03*
X1148460D03*
X1150960D03*
X1153460D03*
X1155960D03*
X1145960Y1489434D03*
X1148460D03*
X1150960D03*
X1153460D03*
X1155960D03*
X1143460D03*
Y1491934D03*
X1153545Y1534952D03*
X1151045D03*
X1148545D03*
X1146045D03*
X1143545D03*
X1153545Y1537452D03*
X1151045D03*
X1148545D03*
X1146045D03*
X1143545D03*
X1151045Y1544952D03*
X1148545D03*
X1146045D03*
X1143545D03*
X1153545D03*
X1143545Y1542452D03*
X1146045D03*
X1148545D03*
X1151045D03*
X1153545D03*
Y1539952D03*
X1151045D03*
X1148545D03*
X1146045D03*
X1143545D03*
X1155253Y1559176D03*
X1147814Y1562823D03*
X1154336Y1555979D03*
X1149467Y1568988D03*
X1142917Y1583314D03*
Y1586714D03*
X1155180Y1655534D03*
X1146501Y1655608D03*
Y1652208D03*
X1158343Y1658514D03*
X1152198Y1669629D03*
X1151985Y1666685D03*
X1151707Y1663655D03*
X1152114Y1672517D03*
X1154500Y1677000D03*
X1142033Y1682412D03*
X1152211Y1682373D03*
X1162086Y76509D03*
X1162144Y487630D03*
X1158764Y489516D03*
X1162067Y570050D03*
X1166131Y580602D03*
X1157038Y583298D03*
Y586298D03*
X1166026Y669006D03*
X1159718Y766870D03*
X1158003Y1307861D03*
Y1310361D03*
Y1312861D03*
Y1300361D03*
Y1302861D03*
Y1305361D03*
X1160503Y1302861D03*
Y1300361D03*
Y1305361D03*
Y1307861D03*
Y1310361D03*
Y1312861D03*
X1158003Y1315361D03*
Y1317861D03*
X1160503D03*
Y1315361D03*
X1168039Y1368999D03*
Y1371540D03*
X1157219Y1372853D03*
X1158059Y1367018D03*
Y1369918D03*
X1164249Y1373158D03*
X1169532Y1379914D03*
X1164249Y1376058D03*
X1159983Y1376288D03*
X1162049Y1374558D03*
X1164249Y1378958D03*
X1159983Y1379188D03*
X1162149Y1377558D03*
X1160163Y1445627D03*
X1163422Y1445000D03*
X1166350Y1454234D03*
X1160750Y1463250D03*
X1164300Y1463300D03*
X1159283Y1471132D03*
X1158460Y1491934D03*
Y1489434D03*
X1170986Y1516590D03*
Y1513190D03*
Y1534990D03*
Y1538390D03*
X1169061Y1543800D03*
X1170061Y1551040D03*
X1163485Y1546195D03*
X1161492Y1551175D03*
X1164528Y1565578D03*
X1170404Y1556331D03*
Y1559731D03*
X1166873Y1561431D03*
X1157255Y1556000D03*
X1170539Y1595621D03*
X1168023Y1586251D03*
X1170539Y1588751D03*
X1168023D03*
X1170539Y1586251D03*
Y1583751D03*
Y1600621D03*
Y1598121D03*
X1170339Y1603121D03*
X1165806Y1658934D03*
X1159688Y1665427D03*
X1169098Y1666278D03*
X1159703Y1673000D03*
X1159500Y1679000D03*
Y1682500D03*
X1177404Y-21711D03*
Y-18311D03*
Y18289D03*
Y21689D03*
X1184194Y57015D03*
Y61515D03*
X1185913Y93634D03*
X1174031Y403519D03*
X1181000Y402500D03*
X1175181Y447841D03*
Y442341D03*
X1185952Y444202D03*
Y436202D03*
X1178340Y447734D03*
Y442234D03*
X1176000Y436500D03*
X1180000Y436000D03*
X1175181Y458841D03*
Y464341D03*
Y453341D03*
X1185952Y452202D03*
X1178340Y458734D03*
X1178254Y453142D03*
X1178340Y461615D03*
X1175181Y469841D03*
X1186040Y481691D03*
X1178340Y467165D03*
X1175181Y481691D03*
X1182950Y577030D03*
X1178000Y572602D03*
X1182594Y587759D03*
X1178000Y592673D03*
X1183811Y640682D03*
X1182256Y632368D03*
X1182713Y733815D03*
X1175860Y767299D03*
Y771099D03*
X1184960Y766870D03*
X1172603Y1302861D03*
Y1300361D03*
Y1305361D03*
Y1307861D03*
Y1310361D03*
Y1312861D03*
X1175103Y1300361D03*
Y1302861D03*
X1177603D03*
Y1300361D03*
X1175103Y1305361D03*
X1177603D03*
X1175103Y1307861D03*
Y1310361D03*
Y1312861D03*
X1177603D03*
Y1310361D03*
Y1307861D03*
X1175103Y1315361D03*
X1177603D03*
X1172603Y1317861D03*
Y1315361D03*
X1175103Y1317861D03*
X1177603D03*
X1185259Y1372853D03*
X1174801Y1382574D03*
Y1380066D03*
X1182243Y1382111D03*
X1178755Y1380511D03*
X1181493Y1379543D03*
X1171812Y1376389D03*
X1184900Y1428500D03*
X1183000Y1422900D03*
X1184175Y1435600D03*
X1176500Y1457071D03*
X1180200Y1457100D03*
X1183924Y1485895D03*
X1180624Y1495595D03*
X1177224D03*
X1178039Y1595621D03*
X1175539D03*
X1173039D03*
X1180923Y1588751D03*
Y1586251D03*
X1173039Y1588751D03*
X1175539D03*
X1178039D03*
Y1586251D03*
X1175539D03*
X1173039D03*
X1178039Y1583751D03*
X1175539D03*
X1173039D03*
X1178039Y1600621D03*
X1175539D03*
X1173039D03*
X1178039Y1598121D03*
X1175539D03*
X1173039D03*
X1175339Y1603121D03*
X1172839D03*
X1177839D03*
X1184362Y1670254D03*
X1181385Y1670312D03*
X1175726Y1686726D03*
X1195488Y93550D03*
X1190587Y99694D03*
X1199756Y128748D03*
X1189727Y164987D03*
Y160987D03*
X1200037Y177187D03*
X1200012Y181187D03*
X1186821Y185430D03*
Y181930D03*
X1195767Y460202D03*
Y470392D03*
Y465272D03*
X1193040Y481691D03*
X1191087Y573809D03*
X1199370Y578154D03*
X1195236Y581407D03*
X1188267Y571807D03*
X1199392Y590500D03*
X1195336Y586606D03*
X1200923Y601734D03*
Y606134D03*
X1199539Y638492D03*
X1197039D03*
X1194539D03*
X1192039D03*
X1195108Y668148D03*
X1198456Y668138D03*
X1190903Y1307861D03*
Y1310361D03*
Y1312861D03*
X1188403D03*
Y1310361D03*
Y1307861D03*
Y1302861D03*
Y1300361D03*
Y1305361D03*
X1190903Y1300361D03*
Y1302861D03*
X1193403D03*
Y1300361D03*
X1190903Y1305361D03*
X1193403D03*
Y1307861D03*
Y1310361D03*
Y1312861D03*
X1190903Y1315361D03*
X1188403D03*
Y1317861D03*
X1190903D03*
X1193403D03*
Y1315361D03*
X1200839Y1368999D03*
Y1371540D03*
X1190119Y1372853D03*
X1191049Y1367188D03*
Y1370088D03*
X1187689Y1372853D03*
X1197149Y1373158D03*
X1192883Y1379188D03*
X1195049Y1377558D03*
X1197149Y1378958D03*
X1192883Y1376288D03*
X1194949Y1374558D03*
X1197149Y1376058D03*
X1194296Y1396500D03*
X1194000Y1401000D03*
Y1414500D03*
X1203242Y1417440D03*
X1194366Y1405500D03*
X1193929Y1410000D03*
X1202548Y1407453D03*
X1202857Y1412454D03*
X1191000Y1425900D03*
X1198800Y1421500D03*
X1202411Y1427410D03*
X1194000Y1424000D03*
X1203117Y1422452D03*
X1202475Y1432468D03*
X1188000Y1419800D03*
X1194000Y1437500D03*
X1203040D03*
X1194000Y1442500D03*
Y1447500D03*
X1187324Y1485895D03*
X1200724Y1505295D03*
X1197324D03*
X1188960Y1609135D03*
X1186455Y1608390D03*
Y1602590D03*
Y1605490D03*
X1190174Y1615418D03*
X1190616Y1670641D03*
X1190314Y1661630D03*
X1199299Y1675517D03*
X1197746Y1680914D03*
X1199272Y1683025D03*
X1189263Y1682551D03*
X1190830Y1675710D03*
X1197612Y1703334D03*
X1192612D03*
X1199612Y1691366D03*
X1189462Y1700334D03*
X1194478Y1699936D03*
X1189407Y1717518D03*
X1205929Y86872D03*
X1206580Y94846D03*
X1208431Y133866D03*
Y128748D03*
X1214094Y258633D03*
Y269008D03*
Y282948D03*
Y287948D03*
X1205625Y313758D03*
X1210698Y313671D03*
X1207447Y341381D03*
X1202508Y341424D03*
X1212700Y475712D03*
X1206590Y481403D03*
X1203269Y481237D03*
X1212051Y559827D03*
X1208733Y585986D03*
X1205900Y582443D03*
X1206191Y588400D03*
X1205679Y594148D03*
X1209796Y668115D03*
X1204334Y668138D03*
X1205630Y766600D03*
X1207903Y1300361D03*
Y1302861D03*
X1210403D03*
Y1300361D03*
X1207903Y1305361D03*
X1210403D03*
X1207903Y1307861D03*
Y1310361D03*
Y1312861D03*
X1210403D03*
Y1310361D03*
Y1307861D03*
X1205403Y1302861D03*
Y1300361D03*
Y1305361D03*
Y1307861D03*
Y1310361D03*
Y1312861D03*
X1207903Y1315361D03*
X1210403D03*
X1205403Y1317861D03*
Y1315361D03*
X1207903Y1317861D03*
X1210403D03*
X1202332Y1379914D03*
X1207601Y1380066D03*
X1215043Y1382111D03*
X1211555Y1380511D03*
X1214293Y1379543D03*
X1207601Y1382574D03*
X1204612Y1376389D03*
X1211000Y1392125D03*
X1211075Y1395200D03*
X1210100Y1436500D03*
X1213000Y1435000D03*
X1210400Y1440000D03*
X1214900Y1439800D03*
X1214124Y1485895D03*
X1210724D03*
X1207424Y1495595D03*
X1204024D03*
X1202697Y1673059D03*
X1205604Y1685400D03*
Y1682200D03*
Y1679000D03*
Y1675800D03*
X1212954Y1703343D03*
X1214954Y1691375D03*
X1204804Y1700343D03*
X1207954Y1703343D03*
X1207770Y1706861D03*
Y1720861D03*
X1205638Y1732766D03*
X1227803Y94210D03*
X1221411Y134230D03*
X1221512Y128239D03*
X1220931Y131307D03*
X1222094Y258633D03*
X1230094D03*
Y269008D03*
X1222094D03*
X1230094Y287948D03*
Y282948D03*
X1222094D03*
Y297066D03*
Y292066D03*
Y314216D03*
Y305216D03*
X1226094Y314216D03*
X1218430Y421012D03*
X1219325Y438151D03*
X1216300Y475682D03*
X1228372Y688501D03*
X1221203Y1312861D03*
Y1310361D03*
Y1307861D03*
X1223703D03*
Y1310361D03*
Y1312861D03*
Y1300361D03*
Y1302861D03*
Y1305361D03*
X1221203Y1302861D03*
Y1300361D03*
Y1305361D03*
Y1315361D03*
X1223703D03*
Y1317861D03*
X1221203D03*
X1222919Y1372853D03*
X1220489D03*
X1223889Y1367188D03*
Y1370088D03*
X1218059Y1372853D03*
X1229949Y1373158D03*
X1228800Y1391300D03*
X1225683Y1379188D03*
X1227849Y1377558D03*
X1225683Y1376288D03*
X1227749Y1374558D03*
X1229949Y1378958D03*
Y1376058D03*
X1227000Y1401300D03*
X1219650Y1392050D03*
X1219500Y1398900D03*
X1224200Y1393500D03*
X1227000Y1404500D03*
X1219500Y1436000D03*
X1221837Y1438800D03*
X1229661Y1442000D03*
X1226200Y1444300D03*
X1222700Y1446300D03*
X1220200Y1449100D03*
X1227524Y1505295D03*
X1224124D03*
X1230824Y1495595D03*
X1219738Y1713861D03*
Y1708861D03*
X1216738Y1717011D03*
X1219738Y1722861D03*
Y1727861D03*
X1216738Y1731011D03*
X1238769Y75320D03*
X1233668Y132739D03*
Y128239D03*
X1247834Y159844D03*
X1238094Y258633D03*
X1246094Y269008D03*
X1238094D03*
X1234000Y385500D03*
X1233468Y419742D03*
X1242429Y431255D03*
Y427255D03*
Y435255D03*
X1236879Y449755D03*
X1242429Y439255D03*
X1232081Y460580D03*
X1242692Y483435D03*
X1236100Y773844D03*
X1233084Y772582D03*
X1235215Y777213D03*
X1231397Y769667D03*
X1243207Y779428D03*
X1241057Y782278D03*
X1244986Y787578D03*
X1244127Y784598D03*
X1238257Y779728D03*
X1243294Y1269197D03*
Y1266697D03*
Y1261697D03*
Y1264197D03*
X1243308Y1271754D03*
X1238830Y1322853D03*
Y1325394D03*
X1240323Y1333768D03*
X1245592Y1333920D03*
Y1336428D03*
X1242603Y1330243D03*
X1239800Y1389500D03*
X1235400Y1391200D03*
X1238500Y1400900D03*
X1234900Y1404400D03*
X1233700Y1395600D03*
X1238200Y1395500D03*
X1244300Y1403500D03*
X1235679Y1418908D03*
X1239242Y1418462D03*
X1238731Y1422362D03*
X1239550Y1437050D03*
X1240924Y1485895D03*
X1237524D03*
X1234224Y1495595D03*
X1245840Y1689D03*
Y-1711D03*
X1249152Y72895D03*
X1253152Y84895D03*
X1255661Y90470D03*
X1253152Y95525D03*
X1259472Y92864D03*
X1252693Y124739D03*
X1249431Y137739D03*
X1249065Y241594D03*
Y236594D03*
Y251594D03*
Y246594D03*
X1246094Y258633D03*
X1254094D03*
X1262094Y269008D03*
X1254094D03*
X1262094Y282948D03*
X1254094D03*
X1262094Y287948D03*
X1250285Y303307D03*
X1259659Y389456D03*
X1260107Y399125D03*
X1260227Y415128D03*
X1256137Y459182D03*
Y453872D03*
X1245752Y470733D03*
X1250975Y474945D03*
X1248130Y783354D03*
X1251177Y784488D03*
X1254981Y787578D03*
X1256447Y798828D03*
X1259297Y798784D03*
X1251177Y794878D03*
X1257527Y808938D03*
X1260427Y809008D03*
X1259194Y1251697D03*
Y1246697D03*
Y1254197D03*
Y1249197D03*
X1248294Y1259197D03*
Y1256697D03*
X1245794Y1259197D03*
X1259194Y1269215D03*
Y1261715D03*
Y1264215D03*
Y1266715D03*
X1245894Y1269215D03*
X1248394D03*
X1245894Y1261715D03*
Y1264215D03*
Y1266715D03*
X1248394D03*
Y1264215D03*
Y1261715D03*
X1259194Y1256697D03*
Y1259197D03*
X1248308Y1271754D03*
X1245808D03*
X1259108D03*
X1256050Y1326707D03*
X1258480D03*
X1253034Y1335965D03*
X1249546Y1334365D03*
X1252284Y1333397D03*
X1249600Y1403425D03*
X1257594Y1417000D03*
X1253100Y1413500D03*
X1256224Y1430075D03*
X1256600Y1434500D03*
X1254324Y1505295D03*
X1250924D03*
X1257624Y1495595D03*
X1275981Y85114D03*
X1263472Y92864D03*
X1269146Y121022D03*
X1263146D03*
X1267037Y180565D03*
Y175030D03*
X1268941Y206017D03*
X1269360Y219632D03*
X1261969Y219505D03*
X1262094Y258633D03*
X1270094D03*
Y269008D03*
Y282948D03*
Y292066D03*
X1268174Y395125D03*
X1275585Y393597D03*
X1269840Y411128D03*
X1270483Y433148D03*
Y435648D03*
X1265227Y454372D03*
X1262457Y798814D03*
X1266677Y802988D03*
X1266568Y809078D03*
X1275177Y808963D03*
X1263647Y809118D03*
X1271177Y808963D03*
X1261694Y1251697D03*
X1264194D03*
Y1246697D03*
X1261694D03*
Y1254197D03*
X1264194D03*
X1261694Y1249197D03*
X1264194D03*
X1261694Y1269215D03*
Y1266715D03*
Y1264215D03*
Y1261715D03*
X1264194Y1269197D03*
Y1256697D03*
Y1259197D03*
Y1261697D03*
X1261694Y1256697D03*
Y1259197D03*
X1264194Y1264197D03*
Y1266697D03*
X1264108Y1271754D03*
X1261608D03*
X1271726Y1322825D03*
Y1325366D03*
X1260910Y1326707D03*
X1262050Y1320878D03*
Y1323778D03*
X1267940Y1327012D03*
X1265740Y1328412D03*
X1273219Y1333740D03*
X1275499Y1330215D03*
X1267940Y1332812D03*
Y1329912D03*
X1265840Y1331412D03*
X1263674Y1330142D03*
Y1333042D03*
X1271042Y1418748D03*
X1266996Y1423617D03*
X1262310Y1428303D03*
X1267724Y1485895D03*
X1264324D03*
X1261024Y1495595D03*
X1275195Y1552250D03*
X1275170Y1579519D03*
X1269310Y1583170D03*
X1287486Y134165D03*
X1278050Y152912D03*
X1278137Y166051D03*
X1278211Y161030D03*
Y156030D03*
X1278137Y180565D03*
Y176051D03*
Y171551D03*
Y184987D03*
X1279447Y213292D03*
X1286094Y258633D03*
X1278094D03*
Y269008D03*
X1286094D03*
X1278094Y282948D03*
X1286094D03*
X1278094Y287948D03*
X1286094Y292066D03*
X1290127Y401125D03*
Y410635D03*
X1289352Y418550D03*
Y421950D03*
X1281190Y1254112D03*
X1276190D03*
X1278690D03*
X1281190Y1249112D03*
Y1251612D03*
X1276190D03*
X1278690D03*
X1276190Y1249112D03*
X1278690D03*
X1281190Y1246612D03*
X1276190D03*
X1278690D03*
X1276190Y1269112D03*
Y1266612D03*
X1281190Y1259112D03*
Y1256612D03*
X1276190D03*
Y1259112D03*
Y1261612D03*
Y1264112D03*
X1278690Y1256612D03*
Y1259112D03*
X1278790Y1269130D03*
X1281290D03*
X1278790Y1261630D03*
Y1264130D03*
Y1266630D03*
X1281290D03*
Y1264130D03*
Y1261630D03*
X1281204Y1271669D03*
X1278704D03*
X1276204D03*
X1288946Y1326679D03*
X1278488Y1333892D03*
X1285930Y1335937D03*
X1282442Y1334337D03*
X1285180Y1333369D03*
X1278488Y1336400D03*
X1287600Y1423100D03*
Y1427600D03*
X1276500Y1432000D03*
X1279525D03*
X1287700Y1431700D03*
X1277724Y1485895D03*
X1281124D03*
X1288494Y1517082D03*
Y1513682D03*
Y1530482D03*
Y1527082D03*
X1287961Y1542469D03*
X1287372Y1552845D03*
X1287647Y1545220D03*
Y1549120D03*
X1277017Y1544953D03*
Y1547453D03*
Y1549953D03*
X1281470Y1552845D03*
X1281347Y1549120D03*
Y1545220D03*
X1284497Y1549120D03*
Y1545220D03*
X1284510Y1554436D03*
X1277702D03*
X1289919Y1582295D03*
Y1574795D03*
Y1579795D03*
Y1577295D03*
X1287419Y1582295D03*
Y1579795D03*
X1284919D03*
Y1582295D03*
X1282419D03*
Y1579795D03*
X1299196Y76209D03*
X1305685Y74748D03*
X1296200Y66911D03*
X1305091Y123680D03*
Y127830D03*
Y131750D03*
X1301582Y166051D03*
X1301743Y162055D03*
X1301582Y171551D03*
Y184051D03*
X1302094Y258633D03*
X1294094D03*
Y269008D03*
X1302094D03*
X1294094Y287948D03*
Y282948D03*
X1302094D03*
Y292066D03*
X1302069Y303184D03*
X1299026Y389355D03*
X1302226D03*
X1295519Y389561D03*
X1304347Y523237D03*
X1302160Y524916D03*
X1304566Y525743D03*
X1301642Y537299D03*
X1293581Y542716D03*
X1294938Y561331D03*
X1300400Y599413D03*
X1297400D03*
X1298000Y657500D03*
X1303250Y655149D03*
X1295000Y655200D03*
X1292297Y657206D03*
X1302500Y664500D03*
X1305100Y662100D03*
X1301900Y660699D03*
X1294590Y1254112D03*
X1297090D03*
X1292090D03*
Y1249112D03*
X1294590D03*
X1297090D03*
X1292090Y1251612D03*
X1294590D03*
X1297090D03*
X1292090Y1246612D03*
X1297090D03*
X1294590D03*
X1292090Y1269130D03*
X1294590D03*
X1292090Y1261630D03*
Y1264130D03*
Y1266630D03*
X1294590D03*
Y1264130D03*
Y1261630D03*
X1297090Y1269112D03*
Y1256612D03*
Y1259112D03*
Y1261612D03*
X1294590Y1256612D03*
Y1259112D03*
X1297090Y1264112D03*
Y1266612D03*
X1292090Y1256612D03*
Y1259112D03*
X1297004Y1271669D03*
X1292004D03*
X1294504D03*
X1304630Y1322768D03*
Y1325309D03*
X1293806Y1326679D03*
X1291376D03*
X1294956Y1320934D03*
Y1323834D03*
X1300836Y1326984D03*
X1298636Y1328384D03*
X1296570Y1330114D03*
Y1333014D03*
X1298736Y1331384D03*
X1300836Y1329884D03*
Y1332784D03*
X1296000Y1427700D03*
X1301900D03*
X1295700Y1421800D03*
X1300800D03*
X1291700Y1431700D03*
X1305286Y1495595D03*
X1299048Y1516590D03*
Y1513190D03*
Y1534990D03*
X1302390Y1530430D03*
X1297490Y1526910D03*
X1297620Y1529534D03*
X1299048Y1538390D03*
X1291897Y1545076D03*
X1290461Y1542469D03*
X1291897Y1547576D03*
X1302915Y1563596D03*
X1298466Y1556331D03*
Y1559731D03*
X1292419Y1582295D03*
Y1579795D03*
Y1574795D03*
Y1577295D03*
X1294919D03*
Y1574795D03*
X1294387Y1571682D03*
X1291887D03*
X1301789Y1574795D03*
X1304289D03*
X1301789Y1577295D03*
X1304289D03*
Y1579795D03*
X1301789D03*
X1304289Y1582295D03*
X1301789D03*
X1299289Y1574795D03*
Y1582295D03*
Y1579795D03*
Y1577295D03*
X1295877Y1581199D03*
X1298382Y1584844D03*
X1295877Y1584099D03*
X1293459Y1584844D03*
X1320020Y66979D03*
X1308110Y66911D03*
X1307857Y103353D03*
X1313951Y104739D03*
X1311045D03*
X1313011Y135820D03*
Y139845D03*
X1306300Y203917D03*
X1318094Y258633D03*
X1310094D03*
Y269008D03*
X1318094D03*
X1310094Y287948D03*
Y282948D03*
X1318094D03*
X1305426Y389355D03*
X1308926Y524111D03*
X1306815Y522726D03*
X1307117Y525897D03*
X1309870Y552788D03*
X1309776Y559831D03*
X1317266Y597213D03*
X1310544Y613100D03*
X1313544Y610100D03*
X1310544D03*
X1313544Y607100D03*
X1310544D03*
X1313544Y604100D03*
X1310544D03*
X1307544Y610100D03*
Y613100D03*
Y604100D03*
Y607100D03*
X1317266Y600213D03*
X1309166Y601713D03*
X1308776Y599181D03*
X1313544Y613100D03*
X1310544Y616100D03*
X1313544D03*
X1307544D03*
X1308800Y619200D03*
Y622200D03*
Y625200D03*
X1318300D03*
Y622200D03*
Y619200D03*
X1307700Y664600D03*
X1309600Y667700D03*
X1315657Y1199532D03*
Y1196132D03*
X1311715Y1221042D03*
X1318776Y1219566D03*
X1311594Y1251612D03*
X1309094D03*
X1311594Y1254112D03*
X1309094D03*
X1311594Y1246612D03*
X1309094D03*
X1311594Y1249112D03*
X1309094D03*
X1314094Y1246612D03*
Y1251612D03*
Y1249112D03*
Y1254112D03*
X1309090Y1269169D03*
Y1266669D03*
Y1261669D03*
Y1264169D03*
X1314194Y1269130D03*
Y1266630D03*
Y1264130D03*
Y1261630D03*
X1311694Y1269130D03*
Y1261630D03*
Y1264130D03*
Y1266630D03*
X1311594Y1259112D03*
Y1256612D03*
X1309094Y1259112D03*
Y1256612D03*
X1314094D03*
Y1259112D03*
X1309090Y1271669D03*
X1311590D03*
X1314090D03*
X1306123Y1333683D03*
X1311392Y1333835D03*
X1318834Y1335880D03*
X1315346Y1334280D03*
X1318084Y1333312D03*
X1311392Y1336343D03*
X1308403Y1330158D03*
X1315386Y1485895D03*
X1311986D03*
X1308686Y1495595D03*
X1308900Y1525510D03*
X1306789Y1574795D03*
Y1582295D03*
Y1579795D03*
Y1577295D03*
X1310914Y1577299D03*
X1331930Y66945D03*
X1327541Y105227D03*
X1337399Y98084D03*
X1333399D03*
X1334094Y258633D03*
X1326094D03*
Y269008D03*
X1334094D03*
Y287948D03*
X1326094Y282948D03*
X1334094D03*
X1326094Y292066D03*
X1328427Y349452D03*
X1329585Y561806D03*
X1325366Y597213D03*
Y600213D03*
X1321300Y619200D03*
Y622200D03*
Y625200D03*
X1326636Y656800D03*
X1322420Y656867D03*
X1332812Y856383D03*
X1325543Y871161D03*
X1329244D03*
X1334301Y867765D03*
X1328992Y1209788D03*
X1327029Y1206788D03*
X1331202Y1206478D03*
X1323169Y1208995D03*
X1333977Y1222158D03*
X1325137Y1210653D03*
X1324901Y1216419D03*
X1322141Y1217365D03*
X1327494Y1246612D03*
Y1251612D03*
Y1249112D03*
Y1254112D03*
X1324994Y1246612D03*
Y1251612D03*
Y1249112D03*
Y1254112D03*
X1329994Y1246612D03*
Y1251612D03*
Y1249112D03*
Y1254112D03*
X1324994Y1269130D03*
Y1261630D03*
Y1264130D03*
Y1266630D03*
X1327494Y1269130D03*
Y1266630D03*
Y1264130D03*
Y1261630D03*
Y1259112D03*
Y1256612D03*
X1324994Y1259112D03*
Y1256612D03*
X1329994Y1259112D03*
Y1256612D03*
Y1266612D03*
Y1264112D03*
Y1261612D03*
Y1269112D03*
X1327490Y1271669D03*
X1324990D03*
X1329990D03*
X1326710Y1326622D03*
X1324280D03*
X1321850D03*
X1327876Y1320934D03*
Y1323834D03*
X1333740Y1326927D03*
X1331540Y1328327D03*
X1333740Y1329827D03*
Y1332727D03*
X1331640Y1331327D03*
X1329474Y1330057D03*
Y1332957D03*
X1322539Y1411278D03*
X1322499Y1413788D03*
X1325499D03*
X1325539Y1411278D03*
Y1416446D03*
X1322539D03*
X1328539Y1411278D03*
X1328499Y1413788D03*
X1328539Y1416446D03*
X1331509Y1416486D03*
X1334509D03*
X1331509Y1408818D03*
X1334509Y1411318D03*
X1334469Y1413828D03*
X1334509Y1408818D03*
X1331469Y1413828D03*
X1331509Y1411318D03*
X1325579Y1418976D03*
X1322579D03*
X1325609Y1421496D03*
X1322609D03*
X1328579Y1418976D03*
X1328609Y1421496D03*
X1331579Y1421536D03*
X1331549Y1419016D03*
X1334579Y1421536D03*
X1334549Y1419016D03*
X1328786Y1505295D03*
X1325386D03*
X1332086Y1495595D03*
X1343840Y66911D03*
X1341399Y98084D03*
X1348199D03*
X1342094Y258633D03*
Y269008D03*
X1350094D03*
Y287948D03*
X1342094Y282948D03*
X1350094D03*
X1342094Y292066D03*
X1340257Y677765D03*
Y675111D03*
X1336812Y856383D03*
X1341301Y867765D03*
X1337801D03*
X1341301Y871265D03*
X1344801D03*
X1348301D03*
X1340948Y1177681D03*
X1342507Y1187848D03*
X1340948Y1181681D03*
X1349012Y1204971D03*
X1342036Y1206429D03*
Y1203029D03*
X1346063Y1217729D03*
Y1214329D03*
X1341590Y1254169D03*
Y1251669D03*
Y1249169D03*
Y1246669D03*
X1344090Y1254169D03*
Y1251669D03*
Y1249169D03*
Y1246669D03*
X1346590Y1254169D03*
Y1249169D03*
Y1251669D03*
Y1246669D03*
X1341690Y1269269D03*
Y1264269D03*
Y1266769D03*
Y1261769D03*
X1341590Y1256669D03*
Y1259169D03*
X1344190Y1269187D03*
X1346690D03*
X1344190Y1261687D03*
Y1264187D03*
Y1266687D03*
X1346690D03*
Y1264187D03*
Y1261687D03*
X1344090Y1256669D03*
Y1259169D03*
X1346590D03*
Y1256669D03*
X1341690Y1271769D03*
X1346690D03*
X1344190D03*
X1337430Y1322968D03*
Y1325509D03*
X1338923Y1333883D03*
X1344192Y1334035D03*
X1348146Y1334480D03*
X1344192Y1336543D03*
X1341203Y1330358D03*
X1340556Y1383674D03*
Y1386674D03*
X1337556D03*
Y1383674D03*
X1346556Y1386674D03*
Y1383674D03*
X1343556Y1386674D03*
Y1383674D03*
X1349556D03*
Y1386674D03*
X1337555Y1389658D03*
X1343712Y1389804D03*
X1348712D03*
X1346212D03*
X1341212D03*
X1348823Y1409626D03*
X1348853Y1413866D03*
X1346323Y1409626D03*
X1346353Y1413866D03*
X1343823Y1409626D03*
X1343853Y1413866D03*
X1346509Y1416486D03*
X1349509D03*
X1343509D03*
X1341323Y1409626D03*
X1341353Y1413866D03*
X1337509Y1416486D03*
Y1411318D03*
X1337469Y1413828D03*
X1337509Y1408818D03*
X1340509Y1416486D03*
X1349579Y1421536D03*
X1349549Y1419016D03*
X1346579Y1421536D03*
X1346549Y1419016D03*
X1343549D03*
X1343579Y1421536D03*
X1337579D03*
X1337549Y1419016D03*
X1340579Y1421536D03*
X1340549Y1419016D03*
X1342186Y1485895D03*
X1338786D03*
X1335486Y1495595D03*
X1355750Y66886D03*
X1360109Y98050D03*
X1352199D03*
X1364369Y120380D03*
X1358094Y258633D03*
X1350094D03*
X1358094Y269008D03*
X1366094D03*
Y287948D03*
X1358094Y282948D03*
X1366094D03*
X1358094Y292066D03*
X1363857Y626579D03*
X1361427D03*
X1354397Y623374D03*
Y626274D03*
X1356597Y624874D03*
X1358663Y623144D03*
X1356497Y621874D03*
X1354397Y620474D03*
X1358663Y620244D03*
X1360964Y629514D03*
Y632414D03*
X1358461Y684151D03*
Y686651D03*
X1360961Y684073D03*
Y686573D03*
X1363461D03*
Y684073D03*
X1363435Y681573D03*
X1358435D03*
X1360935D03*
X1358461Y694151D03*
X1363461D03*
X1360961D03*
X1358461Y689151D03*
Y691651D03*
X1363461Y696651D03*
X1360961D03*
X1363461Y699151D03*
X1360961Y691573D03*
X1363461D03*
X1360961Y689073D03*
X1363461D03*
X1362523Y1015473D03*
Y1022559D03*
Y1019016D03*
X1355222Y1200561D03*
X1361285Y1206718D03*
X1355641Y1210674D03*
X1362810Y1211071D03*
X1357490Y1254169D03*
Y1249169D03*
Y1251669D03*
Y1246669D03*
X1359990Y1254169D03*
X1362490D03*
X1359990Y1249169D03*
X1362490D03*
X1359990Y1251669D03*
X1362490D03*
Y1246669D03*
X1359990D03*
Y1269187D03*
Y1266687D03*
Y1264187D03*
Y1261687D03*
X1357490Y1269187D03*
Y1261687D03*
Y1264187D03*
Y1266687D03*
Y1256669D03*
Y1259169D03*
X1362490Y1269269D03*
Y1261769D03*
Y1266769D03*
Y1264269D03*
Y1256669D03*
Y1259169D03*
X1359990Y1256669D03*
Y1259169D03*
X1357490Y1271769D03*
X1362490D03*
X1359990D03*
X1359510Y1326822D03*
X1360724Y1321184D03*
Y1324084D03*
X1357080Y1326822D03*
X1354650D03*
X1364340Y1328527D03*
X1351634Y1336080D03*
X1350884Y1333512D03*
X1364440Y1337527D03*
Y1331527D03*
Y1334527D03*
X1362274Y1330257D03*
Y1333157D03*
Y1336057D03*
X1352226Y1386804D03*
Y1383804D03*
X1352225Y1389788D03*
X1358509Y1416486D03*
Y1413818D03*
Y1411318D03*
Y1408818D03*
X1352509Y1416486D03*
Y1411318D03*
Y1413818D03*
Y1408818D03*
X1355509Y1416486D03*
Y1411318D03*
Y1413818D03*
Y1408818D03*
X1352579Y1421536D03*
X1352549Y1419016D03*
X1355549D03*
X1355586Y1505295D03*
X1362286Y1495595D03*
X1352186Y1505295D03*
X1358886Y1495595D03*
X1367950Y66886D03*
X1377682Y87587D03*
X1368109Y98000D03*
X1366094Y258633D03*
X1373862Y485552D03*
Y511052D03*
X1381457Y511050D03*
X1376757Y619497D03*
X1369303Y617321D03*
X1372791Y618921D03*
X1370053Y619889D03*
X1376745Y616858D03*
X1379734Y623043D03*
X1366287Y626579D03*
X1376761Y686573D03*
Y684073D03*
X1374261D03*
Y686573D03*
X1374245Y681573D03*
X1376745D03*
X1376761Y694151D03*
X1374261D03*
X1376761Y696651D03*
X1374261D03*
X1376761Y699151D03*
X1374261D03*
X1376761Y701651D03*
X1374261D03*
X1376761Y691573D03*
Y689073D03*
X1374261Y691573D03*
Y689073D03*
X1376761Y706651D03*
Y704151D03*
X1374261Y706651D03*
Y704151D03*
X1377483Y1015473D03*
X1370003D03*
X1377483Y1022559D03*
Y1019016D03*
X1370003Y1022559D03*
Y1019016D03*
X1370685Y1223032D03*
Y1226432D03*
X1374476Y1266143D03*
X1376976D03*
X1379476D03*
X1374476Y1268643D03*
X1376976D03*
X1379476D03*
X1374476Y1273643D03*
Y1271143D03*
X1374576Y1283743D03*
Y1281243D03*
X1374476Y1276143D03*
Y1278643D03*
X1376976Y1273643D03*
Y1271143D03*
X1379476Y1273643D03*
Y1271143D03*
X1377076Y1281161D03*
Y1283661D03*
X1379576D03*
Y1281161D03*
X1376976Y1276143D03*
Y1278643D03*
X1379476D03*
Y1276143D03*
X1379576Y1288661D03*
X1377076Y1286161D03*
X1379576D03*
X1377076Y1288661D03*
X1379576Y1291243D03*
X1377076D03*
X1374576Y1288743D03*
Y1286243D03*
Y1291243D03*
X1370012Y1342299D03*
X1371505Y1353214D03*
X1376774Y1353366D03*
X1370012Y1344840D03*
X1376774Y1355874D03*
X1373785Y1349689D03*
X1368986Y1485895D03*
X1365586D03*
X1378986Y1505295D03*
X1382045Y1700038D03*
X1379804Y1733118D03*
X1383715Y236594D03*
Y241594D03*
X1381457Y485550D03*
X1382014Y619518D03*
X1383507Y627892D03*
Y630433D03*
X1387097Y656274D03*
X1389297Y657774D03*
X1391363Y656044D03*
X1387097Y653374D03*
X1389197Y654774D03*
X1391363Y653144D03*
X1394127Y659479D03*
X1387097Y659174D03*
X1393664Y662384D03*
Y665284D03*
X1393343Y716971D03*
X1390807Y717053D03*
X1390817Y714471D03*
X1393317D03*
X1393343Y719471D03*
X1390807Y719553D03*
X1393367Y727023D03*
Y729523D03*
X1393343Y724471D03*
Y721971D03*
X1390807Y722053D03*
Y724553D03*
X1390853Y727053D03*
X1391460Y1009764D03*
Y1006024D03*
Y1013504D03*
Y1020985D03*
Y1024725D03*
Y1028465D03*
Y1017244D03*
X1390376Y1268643D03*
X1392876D03*
Y1283661D03*
Y1281161D03*
X1390376D03*
Y1283661D03*
Y1273643D03*
Y1271143D03*
Y1276143D03*
Y1278643D03*
X1392876Y1273643D03*
Y1271143D03*
Y1276143D03*
Y1278643D03*
Y1288661D03*
Y1286161D03*
X1390376Y1288661D03*
Y1286161D03*
Y1291243D03*
X1392876D03*
X1393306Y1340515D03*
Y1343415D03*
X1384216Y1355411D03*
X1380728Y1353811D03*
X1383466Y1352843D03*
X1392092Y1346153D03*
X1389662D03*
X1387232D03*
X1392386Y1485895D03*
X1382386Y1505295D03*
X1389086Y1495595D03*
X1385686D03*
X1385068Y1664907D03*
X1390738Y1664938D03*
X1392068Y1676875D03*
X1381918D03*
X1391750Y1697747D03*
X1382045Y1704038D03*
X1390045Y1712038D03*
X1390179Y1733118D03*
X1404917Y116911D03*
X1395302Y251136D03*
Y256136D03*
X1411000Y460362D03*
X1406500Y458362D03*
X1400500Y458377D03*
X1409445Y652266D03*
X1402003Y650221D03*
X1405491Y651821D03*
X1402753Y652789D03*
X1409445Y649758D03*
X1398987Y659479D03*
X1396557D03*
X1409143Y716971D03*
X1395843D03*
X1406643D03*
X1409127Y714471D03*
X1395817D03*
X1406627D03*
X1409143Y719471D03*
X1395843D03*
X1406643D03*
X1395867Y732023D03*
Y727023D03*
Y729523D03*
X1406667Y727023D03*
X1409167Y732023D03*
Y729523D03*
X1406667Y732023D03*
Y729523D03*
X1409167Y727023D03*
X1409143Y724471D03*
Y721971D03*
X1395843Y724471D03*
Y721971D03*
X1406643Y724471D03*
Y721971D03*
X1409167Y739523D03*
Y734523D03*
Y737023D03*
X1406667Y734523D03*
Y737023D03*
Y739523D03*
X1401015Y1014744D03*
X1399953Y1005799D03*
X1403693D03*
X1407433D03*
X1401015Y1023012D03*
Y1018878D03*
X1407433Y1032430D03*
X1403693D03*
X1395060Y1032205D03*
X1399953Y1032430D03*
X1395376Y1268643D03*
Y1273643D03*
Y1271143D03*
Y1281243D03*
Y1283743D03*
Y1276143D03*
Y1278643D03*
Y1288743D03*
Y1286243D03*
Y1291243D03*
X1399122Y1352258D03*
X1394856Y1352488D03*
X1399122Y1346458D03*
Y1349358D03*
X1396922Y1347858D03*
X1394856Y1349588D03*
X1397022Y1350858D03*
X1405811Y1430021D03*
X1395786Y1485895D03*
X1409186D03*
X1405786D03*
X1409532Y1552845D03*
X1409409Y1549120D03*
Y1545220D03*
X1403257Y1552250D03*
X1405079Y1549953D03*
Y1544953D03*
Y1547453D03*
X1405764Y1554436D03*
X1403232Y1579519D03*
X1397030Y1594060D03*
X1409286Y1605796D03*
X1406666Y1616332D03*
X1400029Y1615796D03*
X1406447Y1619572D03*
X1396783Y1617170D03*
X1408023Y1638705D03*
X1398058Y1628651D03*
X1408208D03*
X1406814Y1652439D03*
X1399599Y1657583D03*
X1398883Y1680341D03*
X1410750Y244583D03*
X1417000Y460362D03*
X1419335Y533958D03*
X1414714Y653008D03*
X1412434Y655943D03*
X1416207Y663333D03*
Y660792D03*
X1421797Y687354D03*
X1423963Y685724D03*
X1419697Y685954D03*
X1421897Y690354D03*
X1423963Y688624D03*
X1419697Y688854D03*
Y691754D03*
X1423417Y747051D03*
X1423407Y757133D03*
Y749633D03*
Y752133D03*
Y754633D03*
X1416301Y970340D03*
Y977840D03*
Y985340D03*
X1414576Y989765D03*
X1414501Y993765D03*
Y997765D03*
X1410858Y1014744D03*
X1418653Y1005799D03*
X1414913D03*
X1411173D03*
X1414501Y1001765D03*
X1419716Y1014744D03*
X1422394Y1005799D03*
X1410858Y1023012D03*
X1419716D03*
X1410858Y1018878D03*
X1419716D03*
X1422394Y1032430D03*
X1419026Y1038765D03*
Y1042765D03*
X1414913Y1032430D03*
X1418653D03*
X1411173D03*
X1417301Y1051540D03*
X1418982Y1175144D03*
X1414165Y1289564D03*
X1414172Y1286188D03*
X1416556Y1513682D03*
Y1517082D03*
Y1530482D03*
Y1527082D03*
X1415434Y1552845D03*
X1415709Y1545220D03*
Y1549120D03*
X1418523Y1542469D03*
X1419959Y1545076D03*
Y1547576D03*
X1416023Y1542469D03*
X1412559Y1549120D03*
Y1545220D03*
X1412572Y1554436D03*
X1417981Y1568680D03*
X1423531Y1574795D03*
Y1582295D03*
Y1579795D03*
Y1577295D03*
X1424621Y1571911D03*
Y1569411D03*
X1416862Y1582871D03*
X1419811Y1599084D03*
X1416709Y1592819D03*
X1413836Y1586944D03*
X1412467Y1602234D03*
X1419914Y1602777D03*
X1418000Y1607500D03*
X1422154Y1626270D03*
X1423722Y1616780D03*
X1419622Y1616000D03*
X1422266Y1628947D03*
X1411113Y1637767D03*
X1421890Y1635500D03*
X1418755Y1654999D03*
X1410315Y1646967D03*
X1424315D03*
X1436263Y1689D03*
Y-1711D03*
X1434262Y52892D03*
X1438262D03*
X1431262Y61392D03*
X1439049Y107443D03*
X1429169Y107313D03*
X1431300Y538800D03*
X1435400Y536200D03*
X1431400Y533400D03*
X1435400Y530800D03*
X1434603Y682801D03*
X1438091Y684401D03*
X1435353Y685369D03*
X1431617Y692359D03*
X1429187D03*
X1426757D03*
X1426264Y694954D03*
Y697854D03*
X1439227Y747051D03*
X1425917D03*
X1428417D03*
X1428407Y762133D03*
Y759633D03*
X1425907D03*
X1439257Y762133D03*
Y759633D03*
X1425943Y757051D03*
X1428443D03*
X1425943Y749551D03*
Y752051D03*
Y754551D03*
X1428443D03*
Y752051D03*
Y749551D03*
X1439243Y757051D03*
Y749551D03*
Y752051D03*
Y754551D03*
X1439257Y764633D03*
Y769633D03*
Y767133D03*
X1429952Y1014744D03*
X1433614Y1005799D03*
X1426134D03*
X1429874D03*
X1429952Y1023012D03*
Y1018878D03*
X1426134Y1032430D03*
X1433614D03*
X1429874D03*
X1435160Y1516590D03*
Y1513190D03*
Y1534990D03*
Y1538390D03*
X1434235Y1550240D03*
X1433235Y1543800D03*
X1430735D03*
X1431735Y1550240D03*
X1434578Y1556331D03*
Y1559731D03*
X1430213Y1553652D03*
X1427713D03*
X1426031Y1582295D03*
X1431031Y1574795D03*
Y1577295D03*
X1426031Y1579795D03*
Y1577295D03*
Y1574795D03*
X1428531D03*
Y1577295D03*
Y1579795D03*
Y1582295D03*
X1430431Y1570595D03*
X1427931D03*
X1437901Y1579795D03*
Y1577295D03*
Y1574795D03*
Y1582295D03*
X1435401D03*
Y1579795D03*
Y1577295D03*
Y1574795D03*
X1431989Y1581199D03*
X1434494Y1584844D03*
X1431989Y1584099D03*
X1429571Y1584844D03*
X1430244Y1609966D03*
X1438565Y1612583D03*
X1434316Y1616909D03*
X1430238Y1617137D03*
X1437594Y1616845D03*
X1426899Y1616990D03*
X1429072Y1643655D03*
X1433911Y1649037D03*
X1433618Y1659331D03*
X1433157Y1651977D03*
X1436311Y1665948D03*
X1438078Y1669992D03*
X1439316Y1675080D03*
X1435904Y1694335D03*
X1443049Y107443D03*
X1448549Y114643D03*
X1446040Y120218D03*
X1452040Y113018D03*
X1440871Y152166D03*
X1454769Y163842D03*
X1444769D03*
Y174217D03*
X1453974Y174414D03*
X1449769Y174217D03*
X1439769D03*
Y182217D03*
X1449769D03*
X1456500Y457000D03*
X1441053Y560535D03*
X1441898Y576755D03*
X1452708Y610954D03*
Y607954D03*
X1449708Y610954D03*
X1446708D03*
Y607954D03*
X1449708D03*
X1440708Y610954D03*
X1443708D03*
X1440708Y607954D03*
X1443708D03*
X1452708Y613954D03*
X1446708Y616954D03*
Y619954D03*
X1440708D03*
Y616954D03*
X1443708D03*
Y619954D03*
X1449708Y613954D03*
X1446708D03*
X1440708D03*
X1443708D03*
X1446708Y622954D03*
X1440708D03*
X1443708D03*
X1452938Y617364D03*
X1450438D03*
X1452898Y621844D03*
X1450398D03*
X1448996Y645270D03*
Y647770D03*
X1451496Y645270D03*
X1453996D03*
Y647770D03*
X1451496D03*
X1449046Y650370D03*
X1454046D03*
X1451546D03*
X1446426D03*
X1443926D03*
X1443876Y645270D03*
Y647770D03*
X1446376Y645270D03*
Y647770D03*
X1447314Y684998D03*
X1442091Y684846D03*
X1442045Y682338D03*
X1448807Y695913D03*
Y693372D03*
X1445034Y688523D03*
X1452615Y705531D03*
X1441727Y747051D03*
X1444257Y757133D03*
Y759633D03*
Y762133D03*
X1441757Y759633D03*
Y762133D03*
X1441743Y757051D03*
Y754551D03*
Y752051D03*
Y749551D03*
X1444257Y772133D03*
Y764633D03*
Y769633D03*
Y767133D03*
X1441757Y772133D03*
Y764633D03*
Y769633D03*
Y767133D03*
X1442107Y1013504D03*
Y1009764D03*
Y1006024D03*
Y1020985D03*
Y1024725D03*
Y1028465D03*
Y1017244D03*
Y1032205D03*
X1451498Y1485895D03*
X1448098D03*
X1444798Y1495595D03*
X1441398D03*
X1439850Y1541470D03*
X1440401Y1574795D03*
Y1582295D03*
Y1579795D03*
Y1577295D03*
X1442901Y1582295D03*
Y1579795D03*
Y1577295D03*
Y1574795D03*
X1447026Y1577299D03*
X1448061Y1593055D03*
X1451000Y1601000D03*
X1446000Y1600500D03*
X1450500Y1614500D03*
Y1624000D03*
X1445500Y1614500D03*
X1441000D03*
X1440027Y1667945D03*
X1455579Y1665701D03*
X1453553Y1686892D03*
X1445079Y1686678D03*
X1449070Y1686722D03*
X1448000Y1676000D03*
X1464830Y59054D03*
X1466681Y78590D03*
X1454549Y107443D03*
X1455667Y125733D03*
X1463017Y139518D03*
X1456226Y152166D03*
X1462682Y450372D03*
X1456982Y437362D03*
X1466609Y458608D03*
X1465395Y487582D03*
X1465832Y530656D03*
X1463647Y544977D03*
X1464257Y560977D03*
Y557498D03*
X1462497Y555021D03*
X1464257Y568977D03*
Y572977D03*
Y580977D03*
Y576977D03*
X1467708Y610954D03*
Y607954D03*
X1464708Y610954D03*
Y607954D03*
X1458708Y610954D03*
X1455708D03*
X1461708D03*
Y607954D03*
X1455708D03*
X1458708D03*
X1467708Y616954D03*
Y619954D03*
Y613954D03*
X1461708Y616954D03*
Y619954D03*
X1464708Y616954D03*
Y619954D03*
Y613954D03*
X1458708D03*
X1455708D03*
X1461708D03*
X1467708Y622954D03*
X1461708D03*
X1464708D03*
X1455438Y617364D03*
X1457938D03*
X1455398Y621844D03*
X1457898D03*
X1456496Y645270D03*
X1459396D03*
X1456496Y647770D03*
X1459396D03*
X1456546Y650370D03*
X1459446D03*
X1467521Y702378D03*
X1454715Y700931D03*
X1468271Y704946D03*
X1462045Y711826D03*
X1464475D03*
X1459615D03*
X1456881Y708201D03*
Y705301D03*
X1454715Y706931D03*
Y703931D03*
X1454815Y709931D03*
X1458777Y714194D03*
Y717094D03*
X1456335Y771710D03*
Y766628D03*
X1458861Y776628D03*
X1461361D03*
X1458861Y769128D03*
Y771628D03*
Y774128D03*
X1461361D03*
Y771628D03*
Y769128D03*
X1461335Y766628D03*
X1458835D03*
X1456335Y776710D03*
Y774210D03*
Y769210D03*
X1461371Y791696D03*
Y789196D03*
X1458871Y779196D03*
X1461371D03*
X1458871Y784196D03*
Y781696D03*
Y786696D03*
X1461371Y784196D03*
Y786696D03*
Y781696D03*
X1456371Y779210D03*
Y781710D03*
Y784210D03*
X1456945Y1015473D03*
X1464526D03*
X1456945Y1019016D03*
Y1022559D03*
X1464526Y1019016D03*
Y1022559D03*
X1464898Y1505295D03*
X1461498D03*
X1468198Y1495595D03*
X1468102Y1670817D03*
X1458795Y1687083D03*
X1457940Y1675710D03*
X1463038Y1687060D03*
X1466111Y1685098D03*
X1472129Y56083D03*
X1483820Y132405D03*
X1471395Y487582D03*
X1473947Y492169D03*
X1472647Y539478D03*
X1475257Y530656D03*
X1473444Y555208D03*
X1473408Y547948D03*
X1478147Y547728D03*
X1478257Y543977D03*
X1481257Y544977D03*
X1482044Y542517D03*
X1472257Y551241D03*
X1472757Y561264D03*
X1473362Y558380D03*
X1472257Y564977D03*
X1481898Y585476D03*
X1484347Y580388D03*
X1478258Y588108D03*
Y584142D03*
X1474963Y701915D03*
X1480232Y704575D03*
X1475009Y704488D03*
X1481725Y715490D03*
X1471009Y703978D03*
X1481725Y712949D03*
X1477952Y708100D03*
X1477171Y774196D03*
Y771696D03*
Y769196D03*
Y776696D03*
X1474661Y776628D03*
Y774128D03*
Y771628D03*
Y769128D03*
X1472161Y776628D03*
Y769128D03*
Y771628D03*
Y774128D03*
X1472145Y766628D03*
X1474645D03*
X1477145D03*
X1477171Y791696D03*
X1474671D03*
X1472171D03*
X1477171Y786696D03*
X1474671D03*
X1477171Y781696D03*
X1474671D03*
X1472171Y789196D03*
Y779196D03*
Y784196D03*
Y786696D03*
Y781696D03*
X1477171Y789196D03*
X1474671D03*
X1477171Y779196D03*
X1474671D03*
X1477171Y784196D03*
X1474671D03*
X1481177Y803488D03*
X1469950Y813232D03*
X1473728Y813552D03*
X1480677Y813488D03*
X1484177Y812988D03*
X1474177Y816872D03*
X1471526Y1015473D03*
Y1019016D03*
Y1022559D03*
X1478298Y1485895D03*
X1474898D03*
X1471598Y1495595D03*
X1482798Y1685982D03*
X1469588Y1673342D03*
X1486000Y1686000D03*
X1470500Y1685500D03*
X1494891Y121171D03*
X1488647Y134562D03*
X1497386Y464980D03*
X1495682Y473302D03*
X1484395Y487582D03*
X1492514Y539657D03*
X1484416Y541658D03*
X1488510Y542816D03*
X1490602Y544755D03*
X1497310Y543960D03*
X1494967Y541898D03*
X1487660Y585748D03*
X1491677Y583588D03*
X1490677Y580688D03*
X1492789Y576602D03*
X1495236Y612838D03*
X1495486Y599938D03*
X1497986Y602438D03*
Y599938D03*
X1495236Y605338D03*
X1495486Y602438D03*
X1495236Y607838D03*
Y610338D03*
X1492636Y605258D03*
Y607758D03*
Y610258D03*
Y612758D03*
X1497986Y612838D03*
Y605338D03*
Y607838D03*
Y610338D03*
X1495486Y615988D03*
Y618488D03*
X1497986Y615988D03*
Y618488D03*
X1492886Y618408D03*
Y615908D03*
X1497587Y711636D03*
X1495157D03*
X1492727D03*
X1489963Y705301D03*
X1487797Y706931D03*
X1487897Y709931D03*
X1489963Y708201D03*
X1485697Y708431D03*
Y705531D03*
Y711331D03*
X1492264Y714544D03*
Y717444D03*
X1491943Y776628D03*
X1494443D03*
X1491943Y769128D03*
Y771628D03*
Y774128D03*
X1494443D03*
Y771628D03*
Y769128D03*
X1494417Y766628D03*
X1491917D03*
X1489417Y776710D03*
Y774210D03*
Y769210D03*
Y771710D03*
Y766628D03*
X1494487Y779210D03*
Y784210D03*
Y786710D03*
Y781710D03*
X1491987Y779210D03*
Y784210D03*
Y786710D03*
Y781710D03*
X1489487Y779210D03*
Y784210D03*
Y786710D03*
Y781710D03*
X1500500Y809063D03*
X1496532Y803513D03*
X1485177Y803488D03*
X1489177Y812988D03*
X1487923Y816770D03*
X1490973Y825557D03*
X1498177Y829359D03*
X1495670Y826073D03*
X1486761Y826279D03*
X1493260Y1167390D03*
X1496960D03*
X1491698Y1505295D03*
X1488298D03*
X1498398Y1495595D03*
X1494998D03*
X1488875Y1677385D03*
X1503785Y464815D03*
X1505974Y470636D03*
X1511917Y483878D03*
X1499752Y488424D03*
X1502085Y545432D03*
X1507109Y550059D03*
X1507644Y554372D03*
X1507468Y564357D03*
X1506337Y561677D03*
X1502757Y570977D03*
X1508281Y559390D03*
X1509757Y575477D03*
X1501821Y577664D03*
X1502986Y602438D03*
Y599938D03*
X1500486Y602438D03*
Y599938D03*
X1502486Y605338D03*
Y607838D03*
Y610338D03*
Y612838D03*
X1500486Y615988D03*
Y618488D03*
X1502986Y615988D03*
Y618488D03*
X1500603Y702378D03*
X1508045Y701915D03*
X1513314Y704575D03*
X1508045Y704423D03*
X1504091Y703978D03*
X1501353Y704946D03*
X1511034Y708100D03*
X1510287Y771710D03*
Y769210D03*
Y774210D03*
Y776710D03*
X1507743Y776628D03*
Y774128D03*
Y771628D03*
Y769128D03*
X1505243Y776628D03*
Y769128D03*
Y771628D03*
Y774128D03*
X1505227Y766628D03*
X1507727D03*
X1510227D03*
X1507787Y786710D03*
Y781710D03*
X1505287Y779210D03*
Y784210D03*
Y786710D03*
Y781710D03*
X1510287Y779210D03*
Y784210D03*
Y786710D03*
Y781710D03*
X1507787Y779210D03*
Y784210D03*
X1508177Y803488D03*
X1501500Y799948D03*
X1510261Y814611D03*
X1500422Y814180D03*
X1512523Y809679D03*
X1502177Y817013D03*
X1512539Y812920D03*
X1505016Y817107D03*
X1501636Y828796D03*
X1499469Y860322D03*
Y863322D03*
X1504362Y1167390D03*
X1508063D03*
X1505098Y1485895D03*
X1501698D03*
X1515854Y119810D03*
X1517708Y216505D03*
X1527392Y238017D03*
X1519120Y479215D03*
X1515936Y484412D03*
X1516757Y537477D03*
X1516257Y547977D03*
X1516336Y551977D03*
X1519457Y556338D03*
X1519317Y561977D03*
X1527853Y560264D03*
X1524777Y605488D03*
Y607988D03*
X1527277Y605488D03*
Y607988D03*
X1524777Y610588D03*
X1527277D03*
X1524777Y613088D03*
X1527277D03*
X1524777Y615618D03*
X1527277D03*
X1524777Y618118D03*
X1527277D03*
X1514807Y715490D03*
Y712949D03*
X1525527Y711636D03*
X1527957D03*
X1522763Y708201D03*
Y705301D03*
X1518497Y705531D03*
X1520597Y706931D03*
X1518497Y708431D03*
X1520697Y709931D03*
X1518497Y711331D03*
X1525064Y714544D03*
Y717444D03*
X1522217Y771710D03*
X1527217Y766628D03*
X1522217Y769210D03*
X1524717Y766628D03*
X1522217D03*
Y774210D03*
Y776710D03*
X1524743Y776628D03*
X1527243D03*
X1524743Y769128D03*
Y771628D03*
Y774128D03*
X1527243D03*
Y771628D03*
Y769128D03*
X1527217Y779210D03*
Y784210D03*
Y786710D03*
Y781710D03*
X1524717Y779210D03*
X1522217D03*
X1524717Y784210D03*
Y786710D03*
X1522217Y784210D03*
Y786710D03*
X1524717Y781710D03*
X1522217D03*
X1517431Y811466D03*
X1521003Y1169488D03*
X1521217Y1190088D03*
X1524425Y1185241D03*
X1528498Y1485895D03*
X1518498Y1505295D03*
X1525198Y1495595D03*
X1515098Y1505295D03*
X1521798Y1495595D03*
X1539134Y-22512D03*
Y-25912D03*
X1538342Y28406D03*
X1540342Y48720D03*
X1535566Y69340D03*
X1538966D03*
X1537450Y226293D03*
X1533160Y231250D03*
X1536538Y296819D03*
X1536422Y292816D03*
X1536542Y308819D03*
X1534584Y467067D03*
X1539693Y543613D03*
X1532824Y555981D03*
X1539693Y558943D03*
X1532730Y562949D03*
X1534565Y564945D03*
X1533403Y702378D03*
X1540845Y701915D03*
Y704423D03*
X1536891Y703978D03*
X1534153Y704946D03*
X1543834Y708100D03*
X1530387Y711636D03*
X1538027Y766628D03*
X1540527D03*
X1540543Y776628D03*
Y774128D03*
Y771628D03*
Y769128D03*
X1538043Y776628D03*
Y769128D03*
Y771628D03*
Y774128D03*
X1538027Y784710D03*
Y779210D03*
X1540527D03*
X1538027Y781710D03*
X1540527D03*
X1539972Y807319D03*
X1529306Y1177468D03*
X1540801Y1178265D03*
X1537301D03*
X1539301Y1175765D03*
X1532896Y1234836D03*
X1542747Y1253602D03*
X1538587Y1245065D03*
X1543772Y1241016D03*
X1543519Y1248205D03*
X1536916Y1240844D03*
X1531898Y1485895D03*
X1541898D03*
X1543582Y1524562D03*
X1541191Y1544953D03*
Y1547453D03*
Y1549953D03*
X1539369Y1552250D03*
X1541876Y1554436D03*
X1539344Y1579519D03*
X1552674Y26477D03*
X1556379Y19541D03*
X1549274Y26477D03*
X1557566Y69340D03*
X1546562Y75343D03*
X1549962D03*
X1554360Y207251D03*
X1556960Y287478D03*
X1551900Y287288D03*
X1544489Y288816D03*
X1546789Y287116D03*
X1548772Y291916D03*
X1553154Y479063D03*
X1558198Y486791D03*
X1551779Y530698D03*
X1546149Y541169D03*
X1545987Y562012D03*
X1553657Y678965D03*
X1553827Y687991D03*
X1556027Y680391D03*
X1555893Y686261D03*
Y683361D03*
X1553657Y681965D03*
X1553727Y684991D03*
X1558657Y689696D03*
X1558194Y695501D03*
Y692501D03*
X1546114Y704575D03*
X1547607Y715490D03*
Y712949D03*
X1556708Y747282D03*
X1556688Y744688D03*
X1556708Y749782D03*
Y754782D03*
Y752282D03*
Y757282D03*
Y762282D03*
Y759782D03*
Y764782D03*
Y769782D03*
Y767282D03*
X1556121Y798542D03*
X1551124Y801289D03*
X1551961Y807269D03*
X1556361D03*
X1547561D03*
X1551113Y1238088D03*
X1548360Y1234750D03*
X1550517Y1232905D03*
X1545627Y1254068D03*
X1545480Y1245090D03*
X1544911Y1260654D03*
X1543980Y1258312D03*
X1554692Y1269688D03*
X1557559Y1269095D03*
X1557510Y1280291D03*
X1554377Y1278763D03*
X1560454Y1279004D03*
X1553226Y1288814D03*
X1553548Y1284991D03*
X1556515Y1292232D03*
X1555222Y1302757D03*
X1547195Y1478165D03*
X1547216Y1480812D03*
X1545298Y1485895D03*
X1545473Y1522117D03*
X1547548Y1520070D03*
X1552668Y1513682D03*
Y1517082D03*
Y1530482D03*
Y1527082D03*
X1551821Y1549120D03*
Y1545220D03*
X1551546Y1552845D03*
X1556071Y1547576D03*
X1554635Y1542469D03*
X1552135D03*
X1556071Y1545076D03*
X1545644Y1552845D03*
X1545521Y1549120D03*
Y1545220D03*
X1548671Y1549120D03*
Y1545220D03*
X1548684Y1554436D03*
X1554093Y1582295D03*
Y1574795D03*
Y1579795D03*
Y1577295D03*
X1551593Y1582295D03*
Y1579795D03*
X1556593Y1582295D03*
Y1579795D03*
Y1574795D03*
Y1577295D03*
X1549093Y1579795D03*
Y1582295D03*
X1546593D03*
Y1579795D03*
X1558560Y1571682D03*
X1556060D03*
X1557633Y1584844D03*
X1566847Y26477D03*
X1559779Y19541D03*
X1570552D03*
X1563447Y26477D03*
X1568566Y75340D03*
X1571966D03*
X1560966Y69340D03*
X1572502Y254250D03*
X1572549Y257491D03*
X1566442Y294816D03*
X1564506Y310334D03*
Y313734D03*
X1571516Y319099D03*
X1568070Y497847D03*
X1573070D03*
X1570570D03*
X1570068Y534095D03*
X1573326Y543351D03*
X1573487Y546996D03*
X1572436Y578933D03*
X1568446Y582733D03*
X1572436Y582433D03*
X1564946Y582733D03*
X1561246Y580393D03*
X1572436Y574022D03*
X1568936Y585933D03*
Y589433D03*
X1565436Y585933D03*
Y589433D03*
X1562016Y584283D03*
Y587783D03*
X1572436Y589433D03*
Y585933D03*
X1566533Y680438D03*
X1570021Y682038D03*
X1567283Y683006D03*
X1563517Y689696D03*
X1561087D03*
X1572514Y747188D03*
X1561714D03*
X1559214D03*
X1561688Y744688D03*
X1559188D03*
X1572498D03*
X1572588Y757282D03*
Y759782D03*
X1561708Y757282D03*
X1559208D03*
X1561708Y759782D03*
X1559208D03*
X1561708Y762282D03*
X1559208D03*
X1572514Y752188D03*
Y749688D03*
Y754688D03*
X1561714Y749688D03*
Y752188D03*
X1559214D03*
Y749688D03*
X1561714Y754688D03*
X1559214D03*
X1561708Y769782D03*
X1559208D03*
X1561708Y767282D03*
X1559208D03*
X1561708Y764782D03*
X1559208D03*
X1570583Y800104D03*
X1572668Y806778D03*
X1567737Y1271411D03*
X1561927Y1269901D03*
X1559181Y1287165D03*
X1568100Y1290418D03*
X1567000Y1293446D03*
X1562820Y1309360D03*
X1568456Y1311533D03*
X1572416Y1303160D03*
X1564268Y1338440D03*
X1562937Y1341609D03*
X1572331Y1348205D03*
X1566901Y1347726D03*
X1564758Y1367834D03*
X1572906Y1366759D03*
X1563967Y1363205D03*
X1572860Y1495595D03*
X1569460D03*
X1563222Y1516590D03*
Y1513190D03*
Y1534990D03*
Y1538390D03*
X1567089Y1563596D03*
X1562640Y1556331D03*
Y1559731D03*
X1559093Y1577295D03*
Y1574795D03*
X1565963D03*
X1568463D03*
X1565963Y1577295D03*
X1568463D03*
Y1579795D03*
X1565963D03*
X1568463Y1582295D03*
X1565963D03*
X1570963Y1574795D03*
Y1582295D03*
Y1579795D03*
Y1577295D03*
X1563463Y1574795D03*
Y1582295D03*
Y1579795D03*
Y1577295D03*
X1560051Y1581199D03*
X1574966Y1577038D03*
X1562556Y1584844D03*
X1560051Y1584099D03*
X1588125Y19541D03*
X1581020Y26477D03*
X1573952Y19541D03*
X1584725D03*
X1577620Y26477D03*
X1579566Y69340D03*
X1582966D03*
X1586291Y303596D03*
X1586621Y484304D03*
X1580519Y497650D03*
X1575570Y497847D03*
X1584397Y655622D03*
X1586497Y651222D03*
X1586597Y654222D03*
X1584397Y652722D03*
Y649822D03*
X1573975Y679975D03*
X1579244Y682635D03*
X1573975Y682483D03*
X1576964Y686160D03*
X1580737Y693550D03*
Y691009D03*
X1577588Y747282D03*
X1575014Y747188D03*
X1577498Y744688D03*
X1574998D03*
X1575088Y757282D03*
X1577588Y749782D03*
Y754782D03*
Y752282D03*
X1575014Y749688D03*
Y752188D03*
Y754688D03*
X1578690Y1283310D03*
X1585290Y1285098D03*
X1574168Y1283300D03*
X1577077Y1270937D03*
X1580577D03*
X1584068Y1271198D03*
X1580010Y1296100D03*
X1574560Y1296410D03*
X1580520Y1289900D03*
X1586167Y1295478D03*
X1575024Y1306373D03*
X1586557Y1304509D03*
X1578336Y1359253D03*
X1578411Y1348623D03*
X1578020Y1344773D03*
X1584156Y1381419D03*
X1586000Y1387641D03*
X1590723Y1381589D03*
X1579560Y1485895D03*
X1576160D03*
X1602299Y19541D03*
X1595194Y26477D03*
X1598899Y19541D03*
X1591794Y26477D03*
X1590566Y75340D03*
X1601562Y69343D03*
X1593966Y75340D03*
X1603970Y222956D03*
X1593303Y234250D03*
Y239250D03*
X1598303Y234250D03*
X1596462Y229790D03*
X1593658Y252010D03*
X1593303Y244250D03*
X1593349Y248160D03*
X1597481Y271991D03*
X1600918Y521688D03*
X1604890Y531226D03*
X1596299Y536344D03*
X1599303Y646669D03*
X1602791Y648269D03*
X1600053Y649237D03*
X1596287Y655927D03*
X1591427D03*
X1593857D03*
X1588663Y649592D03*
Y652492D03*
X1590964Y661741D03*
Y658741D03*
X1594844Y713419D03*
Y715919D03*
X1592344D03*
Y713419D03*
X1594818Y710919D03*
X1594844Y718419D03*
X1592344D03*
X1594844Y720919D03*
X1592344D03*
X1594688Y723512D03*
Y726012D03*
Y728512D03*
Y731012D03*
X1592188Y723512D03*
Y726012D03*
Y728512D03*
Y731012D03*
X1594688Y736012D03*
X1592188D03*
X1594688Y733512D03*
X1592188D03*
X1594900Y780112D03*
X1598467Y1267539D03*
X1588832Y1269083D03*
X1597177Y1282288D03*
X1594152Y1282578D03*
X1598883Y1270766D03*
X1590827Y1271378D03*
X1593397Y1271458D03*
X1596273Y1271472D03*
X1591005Y1288892D03*
X1596363Y1286296D03*
X1590921Y1309276D03*
X1599241Y1306622D03*
X1589845Y1305289D03*
X1599007Y1309762D03*
X1597621Y1365384D03*
X1595438Y1370603D03*
X1592788Y1388318D03*
X1597234Y1382689D03*
X1600531Y1404710D03*
X1597992Y1433183D03*
X1595716Y1431861D03*
X1602782Y1435920D03*
X1600442Y1434535D03*
X1602960Y1485895D03*
X1592960Y1505295D03*
X1599660Y1495595D03*
X1589560Y1505295D03*
X1596260Y1495595D03*
X1612566Y75340D03*
X1615966D03*
X1604962Y69343D03*
X1615020Y183050D03*
X1619909Y298742D03*
Y293742D03*
X1612144Y418552D03*
X1614701Y422587D03*
X1616464Y457509D03*
X1616250Y465042D03*
X1609166Y527300D03*
X1611775D03*
X1609166Y524700D03*
X1611775D03*
X1613169Y531819D03*
X1604991Y536344D03*
X1616084Y549105D03*
X1616198Y556364D03*
X1618859Y542820D03*
X1618356Y612137D03*
Y609137D03*
X1618434Y605753D03*
X1609044Y600986D03*
X1617397Y630822D03*
Y636622D03*
Y633722D03*
X1606745Y646206D03*
X1612014Y648866D03*
X1606745Y648714D03*
X1613507Y657240D03*
X1609734Y652391D03*
X1613507Y659781D03*
X1605644Y715919D03*
Y713419D03*
X1608144D03*
Y715919D03*
X1605628Y710919D03*
X1608128D03*
X1610628D03*
X1610718Y713513D03*
Y716013D03*
X1605644Y718419D03*
Y720919D03*
X1608144Y718419D03*
Y720919D03*
X1610718Y721013D03*
Y718513D03*
X1608118Y723512D03*
X1605618D03*
X1608118Y726012D03*
X1605618D03*
X1610618Y723512D03*
X1605618Y728512D03*
X1617200Y766870D03*
X1607267Y1271978D03*
X1604137Y1271358D03*
X1605801Y1286168D03*
X1608901Y1285887D03*
X1605360Y1294595D03*
X1608652Y1303338D03*
X1608341Y1313269D03*
X1608418Y1333589D03*
Y1331089D03*
X1614767Y1443512D03*
X1605648Y1437305D03*
X1606360Y1485895D03*
X1616360Y1505295D03*
X1622329Y28261D03*
X1631060Y26477D03*
X1627660D03*
X1623189Y48720D03*
X1623562Y69343D03*
X1626962D03*
X1631200Y164110D03*
X1631455Y167875D03*
X1627152Y168920D03*
X1629597Y227157D03*
X1627156Y238303D03*
X1627986Y282728D03*
X1627909Y286742D03*
Y298742D03*
Y294742D03*
Y290742D03*
X1619909Y303596D03*
X1627909Y302742D03*
X1621680Y366920D03*
X1625000Y383399D03*
X1631657Y392925D03*
X1632012Y603015D03*
X1621512D03*
X1625012D03*
X1628512D03*
X1632303Y627669D03*
X1633053Y630237D03*
X1626857Y636927D03*
X1629287D03*
X1624427D03*
X1621663Y630592D03*
X1619597Y635222D03*
X1621663Y633492D03*
X1619497Y632222D03*
X1623964Y642741D03*
Y639741D03*
X1627643Y694419D03*
Y696919D03*
Y699419D03*
X1625143D03*
Y696919D03*
Y694419D03*
X1627643Y701919D03*
X1625143D03*
X1627617Y691919D03*
X1625117D03*
Y709512D03*
Y704512D03*
Y707012D03*
Y712012D03*
X1627617Y709512D03*
Y704512D03*
Y707012D03*
Y712012D03*
X1628046Y763765D03*
X1626928Y1260917D03*
X1629428D03*
X1631928D03*
X1626333Y1311091D03*
Y1308091D03*
X1627174Y1420450D03*
X1625285Y1433384D03*
X1635281Y1422450D03*
X1627217Y1428366D03*
X1622697Y1440797D03*
X1625170Y1444016D03*
X1635227Y1436528D03*
X1633160Y1485895D03*
X1629760D03*
X1619760Y1505295D03*
X1626460Y1495595D03*
X1623060D03*
X1645233Y26477D03*
X1638165Y19541D03*
X1641833Y26477D03*
X1634765Y19541D03*
X1646770Y69340D03*
X1635770Y75340D03*
X1639170D03*
X1636047Y224597D03*
Y229912D03*
X1647310Y408922D03*
Y411422D03*
X1635697Y561253D03*
X1635944Y609510D03*
Y612510D03*
X1636022Y606126D03*
X1647158Y618971D03*
X1639745Y627206D03*
X1646507Y640781D03*
X1645014Y629866D03*
X1639745Y629714D03*
X1635791Y629269D03*
X1646507Y638240D03*
X1642734Y633391D03*
X1638443Y699419D03*
Y696919D03*
Y694419D03*
Y701919D03*
X1640943Y694419D03*
Y696919D03*
Y699419D03*
Y701919D03*
X1643517Y702013D03*
Y699513D03*
Y694513D03*
Y697013D03*
X1643427Y691919D03*
X1640927D03*
X1638427D03*
X1640877Y706972D03*
Y709472D03*
X1638377D03*
Y704472D03*
Y706972D03*
X1640877Y704472D03*
X1643377Y709510D03*
Y704510D03*
Y707010D03*
X1640877Y711972D03*
X1638377D03*
X1643377Y712010D03*
X1635088Y767205D03*
Y771005D03*
X1644188Y766870D03*
X1634428Y1260917D03*
X1645163Y1276184D03*
X1641677Y1341488D03*
Y1344488D03*
X1641087Y1396118D03*
X1641065Y1403393D03*
X1644001Y1408069D03*
X1646483Y1412741D03*
X1641065Y1406393D03*
X1635619Y1430536D03*
X1639834Y1434478D03*
X1636167Y1446746D03*
X1642400Y1439674D03*
X1645979Y1437950D03*
X1650400Y1437820D03*
X1641167Y1446746D03*
X1646560Y1505295D03*
X1643160D03*
X1646879Y1681738D03*
X1645029Y1715609D03*
Y1710609D03*
X1648029Y1708609D03*
Y1723759D03*
X1645029Y1725759D03*
Y1730759D03*
X1652338Y19541D03*
X1648938D03*
X1657766Y75343D03*
X1661166D03*
X1650170Y69340D03*
X1652525Y146762D03*
Y151762D03*
Y161762D03*
X1650023Y221842D03*
X1654419Y224597D03*
X1659419D03*
X1650023Y227157D03*
X1654419Y229912D03*
X1661928Y230172D03*
X1650020Y408952D03*
Y411452D03*
X1654110Y434177D03*
X1657545Y434506D03*
X1650035Y434750D03*
X1657194Y599956D03*
X1651194D03*
X1660194Y609450D03*
X1654194D03*
X1660194Y599956D03*
X1657194Y609450D03*
X1654194Y599956D03*
X1651194Y609450D03*
X1654147Y616523D03*
X1662377Y696300D03*
Y693300D03*
X1651072Y1314137D03*
X1660572Y1313837D03*
X1660635Y1329166D03*
X1651072Y1323137D03*
Y1320137D03*
Y1317137D03*
X1660572Y1322837D03*
Y1319837D03*
X1660635Y1326466D03*
X1660572Y1316837D03*
X1658015Y1328966D03*
X1658115Y1326466D03*
X1660635Y1331666D03*
Y1334166D03*
Y1339166D03*
Y1336666D03*
X1650177Y1341488D03*
X1658277Y1341888D03*
X1658015Y1336466D03*
Y1338966D03*
Y1331466D03*
Y1333966D03*
X1650177Y1344488D03*
X1658677D03*
X1653390Y1386316D03*
Y1388857D03*
X1649197Y1396743D03*
X1654883Y1397231D03*
X1660152Y1397383D03*
X1664106Y1397828D03*
X1660152Y1399891D03*
X1657163Y1393706D03*
X1661807Y1416948D03*
X1663777Y1421568D03*
X1662487Y1424178D03*
X1658089Y1437444D03*
X1649380Y1446713D03*
X1659960Y1485895D03*
X1656560D03*
X1653260Y1495595D03*
X1649860D03*
X1659975Y1592929D03*
X1656101Y1671720D03*
X1651101Y1671833D03*
X1653930Y1660640D03*
X1656180Y1659220D03*
X1656849Y1664949D03*
X1651698Y1665045D03*
X1661125Y1690751D03*
X1656101Y1701094D03*
X1656997Y1718759D03*
Y1733909D03*
X1675194Y26477D03*
X1671794D03*
X1668770Y69340D03*
X1672170D03*
X1673100Y121762D03*
Y136762D03*
Y131762D03*
X1673403Y199997D03*
X1664335Y210191D03*
X1663310Y215488D03*
X1664789Y767265D03*
Y771065D03*
X1673889Y766870D03*
X1674972Y1313837D03*
X1675134Y1329219D03*
X1675234Y1326519D03*
X1674972Y1316837D03*
X1672623Y1326476D03*
X1663437Y1326526D03*
X1674972Y1319837D03*
Y1322837D03*
X1677754Y1326519D03*
Y1329019D03*
X1663437Y1334726D03*
X1672623Y1334676D03*
X1663437Y1329726D03*
X1672623Y1332176D03*
X1663437Y1332226D03*
X1672623Y1329676D03*
X1675134Y1331719D03*
Y1334219D03*
Y1336719D03*
Y1339219D03*
X1677754Y1339019D03*
Y1336519D03*
Y1331519D03*
Y1334019D03*
X1675931Y1384335D03*
Y1387235D03*
X1667594Y1399428D03*
X1666844Y1396860D03*
X1675470Y1390170D03*
X1673040D03*
X1670610D03*
X1672501Y1416678D03*
X1675641Y1432891D03*
X1672401Y1423365D03*
X1664237Y1426278D03*
X1671079Y1435069D03*
X1663239Y1428592D03*
X1670147Y1444311D03*
X1673360Y1485895D03*
X1669960D03*
X1676685Y1537893D03*
X1671034Y1549734D03*
Y1552234D03*
X1668703Y1550898D03*
X1671034Y1546934D03*
X1668827Y1553551D03*
X1671034Y1557234D03*
Y1554734D03*
X1673706Y1560425D03*
X1671006Y1576744D03*
Y1574244D03*
Y1571744D03*
X1668826Y1575498D03*
Y1572998D03*
X1676176Y1580650D03*
X1674923Y1582973D03*
X1677556Y1656405D03*
X1674356D03*
X1671156D03*
X1666168Y1667688D03*
X1670202Y1663150D03*
X1675290Y1663157D03*
X1674338Y1677832D03*
X1671902Y1676267D03*
X1669377Y1675241D03*
X1670773Y1688827D03*
X1680029Y1710609D03*
Y1715609D03*
X1672500Y1708927D03*
X1675360Y1721252D03*
X1689367Y26477D03*
X1682299Y19541D03*
X1685967Y26477D03*
X1678899Y19541D03*
X1690900Y69343D03*
X1679904Y75340D03*
X1683304D03*
X1695100Y121762D03*
X1683275Y120762D03*
X1695100Y136762D03*
Y131762D03*
X1684925D03*
Y136762D03*
Y123762D03*
Y126762D03*
Y145762D03*
X1695100Y146762D03*
X1684925Y141762D03*
X1695100Y156762D03*
Y161762D03*
Y166762D03*
X1684925Y157762D03*
Y166762D03*
X1678809Y206451D03*
X1682433Y220857D03*
X1682408Y228337D03*
X1689000Y234000D03*
X1692429Y403985D03*
X1694050Y416643D03*
X1690208Y421855D03*
X1690140Y434160D03*
X1692450Y436772D03*
X1692974Y553115D03*
X1685890Y708610D03*
X1684672Y1313837D03*
X1690697Y1329066D03*
Y1326566D03*
X1684672Y1322837D03*
Y1319837D03*
Y1316837D03*
X1690697Y1336566D03*
Y1334066D03*
Y1331566D03*
X1679028Y1341733D03*
X1687234Y1341533D03*
Y1344033D03*
X1679028Y1344233D03*
X1690697Y1339066D03*
X1686172Y1386416D03*
Y1388957D03*
X1687665Y1397331D03*
X1692934Y1397483D03*
Y1399991D03*
X1689945Y1393806D03*
X1682500Y1390475D03*
X1680300Y1391875D03*
X1682500Y1396275D03*
X1680400Y1394875D03*
X1678234Y1393605D03*
Y1396505D03*
X1682500Y1393375D03*
X1683741Y1443075D03*
X1681538Y1451522D03*
X1689062Y1451496D03*
X1687783Y1472068D03*
X1680730Y1517082D03*
Y1513682D03*
Y1530482D03*
Y1527082D03*
X1685745Y1552579D03*
X1686219Y1549994D03*
X1685745Y1555079D03*
Y1557579D03*
X1685995Y1561516D03*
X1680589Y1559626D03*
Y1563526D03*
X1690353Y1591494D03*
X1680695Y1656307D03*
X1686675Y1659287D03*
X1692415Y1663740D03*
X1685500Y1663599D03*
X1680367Y1663367D03*
X1691952Y1698947D03*
X1689184Y1702095D03*
X1683029Y1708609D03*
X1680877Y1723593D03*
X1692218Y1717539D03*
X1685383Y1729559D03*
X1707186Y15708D03*
X1696472Y19541D03*
X1693072D03*
X1703583Y26505D03*
X1700183D03*
X1703536Y50649D03*
X1700136D03*
X1701904Y75340D03*
X1705304D03*
X1694300Y69343D03*
X1695100Y126762D03*
Y141762D03*
Y151762D03*
X1705120Y143610D03*
X1693000Y234000D03*
X1698220Y369652D03*
X1699809Y403985D03*
X1695579D03*
X1702959Y404243D03*
X1697161Y406602D03*
X1706500Y415862D03*
Y413362D03*
X1707780Y410738D03*
X1695455Y422287D03*
X1707568Y420370D03*
X1701124Y423802D03*
X1707544Y431745D03*
X1704974Y553115D03*
X1700974D03*
X1696974D03*
X1693490Y620672D03*
X1697530Y636369D03*
X1701661Y644554D03*
X1705561D03*
X1699500Y654738D03*
Y673738D03*
X1694490Y767265D03*
Y771065D03*
X1708049Y766870D03*
X1699072Y1313737D03*
X1696047Y1326576D03*
X1705383D03*
X1693417Y1329266D03*
X1693217Y1326566D03*
X1699072Y1322737D03*
Y1319737D03*
Y1316737D03*
X1693417Y1334266D03*
Y1331766D03*
X1705383Y1334676D03*
X1696047D03*
X1705383Y1329676D03*
X1696047Y1332176D03*
Y1329676D03*
X1705383Y1332176D03*
X1693417Y1336766D03*
Y1339266D03*
X1700376Y1399528D03*
X1696888Y1397928D03*
X1699626Y1396960D03*
X1703392Y1390270D03*
X1705822D03*
X1700272Y1460547D03*
X1702281Y1449801D03*
X1705108Y1451774D03*
X1695020Y1465621D03*
X1698440Y1466590D03*
X1705246Y1465325D03*
X1701348Y1466557D03*
X1709964Y1597490D03*
X1709833Y1612940D03*
Y1606340D03*
X1701984Y1671618D03*
X1695987D03*
X1700156Y1698830D03*
X1702750Y1696185D03*
X1706086Y1691568D03*
X1717148Y19910D03*
X1712977Y19986D03*
X1722148Y19910D03*
X1722085Y25908D03*
X1717055D03*
X1710106Y39768D03*
X1723241Y48822D03*
X1710106Y48978D03*
X1721646Y68115D03*
X1716558Y67866D03*
X1715861Y72593D03*
X1712486Y117908D03*
X1712686Y111908D03*
X1719909Y112713D03*
Y116713D03*
X1713399Y132858D03*
X1721384Y135373D03*
X1717384D03*
X1716609Y141297D03*
X1721628Y147312D03*
X1714293Y156278D03*
X1711293D03*
X1716893D03*
X1719493D03*
X1722093D03*
X1711293Y158878D03*
X1714293D03*
X1711293Y161478D03*
X1714293D03*
X1711293Y163978D03*
X1714293D03*
X1711293Y166478D03*
X1714293D03*
X1722093Y158878D03*
X1719493D03*
X1716893D03*
X1722093Y161478D03*
Y163978D03*
Y166478D03*
X1719493Y161478D03*
X1716893D03*
X1719493Y163978D03*
X1716893D03*
Y166478D03*
X1719493D03*
X1719200Y371162D03*
X1717220Y381152D03*
X1713720D03*
X1717220Y384652D03*
Y388152D03*
X1713720D03*
Y384652D03*
X1717220Y391652D03*
X1713720D03*
X1709000Y415862D03*
Y413362D03*
X1709339Y637251D03*
X1718465Y657982D03*
X1720050Y649142D03*
X1716030Y668182D03*
X1709759Y670221D03*
X1718686Y676154D03*
X1722672Y1313237D03*
X1708672Y1313737D03*
X1707916Y1329319D03*
X1722672Y1316237D03*
X1708672Y1322737D03*
Y1319737D03*
X1710536Y1329119D03*
X1708016Y1326619D03*
X1710536D03*
X1722672Y1319237D03*
Y1322237D03*
X1719916Y1326559D03*
X1717396D03*
X1719916Y1329059D03*
X1717396D03*
X1708672Y1316737D03*
X1707916Y1334319D03*
Y1331819D03*
Y1339319D03*
Y1336819D03*
X1710536Y1336619D03*
Y1339119D03*
X1719916Y1339059D03*
X1717396D03*
X1719916Y1336559D03*
X1717396D03*
X1710536Y1334119D03*
Y1331619D03*
X1719916Y1331559D03*
Y1334059D03*
X1717396D03*
Y1331559D03*
X1710176Y1342089D03*
X1718706Y1341629D03*
Y1344129D03*
X1710176Y1344589D03*
X1708713Y1384435D03*
Y1387335D03*
X1708252Y1390270D03*
X1715282Y1396375D03*
X1713082Y1391975D03*
X1715282Y1390575D03*
X1711016Y1393705D03*
Y1396605D03*
X1713182Y1394975D03*
X1715282Y1393475D03*
X1717447Y1417213D03*
X1714447D03*
X1717447Y1423213D03*
Y1420213D03*
X1714447D03*
Y1423213D03*
X1722334Y1468146D03*
X1718425Y1468245D03*
X1722347Y1471246D03*
X1716070Y1472037D03*
X1712870Y1586615D03*
X1715693Y1597190D03*
X1713593Y1609640D03*
Y1603040D03*
X1720845Y1668498D03*
X1719181Y1706712D03*
X1721172Y1712115D03*
X1710360Y1706502D03*
X1721912Y1705115D03*
X1719218Y1727265D03*
X1719148Y1721530D03*
X1722149Y1720265D03*
X1710230Y1729654D03*
X1729557Y-22512D03*
Y-25912D03*
X1736006Y41838D03*
Y44338D03*
X1729836Y54524D03*
X1727336D03*
X1724685Y51454D03*
X1727225Y51424D03*
X1729895Y51354D03*
X1726741Y48822D03*
X1730241D03*
X1737617Y75640D03*
Y73140D03*
Y79140D03*
Y81640D03*
X1722984Y101713D03*
X1723184Y93313D03*
X1736731Y102293D03*
X1728965Y112941D03*
X1729046Y118178D03*
X1739686Y120938D03*
X1725093Y156278D03*
Y158878D03*
Y161478D03*
Y163978D03*
Y166478D03*
X1735471Y293682D03*
Y290682D03*
Y296682D03*
Y299682D03*
X1730331Y293722D03*
Y296722D03*
X1732831D03*
X1730331Y299722D03*
X1732831D03*
Y293722D03*
X1723492Y293068D03*
X1732751Y305732D03*
X1730251D03*
X1732751Y302732D03*
X1730251D03*
X1735391Y305692D03*
Y302692D03*
X1725344Y359334D03*
X1728300Y377787D03*
X1733043Y657091D03*
X1736848Y650974D03*
X1726409Y653641D03*
X1737002Y671494D03*
X1724191Y767299D03*
Y771099D03*
X1737850Y766794D03*
X1732702Y1313007D03*
Y1316007D03*
Y1322007D03*
Y1319007D03*
X1732766Y1410562D03*
Y1413062D03*
X1735266Y1410562D03*
Y1413062D03*
X1732766Y1426362D03*
Y1428862D03*
X1735266Y1426362D03*
Y1428862D03*
X1730004Y1540968D03*
X1726604Y1540970D03*
X1735379Y1566282D03*
X1735354Y1580480D03*
X1735351Y1569832D03*
X1736479Y1584330D03*
X1730202Y1602093D03*
X1735463Y1651965D03*
X1730381Y1647386D03*
X1726381D03*
X1734500Y1656965D03*
X1734589Y1666203D03*
X1734962Y1662965D03*
X1734963Y1673465D03*
X1724263Y1672465D03*
X1734763Y1680465D03*
X1735463Y1694465D03*
X1725423Y1692656D03*
X1731936Y1690165D03*
X1731117Y1715265D03*
X1732251Y1708265D03*
X1731117Y1730415D03*
X1748708Y26641D03*
X1751031Y39063D03*
X1738093Y53103D03*
Y55603D03*
X1741621Y76613D03*
Y74113D03*
Y82613D03*
Y80113D03*
X1743491Y92827D03*
X1738435Y100244D03*
X1741935D03*
X1745435D03*
X1740231Y102293D03*
X1743731D03*
X1748686Y97408D03*
X1740091Y92827D03*
X1750786Y120018D03*
X1744976Y122998D03*
X1754339Y128242D03*
X1752022Y269794D03*
Y266794D03*
X1742971Y293682D03*
Y290682D03*
X1737971D03*
X1740471Y293682D03*
Y290682D03*
Y299682D03*
X1737971D03*
X1740471Y296682D03*
X1737971D03*
Y293682D03*
X1751352Y293386D03*
X1745671Y290682D03*
Y293682D03*
X1737891Y302692D03*
X1740391D03*
X1737891Y305692D03*
X1740391D03*
X1744510Y377452D03*
X1744380Y382892D03*
X1742398Y484304D03*
X1742306Y661032D03*
X1745484Y668216D03*
X1751490Y713890D03*
X1748990D03*
X1746490D03*
X1743990D03*
X1751490Y706390D03*
X1748990D03*
X1746490D03*
X1743990D03*
X1751490Y708890D03*
X1748990D03*
X1746490D03*
X1743990D03*
X1751490Y711390D03*
X1748990D03*
X1746490D03*
X1743990D03*
X1742766Y1418462D03*
Y1415962D03*
X1737766Y1410562D03*
Y1413062D03*
X1740266Y1410562D03*
Y1413062D03*
X1742766D03*
Y1410562D03*
X1740266Y1415962D03*
Y1418462D03*
X1737766Y1426362D03*
Y1428862D03*
X1742766Y1423462D03*
X1740266Y1426362D03*
Y1423462D03*
Y1420962D03*
X1742766D03*
X1741329Y1506405D03*
Y1503405D03*
Y1509405D03*
Y1512405D03*
X1745543Y1518678D03*
X1742758Y1521239D03*
X1745746D03*
X1751120Y1521223D03*
X1751087Y1518704D03*
X1748346Y1521223D03*
X1748313Y1518704D03*
X1739565Y1528105D03*
X1751132Y1526748D03*
Y1524248D03*
Y1529248D03*
X1742810Y1524534D03*
X1745410D03*
X1748358Y1526748D03*
Y1524248D03*
Y1529248D03*
X1746779Y1583378D03*
X1751558Y1579332D03*
X1746079Y1587705D03*
X1750463Y1654465D03*
X1744963Y1656465D03*
X1744463Y1651229D03*
X1747986Y1686215D03*
X1751340Y1686140D03*
X1744620Y1716018D03*
X1750380Y1707468D03*
X1747120Y1710824D03*
X1749480Y1718158D03*
X1765920Y17031D03*
X1765980Y27031D03*
X1765920Y22031D03*
X1758638Y26477D03*
X1755238D03*
X1767266Y48748D03*
X1763010Y51223D03*
X1765527Y53692D03*
X1758635Y50649D03*
X1755235D03*
X1757923Y72637D03*
X1767956Y76843D03*
X1767136Y83653D03*
X1761417Y90017D03*
X1760444Y106173D03*
X1763644D03*
X1755944Y111073D03*
Y108473D03*
X1760944Y116773D03*
X1757944D03*
X1760124Y128246D03*
X1755504Y202263D03*
X1758030D03*
X1762564Y202326D03*
X1765090D03*
X1761573Y266657D03*
X1764573D03*
X1761573Y269657D03*
X1764573D03*
X1758022Y269794D03*
Y266794D03*
X1755022Y269794D03*
Y266794D03*
X1755772Y278859D03*
X1758772D03*
X1761772D03*
X1755772Y281859D03*
X1758772D03*
X1761772D03*
X1752772Y278859D03*
Y281859D03*
X1756800Y364048D03*
Y368048D03*
X1756933Y372452D03*
X1759379Y507927D03*
X1753566Y512968D03*
X1768041Y556537D03*
X1753990Y711390D03*
Y708890D03*
Y706390D03*
Y713890D03*
X1753891Y767305D03*
Y771105D03*
X1767450Y766870D03*
X1759949Y1297324D03*
X1764267Y1460080D03*
X1756329Y1506405D03*
Y1503405D03*
X1764029Y1506405D03*
Y1503405D03*
X1756329Y1509405D03*
Y1512405D03*
X1764029Y1509405D03*
Y1512405D03*
X1765286Y1518471D03*
X1765176Y1515902D03*
X1765286Y1521095D03*
X1765246Y1524001D03*
Y1526601D03*
X1765334Y1529342D03*
X1764679Y1572105D03*
X1765679Y1575405D03*
X1762679D03*
X1766079Y1578705D03*
X1763079D03*
X1753512Y1583478D03*
X1763706Y1616451D03*
X1760206D03*
X1767206D03*
X1765854Y1646456D03*
X1755463Y1654465D03*
X1767888Y1664465D03*
X1762263Y1671765D03*
X1765163Y1670543D03*
X1765463Y1677465D03*
X1761463Y1683465D03*
X1775920Y17031D03*
X1770920D03*
X1775920Y27068D03*
X1770920Y22031D03*
X1775920D03*
X1768956Y37558D03*
X1777720Y37792D03*
X1773830Y49000D03*
X1779377Y50738D03*
X1774294Y60133D03*
X1774291Y57191D03*
X1769240Y50788D03*
X1769200Y54300D03*
X1780300Y54400D03*
X1775546Y73376D03*
X1774294Y63033D03*
X1779744Y72973D03*
Y70073D03*
X1770334Y72737D03*
X1778205Y90982D03*
X1781451Y88238D03*
X1773577Y88339D03*
X1778544Y97973D03*
X1769244Y113773D03*
Y110973D03*
Y108073D03*
X1781368Y162824D03*
X1780929Y179408D03*
X1776930Y179051D03*
X1773581Y194120D03*
X1771055D03*
X1771931Y200920D03*
X1769405D03*
X1777170Y201002D03*
X1774644D03*
X1778796Y261633D03*
X1767573Y266657D03*
X1775633Y261666D03*
X1767573Y269657D03*
X1778796Y266633D03*
Y269133D03*
Y264133D03*
X1775633Y269166D03*
Y266666D03*
Y264166D03*
X1778796Y271633D03*
X1775633Y271666D03*
X1770280Y372452D03*
X1770220Y382952D03*
Y377452D03*
X1782324Y403932D03*
Y410432D03*
Y418932D03*
Y425432D03*
X1779376Y558324D03*
X1782376D03*
X1773963Y557537D03*
X1776986Y749023D03*
X1776550Y763765D03*
X1769650Y1280200D03*
X1771000Y1278060D03*
X1782369Y1447581D03*
X1782385Y1450095D03*
X1782337Y1453191D03*
X1775682Y1466568D03*
X1779029Y1506405D03*
Y1503405D03*
Y1509405D03*
Y1512405D03*
X1780012Y1518631D03*
Y1516031D03*
Y1521231D03*
X1777152Y1518631D03*
Y1516031D03*
Y1521231D03*
X1774552D03*
Y1516031D03*
Y1518631D03*
X1768176Y1515902D03*
X1768286Y1518471D03*
Y1521095D03*
X1770886D03*
Y1518471D03*
X1770776Y1515902D03*
X1780039Y1523860D03*
Y1526360D03*
X1779997Y1528888D03*
X1777179Y1526360D03*
Y1523860D03*
X1774579D03*
Y1526360D03*
X1768246Y1526601D03*
Y1524001D03*
X1768334Y1529342D03*
X1770846Y1524001D03*
Y1526601D03*
X1771079Y1566782D03*
X1770404Y1575330D03*
X1780579Y1582178D03*
X1771094Y1570332D03*
X1778794Y1585332D03*
X1768105Y1595925D03*
X1775794Y1585332D03*
X1768030Y1599249D03*
X1768180Y1606549D03*
X1768030Y1603149D03*
X1780154Y1615026D03*
X1777454D03*
X1780154Y1617726D03*
X1777454D03*
X1773349Y1631938D03*
Y1634438D03*
Y1636938D03*
X1770649Y1631938D03*
Y1634438D03*
X1781423Y1634394D03*
Y1636894D03*
X1778723Y1634294D03*
X1776023D03*
Y1636894D03*
X1778723D03*
X1773929Y1657465D03*
Y1654956D03*
X1768929Y1651956D03*
X1774338Y1676865D03*
X1771038Y1692956D03*
X1787826Y37548D03*
X1783700Y50011D03*
X1794099Y50461D03*
X1788204Y74958D03*
X1785108Y76078D03*
X1787756Y85178D03*
X1788204Y82338D03*
Y78108D03*
X1784144Y113973D03*
Y111173D03*
Y108273D03*
X1797692Y146285D03*
X1784006Y137395D03*
X1788950Y142750D03*
X1787390Y165834D03*
Y156834D03*
Y151834D03*
X1793444Y178083D03*
X1785320Y193072D03*
X1784915Y186053D03*
X1783896Y266633D03*
Y269133D03*
X1794174Y274499D03*
X1790674D03*
X1783896Y271633D03*
X1789771Y367866D03*
X1797929Y385293D03*
X1786260Y379059D03*
X1792507Y403932D03*
X1792335Y418775D03*
X1792450Y410615D03*
X1792220Y425432D03*
X1785376Y558324D03*
X1788376D03*
X1792895Y683536D03*
X1783592Y767565D03*
Y771365D03*
X1792692Y766870D03*
X1794362Y1275546D03*
X1785336Y1447565D03*
Y1450065D03*
X1785634Y1456326D03*
X1782530Y1456229D03*
X1785408Y1453385D03*
X1788029Y1506405D03*
Y1503405D03*
Y1509405D03*
Y1512405D03*
X1794265Y1518262D03*
Y1520862D03*
Y1523462D03*
Y1526062D03*
X1794268Y1528720D03*
X1784601Y1578967D03*
X1787239Y1579406D03*
X1789294Y1583278D03*
X1797118Y1596588D03*
X1797143Y1607014D03*
X1797076Y1603662D03*
X1797043Y1599811D03*
X1791979Y1616550D03*
X1795479D03*
X1782654Y1615026D03*
Y1617726D03*
X1784048Y1636875D03*
Y1634375D03*
X1786615Y1631800D03*
X1786588Y1634472D03*
X1786624Y1637021D03*
X1802565Y156557D03*
X1800554Y177229D03*
X1808622Y170869D03*
X1806470Y186866D03*
X1802570Y186913D03*
X1811274Y198098D03*
X1807596Y264133D03*
Y266633D03*
Y269133D03*
X1797674Y274499D03*
X1801174D03*
X1807596Y271633D03*
X1800160Y362542D03*
X1808962Y698055D03*
Y700555D03*
Y703055D03*
X1798462Y698055D03*
X1801962D03*
X1805462D03*
Y700555D03*
X1801962D03*
X1798462D03*
X1805462Y703055D03*
X1801962D03*
X1798462D03*
X1808962Y705555D03*
Y708055D03*
X1798462Y705555D03*
X1801962D03*
X1805462D03*
X1798462Y708055D03*
X1801962D03*
X1805462D03*
X1809002Y710945D03*
Y713445D03*
Y715945D03*
X1805502Y710945D03*
Y713445D03*
Y715945D03*
X1802050Y710940D03*
X1811526Y1281671D03*
X1803029Y1506405D03*
Y1503405D03*
X1812029Y1506405D03*
Y1503405D03*
X1803029Y1509405D03*
Y1512405D03*
X1812029Y1509405D03*
Y1512405D03*
X1797362Y1518304D03*
X1799882Y1520912D03*
Y1518312D03*
X1797362Y1520904D03*
X1804049Y1528031D03*
X1799882Y1523512D03*
X1797362Y1523504D03*
X1799882Y1526112D03*
X1797362Y1526104D03*
X1799994Y1528674D03*
X1797450Y1528768D03*
X1809890Y1524532D03*
X1807290D03*
X1798479Y1575605D03*
X1798879Y1578905D03*
X1801479Y1575605D03*
X1800479Y1572305D03*
X1801879Y1578905D03*
X1798979Y1616550D03*
X1815005Y149325D03*
X1817196Y163797D03*
Y159947D03*
X1818828Y175241D03*
X1817275Y180619D03*
X1813224Y194699D03*
X1816190Y208879D03*
X1817157Y373829D03*
X1828669Y379552D03*
X1816994Y398052D03*
X1816224Y410432D03*
X1822724Y424948D03*
X1815724Y423932D03*
X1825874Y424948D03*
X1822394Y436225D03*
X1827073Y565157D03*
X1824073D03*
X1821073D03*
X1812462Y698055D03*
Y700555D03*
Y703055D03*
Y705555D03*
Y708055D03*
X1812502Y710945D03*
Y713445D03*
Y715945D03*
X1827029Y1506405D03*
Y1503405D03*
Y1509405D03*
Y1512405D03*
X1818475Y1524682D03*
X1815875D03*
X1823649Y1525144D03*
X1831166Y149986D03*
X1827580Y151834D03*
X1829732Y371329D03*
X1828483Y431678D03*
X1833288Y1469639D03*
X1850791Y170287D03*
G54D30*
X180780Y1507509D03*
X178580D03*
X177487Y1521612D03*
X177086Y1518121D03*
X178745Y1513218D03*
X177533Y1535698D03*
Y1537898D03*
X178980Y1540317D03*
X183051Y1544625D03*
X188155Y1516970D03*
X192879D03*
X197604D03*
X189730Y1519698D03*
X194454D03*
X199178D03*
X188155Y1530608D03*
X192879D03*
X197604D03*
X189730Y1533336D03*
X194454D03*
X199178D03*
X202328Y1516970D03*
X207052D03*
X211777D03*
X216501D03*
X203903Y1519698D03*
X208627D03*
X213352D03*
X202328Y1530608D03*
X207052D03*
X211777D03*
X216501D03*
X203903Y1533336D03*
X208627D03*
X213352D03*
X221226Y1516970D03*
X225950D03*
X230674D03*
X218076Y1519698D03*
X222800D03*
X227525D03*
X221226Y1530608D03*
X225950D03*
X230674D03*
X218076Y1533336D03*
X222800D03*
X227525D03*
X235399Y1516970D03*
X240123D03*
X244848D03*
X236974Y1519698D03*
X241698D03*
X246422D03*
X232249D03*
X235399Y1530608D03*
X240123D03*
X244848D03*
X236974Y1533336D03*
X241698D03*
X246422D03*
X232249D03*
X249572Y1516970D03*
X254297D03*
X259021D03*
X251147Y1519698D03*
X255871D03*
X260596D03*
X249572Y1530608D03*
X254297D03*
X259021D03*
X251147Y1533336D03*
X255871D03*
X260596D03*
X265421Y1507355D03*
X263321D03*
X266828Y1514073D03*
X266772Y1516336D03*
X267123Y1536640D03*
Y1534540D03*
X267124Y1531618D03*
X267035Y1528698D03*
X266538Y1538658D03*
X305549Y1521612D03*
X305148Y1518121D03*
X305595Y1535698D03*
Y1537898D03*
X317957Y886002D03*
X319807Y889191D03*
Y895569D03*
X317957Y892380D03*
X316107Y895569D03*
X319807Y908325D03*
X317957Y898758D03*
X319807Y901947D03*
X317957Y905135D03*
Y911513D03*
X314256Y905135D03*
X317957Y917891D03*
X319807Y921080D03*
X317957Y924269D03*
X319807Y914702D03*
X314256Y924269D03*
X316107Y914702D03*
X319807Y927458D03*
X317957Y937025D03*
X319807Y940214D03*
Y933836D03*
X317957Y930647D03*
X316107Y933836D03*
X317957Y943403D03*
X319807Y946592D03*
X317957Y956159D03*
X319807Y952970D03*
X317957Y949781D03*
X316107Y952970D03*
X314256Y943403D03*
X317957Y962537D03*
X319807Y965726D03*
Y959348D03*
X317957Y968915D03*
X314256Y962537D03*
X317957Y975293D03*
X319807Y978482D03*
Y972104D03*
X316107D03*
X314256Y981671D03*
X317957Y994427D03*
X319807Y997616D03*
X317957Y1000805D03*
X319807Y991238D03*
X314256Y1000805D03*
X316107Y991238D03*
X317957Y988049D03*
X319807Y1010372D03*
X317957Y1007183D03*
X319807Y1003994D03*
X317288Y1028056D03*
X313587D03*
X320988D03*
Y1034434D03*
X319138Y1037623D03*
X320988Y1040812D03*
X319138Y1044001D03*
X315437Y1037623D03*
X319138Y1031245D03*
X320988Y1059946D03*
X319138Y1050379D03*
X320988Y1053568D03*
X315437Y1056757D03*
X317288Y1047190D03*
X319138Y1056757D03*
X320988Y1047190D03*
Y1072702D03*
X319138Y1063135D03*
Y1069513D03*
X320988Y1066324D03*
X317288D03*
X319138Y1075891D03*
X320988Y1079080D03*
X319138Y1082269D03*
Y1088647D03*
X320988Y1085458D03*
X317288D03*
X315437Y1075891D03*
X319138Y1101403D03*
X320988Y1091836D03*
X319138Y1095025D03*
X320988Y1098214D03*
Y1104592D03*
X317288D03*
X315437Y1095025D03*
X320988Y1110970D03*
X319138Y1114159D03*
X320988Y1117348D03*
X319138Y1107781D03*
X315437Y1114159D03*
X319138Y1120537D03*
X320988Y1130103D03*
X319138Y1133293D03*
Y1126915D03*
X320988Y1123726D03*
X315437Y1133293D03*
X317288Y1123726D03*
X320988Y1136481D03*
X319138Y1139670D03*
X320988Y1149237D03*
X319138Y1146048D03*
X320988Y1142859D03*
X317288D03*
X315437Y1158804D03*
X319138Y1152426D03*
X315437D03*
X319138Y1158804D03*
X308893Y1507460D03*
X316217Y1516970D03*
X320941D03*
X317792Y1519698D03*
X306807Y1513218D03*
X316217Y1530608D03*
X320941D03*
X317792Y1533336D03*
X311113Y1544625D03*
X307042Y1540317D03*
X327209Y882813D03*
X323508Y889191D03*
X325358Y892380D03*
X323508Y895569D03*
X332760Y886002D03*
X330910Y889191D03*
Y895569D03*
X332760Y892380D03*
X323508Y882813D03*
X325358Y911513D03*
X323508Y901947D03*
X325358Y905135D03*
X323508Y908325D03*
X325358Y898758D03*
X330910Y908325D03*
X332760Y898758D03*
X330910Y901947D03*
X332760Y905135D03*
Y911513D03*
X323508Y921080D03*
X325358Y924269D03*
X323508Y914702D03*
X325358Y917891D03*
X332760D03*
X330910Y921080D03*
X332760Y924269D03*
X330910Y914702D03*
X323508Y927458D03*
X325358Y930647D03*
X323508Y940214D03*
Y933836D03*
X325358Y937025D03*
X330910Y927458D03*
X332760Y937025D03*
X330910Y940214D03*
Y933836D03*
X332760Y930647D03*
X325358Y943403D03*
X323508Y946592D03*
X325358Y949781D03*
X323508Y952970D03*
X325358Y956159D03*
X332760Y943403D03*
X330910Y946592D03*
X332760Y956159D03*
X330910Y952970D03*
X332760Y949781D03*
X323508Y965726D03*
X325358Y968915D03*
X323508Y959348D03*
X325358Y962537D03*
X332760D03*
X330910Y965726D03*
Y959348D03*
X332760Y968915D03*
X323508Y984860D03*
Y978482D03*
X325358Y981671D03*
X323508Y972104D03*
X325358Y975293D03*
X332760D03*
X330910Y978482D03*
Y972104D03*
X325358Y988049D03*
X323508Y997616D03*
X325358Y1000805D03*
Y994427D03*
X332760D03*
X330910Y997616D03*
X332760Y1000805D03*
X330910Y991238D03*
X332760Y988049D03*
X323508Y991238D03*
Y1003994D03*
X325358Y1007183D03*
X330910Y1010372D03*
X332760Y1007183D03*
X330910Y1003994D03*
X323508Y1010372D03*
X324689Y1028056D03*
X332091D03*
X326539Y1031245D03*
X324689Y1034434D03*
X326539Y1037623D03*
X324689Y1040812D03*
X332091Y1034434D03*
X333941Y1037623D03*
X332091Y1040812D03*
X333941Y1044001D03*
Y1031245D03*
X326540Y1044001D03*
X326539Y1050379D03*
X324689Y1047190D03*
X332091Y1059946D03*
X333941Y1050379D03*
X332091Y1053568D03*
X333941Y1056757D03*
X332091Y1047190D03*
X324689Y1053568D03*
X326539Y1063135D03*
X324689Y1066324D03*
X326539Y1069513D03*
X324689Y1072702D03*
X332091D03*
X333941Y1063135D03*
Y1069513D03*
X332091Y1066324D03*
X326539Y1075891D03*
X324689Y1079080D03*
X326539Y1082269D03*
X324689Y1085458D03*
X326539Y1088647D03*
X333941Y1075891D03*
X332091Y1079080D03*
X333941Y1082269D03*
Y1088647D03*
X332091Y1085458D03*
X324689Y1104592D03*
X326539Y1095025D03*
X324689Y1098214D03*
X326539Y1101403D03*
X324689Y1091836D03*
X333941Y1101403D03*
X332091Y1091836D03*
X333941Y1095025D03*
X332091Y1098214D03*
Y1104592D03*
X326539Y1114159D03*
X324689Y1117348D03*
X326539Y1107781D03*
X324689Y1110970D03*
X332091D03*
X333941Y1114159D03*
X332091Y1117348D03*
X333941Y1107781D03*
X326539Y1120537D03*
X324689Y1123726D03*
X326539Y1133293D03*
Y1126915D03*
X324689Y1130103D03*
X333941Y1120537D03*
X332091Y1130103D03*
X333941Y1133293D03*
Y1126915D03*
X332091Y1123726D03*
X324689Y1136481D03*
X326539Y1139670D03*
X324689Y1142859D03*
X326539Y1146048D03*
X324689Y1149237D03*
X332091Y1136481D03*
X333941Y1139670D03*
X332091Y1149237D03*
X333941Y1146048D03*
X332091Y1142859D03*
X326539Y1152426D03*
X324689Y1155615D03*
X333941Y1152426D03*
X332091Y1155615D03*
Y1161993D03*
X333941Y1165182D03*
X326539D03*
X324689Y1161993D03*
X325666Y1516970D03*
X330390D03*
X335114D03*
X322516Y1519698D03*
X327240D03*
X331965D03*
X325666Y1530608D03*
X330390D03*
X335114D03*
X322516Y1533336D03*
X327240D03*
X331965D03*
X343862Y886002D03*
X349414Y889191D03*
X345713D03*
Y895569D03*
X349414D03*
X343862Y892380D03*
X338311Y889191D03*
X336461Y892380D03*
X338311Y895569D03*
X342012D03*
X345713Y908325D03*
X343862Y898758D03*
X349414Y901947D03*
X345713D03*
X343862Y905135D03*
X349414Y908325D03*
X343862Y911513D03*
X336461D03*
X338311Y901947D03*
X336461Y905135D03*
X338311Y908325D03*
X336461Y898758D03*
X340162Y905135D03*
X343862Y917891D03*
X349414Y921080D03*
X345713D03*
X343862Y924269D03*
X345713Y914702D03*
X349414D03*
X338311Y921080D03*
X336461Y924269D03*
X338311Y914702D03*
X336461Y917891D03*
X340162Y924269D03*
X342012Y914702D03*
X349414Y927458D03*
X345713D03*
X343862Y937025D03*
X349414Y940214D03*
X345713D03*
Y933836D03*
X349414D03*
X343862Y930647D03*
X338311Y927458D03*
X336461Y930647D03*
X338311Y940214D03*
Y933836D03*
X336461Y937025D03*
X342012Y933836D03*
X343862Y943403D03*
X349414Y946592D03*
X345713D03*
X343862Y956159D03*
X345713Y952970D03*
X349414D03*
X343862Y949781D03*
X336461Y943403D03*
X338311Y946592D03*
X336461Y949781D03*
X338311Y952970D03*
X336461Y956159D03*
X342012Y952970D03*
X340162Y943403D03*
X343862Y962537D03*
X349414Y965726D03*
X345713D03*
X349414Y959348D03*
X345713D03*
X343862Y968915D03*
X338311Y965726D03*
X336461Y968915D03*
X338311Y959348D03*
X336461Y962537D03*
X340162D03*
X349414Y984860D03*
X343862Y975293D03*
X349414Y978482D03*
X345713D03*
Y972104D03*
X349414D03*
X338311Y984860D03*
Y978482D03*
X336461Y981671D03*
X338311Y972104D03*
X336461Y975293D03*
X342012Y972104D03*
X340162Y981671D03*
X343862Y994427D03*
X345713Y997616D03*
X349414D03*
X343862Y1000805D03*
X345713Y991238D03*
X336461Y988049D03*
X338311Y997616D03*
X336461Y1000805D03*
Y994427D03*
X340162Y1000805D03*
X342012Y991238D03*
X338311D03*
X349414D03*
X343862Y988049D03*
X345713Y1010372D03*
X343862Y1007183D03*
X345713Y1003994D03*
X349414D03*
X338311D03*
X336461Y1007183D03*
X338311Y1010372D03*
X349414D03*
X343193Y1028056D03*
X350595D03*
X339492D03*
X346894D03*
X350595Y1034434D03*
X346894D03*
X345043Y1037623D03*
X350595Y1040812D03*
X346894D03*
X345043Y1044001D03*
X337642Y1031245D03*
X339492Y1034434D03*
X337642Y1037623D03*
X339492Y1040812D03*
X341343Y1037623D03*
X337642Y1044001D03*
X345043Y1031245D03*
X346894Y1059946D03*
X350595Y1047190D03*
X345043Y1050379D03*
X346894Y1053568D03*
X337642Y1050379D03*
X339492Y1047190D03*
X341343Y1056757D03*
X343193Y1047190D03*
X339492Y1053568D03*
X345043Y1056757D03*
X346894Y1047190D03*
X350595Y1053568D03*
X346894Y1072702D03*
X345043Y1063135D03*
X350595Y1066324D03*
X345043Y1069513D03*
X350595Y1072702D03*
X346894Y1066324D03*
X337642Y1063135D03*
X339492Y1066324D03*
X337642Y1069513D03*
X339492Y1072702D03*
X343193Y1066324D03*
X345043Y1075891D03*
X350595Y1079080D03*
X346894D03*
X345043Y1082269D03*
X350595Y1085458D03*
X345043Y1088647D03*
X346894Y1085458D03*
X337642Y1075891D03*
X339492Y1079080D03*
X337642Y1082269D03*
X339492Y1085458D03*
X337642Y1088647D03*
X343193Y1085458D03*
X341343Y1075891D03*
X345043Y1101403D03*
X350595Y1104592D03*
X346894Y1091836D03*
X345043Y1095025D03*
X350595Y1098214D03*
X346894D03*
Y1104592D03*
X350595Y1091836D03*
X339492Y1104592D03*
X337642Y1095025D03*
X339492Y1098214D03*
X337642Y1101403D03*
X339492Y1091836D03*
X341343Y1095025D03*
X343193Y1104592D03*
X346894Y1110970D03*
X345043Y1114159D03*
X350595Y1117348D03*
X346894D03*
X345043Y1107781D03*
X350595Y1110970D03*
X337642Y1114159D03*
X339492Y1117348D03*
X337642Y1107781D03*
X339492Y1110970D03*
X341343Y1114159D03*
X345043Y1120537D03*
X350595Y1123726D03*
X346894Y1130103D03*
X345043Y1133293D03*
Y1126915D03*
X346894Y1123726D03*
X350595Y1130103D03*
X337642Y1120537D03*
X339492Y1123726D03*
X337642Y1133293D03*
Y1126915D03*
X339492Y1130103D03*
X343193Y1123726D03*
X341343Y1133293D03*
X350595Y1136481D03*
X346894D03*
X345043Y1139670D03*
X350595Y1142859D03*
X346894Y1149237D03*
X345043Y1146048D03*
X346894Y1142859D03*
X350595Y1149237D03*
X339492Y1136481D03*
X337642Y1139670D03*
X339492Y1142859D03*
X337642Y1146048D03*
X339492Y1149237D03*
X343193Y1142859D03*
X345043Y1152426D03*
X350595Y1155615D03*
X337642Y1152426D03*
X339492Y1161993D03*
X341343Y1165182D03*
X350595Y1161993D03*
X341343Y1152426D03*
X345043Y1158804D03*
X339839Y1516970D03*
X344563D03*
X349288D03*
X336689Y1519698D03*
X341414D03*
X346138D03*
X350862D03*
X339839Y1530608D03*
X344563D03*
X349288D03*
X336689Y1533336D03*
X341414D03*
X346138D03*
X350862D03*
X364217Y876435D03*
X358665Y879624D03*
X351264Y892380D03*
X358665Y886002D03*
X364217Y889191D03*
X356815D03*
X362366Y892380D03*
X356815Y895569D03*
X364217D03*
X358665Y892380D03*
X351264Y911513D03*
Y905135D03*
Y898758D03*
X356815Y908325D03*
X362366Y911513D03*
X358665Y898758D03*
X364217Y901947D03*
X356815D03*
X362366Y905135D03*
X358665D03*
X364217Y908325D03*
X358665Y911513D03*
X362366Y898758D03*
X351264Y924269D03*
Y917891D03*
X358665D03*
X364217Y921080D03*
X356815D03*
X362366Y924269D03*
X358665D03*
X356815Y914702D03*
X364217D03*
X362366Y917891D03*
X351264Y930647D03*
Y937025D03*
X364217Y927458D03*
X356815D03*
X362366Y930647D03*
X358665Y937025D03*
X364217Y940214D03*
X356815D03*
Y933836D03*
X364217D03*
X358665Y930647D03*
X362366Y937025D03*
X351264Y943403D03*
Y949781D03*
Y956159D03*
X362366Y943403D03*
X358665D03*
X364217Y946592D03*
X356815D03*
X362366Y949781D03*
X358665Y956159D03*
X356815Y952970D03*
X364217D03*
X358665Y949781D03*
X362366Y956159D03*
X351264Y968915D03*
Y962537D03*
X358665D03*
X364217Y965726D03*
X356815D03*
X362366Y968915D03*
X364217Y959348D03*
X356815D03*
X362366Y962537D03*
X358665Y968915D03*
X351264Y981671D03*
Y975293D03*
X364217Y984860D03*
X358665Y975293D03*
X364217Y978482D03*
X356815D03*
X362366Y981671D03*
X356815Y972104D03*
X364217D03*
X362366Y975293D03*
X351264Y988049D03*
Y1000805D03*
Y994427D03*
X362366Y988049D03*
X358665Y994427D03*
X356815Y997616D03*
X364217D03*
X362366Y1000805D03*
X358665D03*
X356815Y991238D03*
X362366Y994427D03*
X364217Y991238D03*
X358666Y988049D03*
X351264Y1007183D03*
X356815Y1010372D03*
X358665Y1007183D03*
X356815Y1003994D03*
X364217D03*
X362366Y1007183D03*
X364217Y1010372D03*
X365398Y1028056D03*
X357996D03*
X352445Y1031245D03*
Y1037623D03*
X363547Y1031245D03*
X365398Y1034434D03*
X357996D03*
X359847Y1037623D03*
X363547D03*
X365398Y1040812D03*
X357996D03*
X359847Y1044001D03*
X363547D03*
X359847Y1031245D03*
X352445Y1044001D03*
Y1050379D03*
X363547D03*
X357996Y1059946D03*
X365398Y1047190D03*
X359847Y1050379D03*
X357996Y1053568D03*
X359847Y1056757D03*
X357996Y1047190D03*
X365398Y1053568D03*
X352445Y1063135D03*
Y1069513D03*
X357996Y1072702D03*
X363547Y1063135D03*
X359847D03*
X365398Y1066324D03*
X363547Y1069513D03*
X359847D03*
X365398Y1072702D03*
X357996Y1066324D03*
X352445Y1075891D03*
Y1082269D03*
Y1088647D03*
X363547Y1075891D03*
X359847D03*
X365398Y1079080D03*
X357996D03*
X363547Y1082269D03*
X359847D03*
X365398Y1085458D03*
X359847Y1088647D03*
X363547D03*
X357996Y1085458D03*
X352445Y1095025D03*
Y1101403D03*
X359847D03*
X365398Y1104592D03*
X357996Y1091836D03*
X363547Y1095025D03*
X359847D03*
X365398Y1098214D03*
X357996D03*
X363547Y1101403D03*
X357996Y1104592D03*
X365398Y1091836D03*
X352445Y1114159D03*
Y1107781D03*
X357996Y1110970D03*
X363547Y1114159D03*
X359847D03*
X365398Y1117348D03*
X357996D03*
X359847Y1107781D03*
X363547D03*
X365398Y1110970D03*
X352445Y1120537D03*
Y1133293D03*
Y1126915D03*
X363547Y1120537D03*
X359847D03*
X365398Y1123726D03*
X357996Y1130103D03*
X363547Y1133293D03*
X359847D03*
Y1126915D03*
X363547D03*
X357996Y1123726D03*
X365398Y1130103D03*
X352445Y1139670D03*
Y1146048D03*
X365398Y1136481D03*
X357996D03*
X363547Y1139670D03*
X359847D03*
X365398Y1142859D03*
X357996Y1149237D03*
X359847Y1146048D03*
X363547D03*
X357996Y1142859D03*
X365398Y1149237D03*
X352445Y1152426D03*
X363547D03*
X359847D03*
X357996Y1155615D03*
X359847Y1165182D03*
X357996Y1161993D03*
X352445Y1165182D03*
X365398Y1161993D03*
X363461Y1516970D03*
X354012D03*
X358736D03*
X365036Y1519698D03*
X355587D03*
X360311D03*
X363461Y1530608D03*
X354012D03*
X358736D03*
X365036Y1533336D03*
X355587D03*
X360311D03*
X367917Y876435D03*
X371618D03*
X379020D03*
X369768Y873246D03*
X373469D03*
X377169D03*
X371618Y882813D03*
X375319D03*
X379020Y889191D03*
X367917Y895569D03*
X366067Y905135D03*
X379020Y901947D03*
X366067Y924269D03*
X367917Y914702D03*
X379020D03*
X367917Y933836D03*
X379020Y927458D03*
X366067Y943403D03*
X367917Y952970D03*
X379020Y946592D03*
X366067Y962537D03*
X379020Y959348D03*
X366067Y981671D03*
X367917Y972104D03*
X379020D03*
X366067Y1000805D03*
X367917Y991238D03*
X375319D03*
X369768Y988049D03*
X379020Y1010372D03*
X375319D03*
X369099Y1028056D03*
X376500D03*
X372799D03*
X367248Y1037623D03*
X378351Y1044001D03*
X370949Y1031245D03*
X367248Y1056757D03*
X369099Y1047190D03*
X370949Y1056757D03*
X372799Y1047190D03*
X376500Y1053568D03*
X369099Y1066324D03*
X380201D03*
X367248Y1075891D03*
X369099Y1085458D03*
X380201Y1079080D03*
Y1091836D03*
X367248Y1095025D03*
X369099Y1104592D03*
X367248Y1114159D03*
X380201Y1110970D03*
X369099Y1123726D03*
X367248Y1133293D03*
X380201Y1123726D03*
Y1149237D03*
X369099Y1142859D03*
X380201Y1136481D03*
X378351Y1165182D03*
X374650D03*
X367248Y1158804D03*
X370949D03*
X369099Y1161993D03*
X372799D03*
X380201D03*
X367248Y1152426D03*
X368185Y1516970D03*
X372910D03*
X377634D03*
X369760Y1519698D03*
X374484D03*
X379209D03*
X368185Y1530608D03*
X372910D03*
X377634D03*
X369760Y1533336D03*
X374484D03*
X379209D03*
X393823Y876435D03*
X382721D03*
X390122D03*
X380870Y879624D03*
X384571D03*
X380870Y873246D03*
X391973D03*
X395673D03*
Y879624D03*
X391973D03*
Y886002D03*
X393823Y895569D03*
X380870Y886002D03*
X382721Y895569D03*
X390122Y889191D03*
X386421Y895569D03*
X395673Y886002D03*
Y911513D03*
X393823Y908325D03*
X386421D03*
X382721D03*
X388272Y924269D03*
Y917891D03*
X384571Y924269D03*
Y917891D03*
X395673Y924269D03*
Y917891D03*
X393823Y921080D03*
X382721D03*
X386421D03*
X388272Y930647D03*
X384571D03*
X395673D03*
X393823Y940214D03*
X382721D03*
X386421D03*
X380870Y937025D03*
X395673D03*
X388272D03*
X391973D03*
X384571D03*
Y949781D03*
Y943403D03*
Y956159D03*
X395673Y949781D03*
Y943403D03*
Y956159D03*
X388272Y949781D03*
Y943403D03*
Y956159D03*
X393823Y952970D03*
X382721D03*
X386421D03*
X393823Y965726D03*
X382721D03*
X386421D03*
X395673Y962537D03*
Y968915D03*
X384571Y962537D03*
Y968915D03*
X388272Y962537D03*
Y968915D03*
X380870Y981671D03*
X382721Y984860D03*
X388272Y981671D03*
X390122Y984860D03*
X386421Y978482D03*
X393823D03*
X395673Y981671D03*
X382721Y978482D03*
X395673Y975293D03*
X384571D03*
X388272D03*
X395673Y994427D03*
Y988049D03*
Y1000805D03*
X380870Y988049D03*
Y994427D03*
X382721Y997616D03*
Y991238D03*
X380870Y1000805D03*
X388272Y994427D03*
X390122Y997616D03*
X388272Y988049D03*
X390122Y991238D03*
X388272Y1000805D03*
X380870Y1007183D03*
X382721Y1003994D03*
X388272Y1007183D03*
X390122Y1003994D03*
X393823Y1010372D03*
X386421D03*
X391303Y1028056D03*
X383902D03*
X382051Y1031245D03*
Y1037623D03*
Y1044001D03*
X391303Y1034434D03*
X389453Y1037623D03*
X391303Y1040812D03*
X389453Y1044001D03*
Y1031245D03*
X383902Y1040812D03*
Y1034434D03*
X395004Y1059946D03*
X383902D03*
X387603D03*
X389453Y1056757D03*
X382051Y1050379D03*
X391303Y1047190D03*
X383902D03*
X391303Y1053568D03*
X389453Y1050379D03*
X383902Y1053568D03*
X385752Y1056757D03*
X382051D03*
X385752Y1069513D03*
Y1063135D03*
X389453Y1069513D03*
Y1063135D03*
X395004Y1072702D03*
X383902D03*
X387603D03*
X385752Y1075891D03*
X389453D03*
X385752Y1088647D03*
Y1082269D03*
X389453Y1088647D03*
Y1082269D03*
X395004Y1085458D03*
X383902D03*
X387603D03*
X385752Y1095025D03*
X389453D03*
X395004Y1098214D03*
X383902D03*
X387603D03*
X382051Y1101403D03*
X393154D03*
X389453D03*
X385752D03*
X389453Y1114159D03*
Y1107781D03*
X385752Y1114159D03*
Y1107781D03*
X395004Y1117348D03*
X387603D03*
X383902D03*
X389453Y1120537D03*
X385752D03*
X389453Y1126915D03*
Y1133293D03*
X385752Y1126915D03*
Y1133293D03*
X395004Y1130103D03*
X387603D03*
X383902D03*
X389453Y1139670D03*
Y1146048D03*
X385752Y1139670D03*
Y1146048D03*
X395004Y1142859D03*
X387603D03*
X383902D03*
X391303Y1149237D03*
X382051Y1152426D03*
X383902Y1161993D03*
X391303D03*
X395004D03*
X393154Y1152426D03*
X393483Y1507355D03*
X391383D03*
X382359Y1516970D03*
X387083D03*
X383933Y1519698D03*
X388658D03*
X394890Y1514073D03*
X394834Y1516336D03*
X382359Y1530608D03*
X387083D03*
X383933Y1533336D03*
X388658D03*
X395185Y1536640D03*
Y1534540D03*
X395186Y1531618D03*
X395097Y1528698D03*
X394600Y1538658D03*
X404925Y876435D03*
X401225D03*
X403075Y879624D03*
X406776D03*
X403075Y873246D03*
X397524Y895569D03*
X403075Y886002D03*
X401225Y889191D03*
X408626Y895569D03*
X404925D03*
X406776Y886002D03*
X410477D03*
X399374D03*
Y911513D03*
X410477D03*
X406776D03*
X397524Y908325D03*
X408626D03*
X404925Y908324D03*
X399374Y924269D03*
Y917891D03*
X410477D03*
Y924269D03*
X406776Y917891D03*
Y924269D03*
X397524Y921080D03*
X408626D03*
X404925D03*
X399374Y930647D03*
X397524Y940214D03*
X410477Y930647D03*
X406776D03*
X408626Y940214D03*
X404925D03*
X403075Y937025D03*
X404925Y933836D03*
X410477Y937025D03*
X408626Y933836D03*
X399374Y937025D03*
X406776D03*
Y949781D03*
Y943403D03*
Y956159D03*
X399374Y949781D03*
Y943403D03*
Y956159D03*
X410477Y949781D03*
Y943403D03*
Y956159D03*
X397524Y952970D03*
X408626D03*
X404925D03*
X397524Y965726D03*
X408626D03*
X404925D03*
X406776Y962537D03*
Y968915D03*
X399374Y962537D03*
Y968915D03*
X410477Y962537D03*
Y968915D03*
X397524Y978482D03*
Y984860D03*
X404925Y978482D03*
X408626D03*
X410477Y981671D03*
X403075D03*
X404925Y984860D03*
X406776Y975293D03*
X399374D03*
X410477D03*
X397524Y991238D03*
X410477Y988049D03*
X403075D03*
X404925Y991238D03*
X397524Y997616D03*
X403075Y994427D03*
Y1000805D03*
X401225Y1010372D03*
X397524Y1003994D03*
X406763Y1007175D03*
X403075Y1007183D03*
X406094Y1028064D03*
X402406Y1028056D03*
X406104Y1040820D03*
X404256Y1044001D03*
X398705Y1040812D03*
X406094Y1034442D03*
X404256Y1037623D03*
Y1031245D03*
X402406Y1034434D03*
X396855Y1044001D03*
Y1031245D03*
Y1037623D03*
X398705Y1047190D03*
X406107D03*
X404256Y1050379D03*
X398705Y1059946D03*
Y1053568D03*
X396855Y1050379D03*
Y1056757D03*
X409807Y1059946D03*
X406107D03*
Y1053568D03*
X404256Y1056757D03*
X396855Y1069513D03*
Y1063135D03*
X407957Y1069513D03*
Y1063135D03*
X400555Y1069513D03*
Y1063135D03*
X398705Y1072702D03*
X406107D03*
X409807D03*
X396855Y1075891D03*
X407957D03*
X400555D03*
X396855Y1088647D03*
Y1082269D03*
X407957Y1088647D03*
Y1082269D03*
X400555Y1088647D03*
Y1082269D03*
X398705Y1085458D03*
X406107D03*
X409807D03*
X396855Y1095025D03*
X407957D03*
X400555D03*
X398705Y1098214D03*
X406107D03*
X409807D03*
Y1104592D03*
X407957Y1101403D03*
X404256D03*
X396855D03*
X406107Y1104592D03*
X400555Y1101403D03*
Y1114159D03*
Y1107781D03*
X396855Y1114159D03*
Y1107781D03*
X407957Y1114159D03*
X398705Y1117348D03*
X407957Y1107781D03*
X406107Y1117348D03*
X409807D03*
X400555Y1120537D03*
Y1126915D03*
X396855Y1120537D03*
Y1126915D03*
X407957Y1120537D03*
Y1126915D03*
X400555Y1133293D03*
X396855D03*
X407957D03*
X398705Y1130103D03*
X406107D03*
X409807D03*
X400555Y1139670D03*
Y1146048D03*
X396855Y1139670D03*
Y1146048D03*
X407957Y1139670D03*
Y1146048D03*
X398705Y1142859D03*
X406107D03*
X409807D03*
X402406Y1149237D03*
X404256Y1152426D03*
X406107Y1161993D03*
X402406D03*
X416028Y876435D03*
X412327D03*
X423429D03*
X414177Y873246D03*
X412327Y889191D03*
X425280Y886002D03*
X423429Y889191D03*
X419729Y895569D03*
X416028D03*
X414177Y886002D03*
X421579Y911513D03*
X417878D03*
X419729Y908325D03*
X416028D03*
X421579Y917891D03*
Y924269D03*
X417878Y917891D03*
Y924269D03*
X416028Y921080D03*
X419729D03*
X417878Y937025D03*
X421579D03*
X417878Y930647D03*
X421579D03*
X416028Y940214D03*
X419729D03*
X417878Y943403D03*
Y956159D03*
Y949781D03*
X421579Y943403D03*
Y956159D03*
Y949781D03*
X416028Y952970D03*
X419729D03*
Y965726D03*
X416028D03*
X417878Y962537D03*
Y968915D03*
X421579Y962537D03*
Y968915D03*
X412327Y984860D03*
X416028Y978482D03*
X419729D03*
X425280Y981671D03*
X417878D03*
X419729Y984860D03*
X417878Y975293D03*
X421579D03*
X417878Y988049D03*
X425280D03*
X412315Y997608D03*
X412327Y991238D03*
X419716Y997608D03*
X419729Y991238D03*
X413496Y1040820D03*
X420897D03*
X413508Y1047190D03*
X420910D03*
X419059Y1050379D03*
X411658D03*
X413508Y1053568D03*
X411658Y1056757D03*
X420910Y1053568D03*
X419059Y1056757D03*
X417209Y1059946D03*
X420910D03*
X419059Y1063135D03*
Y1069513D03*
X422760Y1063135D03*
X411658Y1069513D03*
Y1063135D03*
X422760Y1069513D03*
X417209Y1072702D03*
X420910D03*
X419059Y1075891D03*
X422760D03*
X411658D03*
X419059Y1082269D03*
Y1088647D03*
X422760Y1082269D03*
X411658Y1088647D03*
Y1082269D03*
X422760Y1088647D03*
X417209Y1085458D03*
X420910D03*
X419059Y1095025D03*
Y1101403D03*
X422760Y1095025D03*
Y1101403D03*
X411658Y1095025D03*
X420910Y1098214D03*
X417209D03*
X411658Y1101403D03*
X422760Y1114159D03*
X411658D03*
X419059D03*
X411658Y1107781D03*
X422760D03*
X419059D03*
X420910Y1117348D03*
X417209D03*
X422760Y1120537D03*
Y1126915D03*
X411658Y1120537D03*
Y1126915D03*
X419059Y1120537D03*
Y1126915D03*
X422760Y1133293D03*
X411658D03*
X419059D03*
X420910Y1130103D03*
X417209D03*
X422760Y1139670D03*
Y1146048D03*
X411658Y1139670D03*
Y1146048D03*
X419059Y1139670D03*
Y1146048D03*
X417209Y1142859D03*
X420910D03*
X413508Y1149237D03*
X424610D03*
Y1161993D03*
X415358Y1152426D03*
X413508Y1161993D03*
X417209D03*
X427130Y876435D03*
X428981Y892380D03*
X432681D03*
X428981Y911513D03*
X432681D03*
X428981Y898758D03*
X432681D03*
X430831Y914702D03*
Y921080D03*
X427130Y914702D03*
Y921080D03*
X428981Y924269D03*
X432681D03*
X430831Y927458D03*
X427130D03*
Y940214D03*
X430831D03*
X427130Y933836D03*
X430831D03*
X427130Y946592D03*
Y952970D03*
X430831Y946592D03*
Y952970D03*
X428981Y943403D03*
Y956159D03*
X432681Y943403D03*
Y956159D03*
X428981Y968915D03*
X432681D03*
X427130Y959348D03*
Y965726D03*
X430831Y959348D03*
Y965726D03*
X427130Y984860D03*
X432681Y981671D03*
X434532Y984860D03*
X427130Y978482D03*
Y972104D03*
X430831Y978482D03*
Y972104D03*
X432681Y988049D03*
X434532Y991238D03*
X427118Y997608D03*
X427130Y991238D03*
X434519Y997608D03*
X428299Y1040820D03*
X428311Y1059946D03*
X432012D03*
X428311Y1047190D03*
X435713D03*
X433862Y1050379D03*
X426461D03*
Y1056757D03*
X428311Y1053568D03*
X433862Y1056757D03*
X435713Y1053568D03*
X428311Y1072702D03*
Y1066324D03*
X432012Y1072702D03*
Y1066324D03*
X430162Y1069513D03*
X433862D03*
X428311Y1079080D03*
X432012D03*
X428311Y1085458D03*
X432012D03*
X430162Y1082269D03*
X433862D03*
X428311Y1098214D03*
Y1091836D03*
X432012Y1098214D03*
Y1091836D03*
X430162Y1095025D03*
X428311Y1104592D03*
X433862Y1095025D03*
X432012Y1104592D03*
Y1117348D03*
Y1110970D03*
X428311Y1117348D03*
Y1110970D03*
X430162Y1114159D03*
X433862D03*
X432012Y1123726D03*
X428311D03*
X432012Y1130103D03*
X428311D03*
X430162Y1126915D03*
X433862D03*
X432012Y1142859D03*
Y1136481D03*
X428311Y1142859D03*
Y1136481D03*
X430162Y1139670D03*
Y1146048D03*
X433862Y1139670D03*
Y1146048D03*
Y1158804D03*
X432012Y1161993D03*
X428311D03*
X426461Y1152426D03*
X430162D03*
X433862D03*
X432012Y1155615D03*
X426461Y1158804D03*
X428311Y1155615D03*
X454861Y873246D03*
X453011Y876435D03*
X449310D03*
X451160Y879624D03*
X454861D03*
X451160Y873246D03*
X449310Y895569D03*
X453011D03*
X451160Y886002D03*
X454861D03*
X451160Y892380D03*
X447460D03*
Y886002D03*
X449310Y882813D03*
Y908325D03*
Y901947D03*
X453011Y908325D03*
Y901947D03*
X451160Y911513D03*
X447460D03*
X451160Y898758D03*
X447460D03*
X449310Y921080D03*
Y914702D03*
X453011Y921080D03*
Y914702D03*
X451160Y924269D03*
X447460D03*
X453011Y940214D03*
X449310D03*
Y927458D03*
X453011D03*
X449310Y933836D03*
X453011D03*
Y952970D03*
Y946592D03*
X449310Y952970D03*
Y946592D03*
X451160Y943403D03*
Y956159D03*
X447460Y943403D03*
Y956159D03*
X453011Y959348D03*
Y965726D03*
X449310Y959348D03*
Y965726D03*
X451160Y968915D03*
X447460D03*
X453011Y978482D03*
Y972104D03*
X449310Y978482D03*
Y972104D03*
X451160Y981671D03*
X449310Y984860D03*
X449323Y997608D03*
X451160Y988049D03*
X449310Y991238D03*
X454192Y1059946D03*
X450491D03*
Y1047190D03*
X452341Y1056757D03*
X450491Y1053568D03*
X452341Y1050379D03*
X454192Y1066324D03*
Y1072702D03*
X450491Y1066324D03*
Y1072702D03*
X448641Y1069513D03*
X452341D03*
X454192Y1079080D03*
X450491D03*
X454192Y1085458D03*
X450491D03*
X448641Y1082269D03*
X452341D03*
X454192Y1091836D03*
Y1098214D03*
X450491Y1091836D03*
Y1098214D03*
X448641Y1095025D03*
X452341D03*
X450491Y1104592D03*
X454192D03*
X450491Y1110970D03*
Y1117348D03*
X454192Y1110970D03*
Y1117348D03*
X448641Y1114159D03*
X452341D03*
X450491Y1123726D03*
X454192D03*
X450491Y1130103D03*
X454192D03*
X448641Y1126915D03*
X452341D03*
X450491Y1136481D03*
Y1142859D03*
X454192Y1136481D03*
Y1142859D03*
X448641Y1139670D03*
X452341D03*
X448641Y1146048D03*
X452341D03*
X450491Y1161993D03*
X452341Y1165182D03*
X454192Y1161993D03*
X452341Y1152426D03*
X448640Y1165182D03*
X448641Y1158804D03*
X452341D03*
X450491Y1155615D03*
X444953Y1507509D03*
X442753D03*
X452328Y1516970D03*
X453903Y1519698D03*
X442918Y1513218D03*
X441660Y1521612D03*
X441259Y1518121D03*
X452328Y1530608D03*
X453903Y1533336D03*
X441706Y1535698D03*
Y1537898D03*
X443153Y1540317D03*
X447224Y1544625D03*
X462263Y879624D03*
X458562D03*
Y873246D03*
X462263D03*
X456712Y876435D03*
X467814D03*
X464113D03*
X465964Y879624D03*
Y873246D03*
X458562Y892380D03*
X469664D03*
X462263D03*
X460412Y882813D03*
X464113D03*
X469664Y886002D03*
X456712Y889191D03*
X460412Y895569D03*
X465964Y886002D03*
X467814Y889191D03*
X464113Y895569D03*
X462263Y886002D03*
X458562D03*
X456712Y882813D03*
X458562Y905135D03*
Y898758D03*
X469664Y905135D03*
Y898758D03*
X462263Y905135D03*
Y898758D03*
X458562Y911513D03*
X469664D03*
X462263D03*
X460412Y908325D03*
X464113D03*
X458562Y924269D03*
Y917891D03*
X469664Y924269D03*
Y917891D03*
X462263Y924269D03*
Y917891D03*
X460412Y921080D03*
X464113D03*
X462263Y937025D03*
X458562D03*
X462263Y930647D03*
X458562D03*
X460412Y940214D03*
X469664Y930647D03*
X464113Y940214D03*
X465964Y930647D03*
X469664Y937025D03*
X462263Y956159D03*
Y943403D03*
Y949781D03*
X458562Y956159D03*
Y943403D03*
Y949781D03*
X469664Y956159D03*
Y943403D03*
Y949781D03*
X460412Y952970D03*
X464113D03*
X462263Y962537D03*
Y968915D03*
X458562Y962537D03*
Y968915D03*
X469664Y962537D03*
Y968915D03*
X460412Y965726D03*
X464113D03*
X462263Y975293D03*
X458562D03*
X469664D03*
X460412Y978482D03*
X458562Y981671D03*
X456712Y984860D03*
X464113Y978482D03*
X465964Y981671D03*
X464113Y984860D03*
X458562Y988049D03*
X456724Y997608D03*
X456712Y991238D03*
X464126Y997608D03*
X465964Y988049D03*
X464113Y991238D03*
X457905Y1040820D03*
X465307D03*
X457893Y1047190D03*
X465294D03*
X459743Y1050379D03*
X465294Y1053568D03*
X467145Y1056757D03*
Y1050379D03*
X457893Y1053568D03*
X461593Y1059946D03*
X459743Y1056757D03*
X465294Y1059946D03*
X463444Y1063135D03*
Y1069513D03*
X459743Y1063135D03*
Y1069513D03*
X461593Y1072702D03*
X465294D03*
X463444Y1075891D03*
X459743D03*
X463444Y1082269D03*
Y1088647D03*
X459743Y1082269D03*
Y1088647D03*
X461593Y1085458D03*
X465294D03*
X463444Y1101403D03*
Y1095025D03*
X459743Y1101403D03*
Y1095025D03*
X461593Y1098214D03*
X465294D03*
X459743Y1114159D03*
X463444D03*
X459743Y1107781D03*
X461593Y1117348D03*
X463444Y1107781D03*
X465294Y1117348D03*
X459743Y1126915D03*
Y1120537D03*
X463444Y1126915D03*
Y1120537D03*
X459743Y1133293D03*
X463444D03*
X461593Y1130103D03*
X465294D03*
X459743Y1146048D03*
Y1139670D03*
X463444Y1146048D03*
Y1139670D03*
X461593Y1142859D03*
X457893Y1149237D03*
X465294Y1142859D03*
X468995Y1149237D03*
X467145Y1165182D03*
X468995Y1161993D03*
X465294D03*
X467145Y1152426D03*
X457893Y1161993D03*
X456042Y1152426D03*
X459743Y1165182D03*
X456042Y1158804D03*
X457893Y1155615D03*
X456042Y1165182D03*
X461593Y1161993D03*
Y1155615D03*
X463444Y1152426D03*
Y1158804D03*
X467145D03*
X468995Y1155615D03*
X463444Y1165182D03*
X457052Y1516970D03*
X461777D03*
X466501D03*
X458627Y1519698D03*
X463351D03*
X468076D03*
X457052Y1530608D03*
X461777D03*
X466501D03*
X458627Y1533336D03*
X463351D03*
X468076D03*
X484467Y873246D03*
X473365D03*
X477066D03*
X484467Y879624D03*
X477066D03*
X473365D03*
X475215Y876435D03*
X478916D03*
X480767Y892380D03*
X484467D03*
X473365D03*
X484467Y886002D03*
X480767D03*
X473365D03*
X477066D03*
X475215Y895569D03*
X471515D03*
X478916Y889191D03*
X482617Y895569D03*
X480767Y898758D03*
Y905135D03*
X484467Y898758D03*
X473365Y905135D03*
Y898758D03*
X484467Y905135D03*
X480767Y911513D03*
X484467D03*
X473365D03*
X475215Y908325D03*
X471515D03*
X482617D03*
X480767Y917891D03*
Y924269D03*
X484467Y917891D03*
Y924269D03*
X473365D03*
Y917891D03*
X475215Y921080D03*
X471515D03*
X482617D03*
X480767Y930647D03*
X484467D03*
X473365D03*
X471515Y940214D03*
X475215D03*
X482617D03*
X477066Y937025D03*
X480767D03*
X475215Y933836D03*
X471515D03*
X484467Y937025D03*
X473365D03*
X484467Y956159D03*
Y943403D03*
Y949781D03*
X473365Y956159D03*
Y943403D03*
Y949781D03*
X480767Y956159D03*
Y943403D03*
Y949781D03*
X475215Y952970D03*
X471515D03*
X482617D03*
X484467Y962537D03*
Y968915D03*
X473365Y962537D03*
Y968915D03*
X480767Y962537D03*
Y968915D03*
X475215Y965726D03*
X471515D03*
X482617D03*
X484467Y975293D03*
X473365D03*
X480767D03*
X475215Y978482D03*
X471515D03*
X473365Y981671D03*
X471515Y984860D03*
X478916D03*
X482617Y978482D03*
X480767Y981671D03*
X473365Y988049D03*
X471527Y997608D03*
X471515Y991238D03*
X478916Y997616D03*
Y991238D03*
X480767Y994427D03*
Y988049D03*
Y1000805D03*
X478916Y1003994D03*
Y1010372D03*
X480767Y1007183D03*
X483798Y1028056D03*
X472708Y1040820D03*
X481948Y1044001D03*
Y1037623D03*
X480097Y1040812D03*
X483798Y1034434D03*
X478247Y1031245D03*
X472696Y1047190D03*
X480097D03*
X474546Y1050379D03*
Y1056757D03*
X472696Y1053568D03*
Y1059946D03*
X476397D03*
X483798D03*
X481948Y1056757D03*
X480097Y1053568D03*
X481948Y1050379D03*
X474546Y1063135D03*
Y1069513D03*
X481948Y1063135D03*
Y1069513D03*
X470845Y1063135D03*
Y1069513D03*
X476397Y1072702D03*
X472696D03*
X483798D03*
X474546Y1075891D03*
X481948D03*
X470845D03*
X474546Y1082269D03*
Y1088647D03*
X481948Y1082269D03*
Y1088647D03*
X470845Y1082269D03*
Y1088647D03*
X472696Y1085458D03*
X476397D03*
X483798D03*
X474546Y1095025D03*
X481948D03*
X470845D03*
X472696Y1098214D03*
X476397D03*
X483798D03*
X478247Y1101403D03*
X472696Y1104592D03*
X481948Y1101403D03*
X476397Y1104592D03*
X470845Y1101403D03*
X474546D03*
X481948Y1114159D03*
X470845D03*
X481948Y1107781D03*
X474546Y1114159D03*
X470845Y1107781D03*
X474546D03*
X476397Y1117348D03*
X472696D03*
X483798D03*
X481948Y1126915D03*
Y1120537D03*
X470845Y1126915D03*
Y1120537D03*
X474546Y1126915D03*
Y1120537D03*
X470845Y1133293D03*
X481948D03*
X474546D03*
X472696Y1130103D03*
X483798D03*
X476396D03*
X481948Y1146048D03*
Y1139670D03*
X470845Y1146048D03*
Y1139670D03*
X474546Y1146048D03*
Y1139670D03*
X472696Y1142859D03*
X476397D03*
X483798D03*
X480097Y1149237D03*
X483798Y1155615D03*
X480097Y1161993D03*
X476397D03*
X478247Y1152426D03*
X470846Y1165182D03*
X481948D03*
X483798Y1161993D03*
X472696Y1155615D03*
X481948Y1152426D03*
X478247Y1158804D03*
X474546D03*
X478247Y1165182D03*
X480097Y1155615D03*
X474546Y1165182D03*
X470845Y1152426D03*
X472696Y1161993D03*
X471225Y1516970D03*
X475950D03*
X480674D03*
X472800Y1519698D03*
X477525D03*
X482249D03*
X471225Y1530608D03*
X475950D03*
X480674D03*
X472800Y1533336D03*
X477525D03*
X482249D03*
X499271Y879624D03*
X488168Y873246D03*
Y879624D03*
X486318Y876435D03*
X490019D03*
X497420D03*
X495570Y879624D03*
X491869Y892380D03*
X495570D03*
Y886002D03*
X491869D03*
X488168D03*
X490019Y889191D03*
X493719Y895569D03*
X486318D03*
X499271Y886002D03*
X497420Y895569D03*
Y882813D03*
X491869Y905135D03*
Y898758D03*
Y911513D03*
X495570Y905135D03*
Y898758D03*
Y911513D03*
X493719Y908325D03*
X486318D03*
X497420D03*
X491869Y917891D03*
Y924269D03*
X495570Y917891D03*
Y924269D03*
X493719Y921080D03*
X486318D03*
X497420D03*
X491869Y930647D03*
X495570D03*
X493719Y940214D03*
X486318D03*
X497420D03*
X499271Y937025D03*
X488168D03*
X491869D03*
X495570D03*
Y956159D03*
Y943403D03*
Y949781D03*
X491869Y956159D03*
Y943403D03*
Y949781D03*
X486318Y952970D03*
X493719D03*
X497420D03*
X495570Y962537D03*
Y968915D03*
X491869Y962537D03*
Y968915D03*
X493719Y965726D03*
X486318D03*
X497420D03*
X495570Y975293D03*
X491869D03*
X493719Y978482D03*
X486318D03*
X488168Y981671D03*
X493719Y984860D03*
X486318D03*
X495570Y981671D03*
X497420Y978482D03*
X488168Y988049D03*
Y994427D03*
X486318Y997616D03*
X493719D03*
X486318Y991238D03*
X493719D03*
X488168Y1000805D03*
X495570Y994427D03*
Y988049D03*
Y1000805D03*
X488168Y1007183D03*
X486318Y1003994D03*
Y1010372D03*
X493719Y1003994D03*
Y1010372D03*
X495570Y1007183D03*
X491200Y1028056D03*
X498601D03*
X494901Y1040812D03*
X489349Y1044001D03*
X487499Y1040812D03*
X489349Y1037623D03*
X496751Y1044001D03*
Y1037623D03*
X485649Y1031245D03*
X493050D03*
X491200Y1034434D03*
X498601D03*
X496751Y1050379D03*
X494901Y1047190D03*
X487499D03*
X489349Y1050379D03*
X494901Y1059946D03*
Y1053568D03*
X487499Y1059946D03*
X489349Y1056757D03*
X487499Y1053568D03*
X496751Y1056757D03*
X498601Y1059946D03*
X485649Y1063135D03*
Y1069513D03*
X496751Y1063135D03*
Y1069513D03*
X493050Y1063135D03*
Y1069513D03*
X494901Y1072702D03*
X487499D03*
X498601D03*
X485649Y1075891D03*
X496751D03*
X493050D03*
X485649Y1082269D03*
Y1088647D03*
X496751Y1082269D03*
Y1088647D03*
X493050Y1082269D03*
Y1088647D03*
X494901Y1085458D03*
X487499D03*
X498601D03*
X485649Y1095025D03*
X496751D03*
X493050D03*
X494901Y1098214D03*
X487499D03*
X498601D03*
X493050Y1101403D03*
X485649D03*
X489349D03*
X493050Y1107781D03*
Y1114159D03*
X485649D03*
X496751Y1107781D03*
Y1114159D03*
X485649Y1107781D03*
X494901Y1117348D03*
X487499D03*
X498601D03*
X493050Y1120537D03*
X485649Y1126915D03*
Y1120537D03*
X496751D03*
X493050Y1133293D03*
Y1126915D03*
X496751Y1133293D03*
Y1126915D03*
X485649Y1133293D03*
X487499Y1130103D03*
X494901D03*
X498601D03*
X493050Y1146048D03*
Y1139670D03*
X485649Y1146048D03*
Y1139670D03*
X496751Y1146048D03*
Y1139670D03*
X494901Y1142859D03*
X487499D03*
X491200Y1149237D03*
X498601Y1142859D03*
Y1161993D03*
X487499D03*
X491200D03*
X489349Y1152426D03*
X493050Y1165182D03*
X485649Y1158804D03*
Y1165182D03*
X496751D03*
Y1158804D03*
X489349D03*
X491200Y1155615D03*
X493050Y1152426D03*
X494901Y1161993D03*
Y1155615D03*
X489349Y1165182D03*
X499572Y1516970D03*
X485399D03*
X490123D03*
X494847D03*
X486973Y1519698D03*
X491698D03*
X496422D03*
X499572Y1530608D03*
X485399D03*
X490123D03*
X494847D03*
X486973Y1533336D03*
X491698D03*
X496422D03*
X510373Y879624D03*
X514074D03*
X508523Y876435D03*
X506672Y879624D03*
X512223Y876435D03*
X501121D03*
Y889191D03*
X512223Y895569D03*
X501121Y882813D03*
X514074Y905135D03*
X501121Y901947D03*
X512223Y914702D03*
X514074Y924269D03*
X501121Y914702D03*
X512223Y933836D03*
X501121Y927458D03*
X514074Y943403D03*
X512223Y952970D03*
X501121Y946592D03*
X514074Y962537D03*
X501121Y959348D03*
X514074Y981671D03*
X512223Y972104D03*
X501121D03*
Y984860D03*
Y997616D03*
Y991238D03*
X512223D03*
X514074Y1000805D03*
X502971Y994427D03*
X508523Y991238D03*
X501121Y1010372D03*
X512223D03*
X501121Y1003994D03*
X504822Y1010372D03*
X506003Y1028056D03*
X509704D03*
X502302Y1040812D03*
X500452Y1031245D03*
X511554Y1044001D03*
Y1031245D03*
X502302Y1047190D03*
Y1053568D03*
X513405Y1047190D03*
X511554Y1056757D03*
X509704Y1047190D03*
X506003Y1053568D03*
X513405Y1066324D03*
X502302D03*
X513405Y1085458D03*
X502302Y1079080D03*
X513405Y1104592D03*
X502302Y1091836D03*
X500452Y1101403D03*
X502302Y1110970D03*
X513405Y1123726D03*
X502302D03*
X513405Y1142859D03*
X502302Y1136481D03*
Y1149237D03*
X513405Y1161993D03*
X511554Y1158804D03*
X509704Y1161993D03*
X502302D03*
X500452Y1152426D03*
X506003Y1161993D03*
X500452Y1158804D03*
Y1165182D03*
X507853D03*
X504153D03*
X504296Y1516970D03*
X509021D03*
X513745D03*
X501147Y1519698D03*
X505871D03*
X510595D03*
X504296Y1530608D03*
X509021D03*
X513745D03*
X501147Y1533336D03*
X505871D03*
X510595D03*
X521475Y879624D03*
X519625Y876435D03*
X517775Y879624D03*
X521475Y873246D03*
X517775D03*
X527027Y876435D03*
X528877Y879624D03*
Y892380D03*
X521475Y886002D03*
X515924Y889191D03*
X523326D03*
X517775Y892380D03*
X523326Y895569D03*
X515924D03*
X521475Y892380D03*
X515924Y882813D03*
X527027D03*
X528877Y911513D03*
Y905135D03*
Y898758D03*
X523326Y908325D03*
X517775Y911513D03*
X521475Y898758D03*
X515924Y901947D03*
X523326D03*
X517775Y905135D03*
X521475D03*
X515924Y908325D03*
X521475Y911513D03*
X517775Y898758D03*
X528877Y924269D03*
Y917891D03*
X521475D03*
X515924Y921080D03*
X523326D03*
X517775Y924269D03*
X521475D03*
X523326Y914702D03*
X515924D03*
X517775Y917891D03*
X528877Y930647D03*
Y937025D03*
X515924Y927458D03*
X523326D03*
X517775Y930647D03*
X521475Y937025D03*
X515924Y940214D03*
X523326D03*
Y933836D03*
X515924D03*
X521475Y930647D03*
X517775Y937025D03*
X528877Y943403D03*
Y949781D03*
Y956159D03*
X517775Y943403D03*
X521475D03*
X515924Y946592D03*
X523326D03*
X517775Y949781D03*
X521475Y956159D03*
X523326Y952970D03*
X515924D03*
X521475Y949781D03*
X517775Y956159D03*
X528877Y968915D03*
Y962537D03*
X521475D03*
X515924Y965726D03*
X523326D03*
X517775Y968915D03*
X515924Y959348D03*
X523326D03*
X517775Y962537D03*
X521475Y968915D03*
X528877Y981671D03*
Y975293D03*
X515924Y984860D03*
X521475Y975293D03*
X515924Y978482D03*
X523326D03*
X517775Y981671D03*
X523326Y972104D03*
X515924D03*
X517775Y975293D03*
X528877Y988049D03*
Y1000805D03*
X517775Y988049D03*
X521475Y994427D03*
X523326Y997616D03*
X515924D03*
X517775Y1000805D03*
X521475D03*
Y988049D03*
X515924Y991238D03*
X517775Y994427D03*
X523326Y991238D03*
X528877Y994427D03*
Y1007183D03*
X523326Y1010372D03*
X521475Y1007183D03*
X523326Y1003994D03*
X515924D03*
X517775Y1007183D03*
X515924Y1010372D03*
X517105Y1028056D03*
X524507D03*
X518956Y1031245D03*
X517105Y1034434D03*
X524507D03*
X522657Y1037623D03*
X518956D03*
X517105Y1040812D03*
X524507D03*
X518956Y1044001D03*
X515255Y1037623D03*
X522656Y1044001D03*
Y1031245D03*
X518956Y1050379D03*
X524507Y1059946D03*
X517105Y1047190D03*
X522657Y1050379D03*
X524507Y1053568D03*
X515255Y1056757D03*
X522656D03*
X524507Y1047190D03*
X517105Y1053568D03*
X524507Y1072702D03*
X518956Y1063135D03*
X522657D03*
X517105Y1066324D03*
X518956Y1069513D03*
X522657D03*
X517105Y1072702D03*
X524507Y1066324D03*
X518956Y1075891D03*
X522657D03*
X517105Y1079080D03*
X524507D03*
X518956Y1082269D03*
X522657D03*
X517105Y1085458D03*
X522657Y1088647D03*
X518956D03*
X524507Y1085458D03*
X515255Y1075891D03*
X522657Y1101403D03*
X517105Y1104592D03*
X524507Y1091836D03*
X518956Y1095025D03*
X522657D03*
X517105Y1098214D03*
X524507D03*
X518956Y1101403D03*
X524507Y1104592D03*
X517105Y1091836D03*
X515255Y1095025D03*
X524507Y1110970D03*
X518956Y1114159D03*
X522657D03*
X517105Y1117348D03*
X524507D03*
X522657Y1107781D03*
X518956D03*
X517105Y1110970D03*
X515255Y1114159D03*
X518956Y1120537D03*
X522657D03*
X517105Y1123726D03*
X524507Y1130103D03*
X518956Y1133293D03*
X522657D03*
Y1126915D03*
X518956D03*
X524507Y1123726D03*
X517105Y1130103D03*
X515255Y1133293D03*
X517105Y1136481D03*
X524507D03*
X518956Y1139670D03*
X522657D03*
X517105Y1142859D03*
X524507Y1149237D03*
X522657Y1146048D03*
X518956D03*
X524507Y1142859D03*
X517105Y1149237D03*
X528208Y1161993D03*
X518956Y1152426D03*
X522657D03*
X524507Y1155615D03*
X515255Y1152426D03*
X524507Y1161993D03*
X520806D03*
X518956Y1158804D03*
X529594Y1507355D03*
X527494D03*
X518470Y1516970D03*
X523194D03*
X515320Y1519698D03*
X520044D03*
X524769D03*
X518470Y1530608D03*
X523194D03*
X515320Y1533336D03*
X520044D03*
X524769D03*
X530727Y876435D03*
X532578Y873246D03*
X536279Y886002D03*
X530727Y889191D03*
X534428D03*
Y895569D03*
X530727D03*
X536279Y892380D03*
X541830Y889191D03*
X543680Y892380D03*
X541830Y895569D03*
X538129D03*
X539979Y886002D03*
X530727Y882813D03*
X541830D03*
X534428Y908325D03*
X536279Y898758D03*
X530727Y901947D03*
X534428D03*
X536279Y905135D03*
X530727Y908325D03*
X536279Y911513D03*
X543680D03*
X541830Y901947D03*
X543680Y905135D03*
X541830Y908325D03*
X543680Y898758D03*
X539979Y905135D03*
X536279Y917891D03*
X530727Y921080D03*
X534428D03*
X536279Y924269D03*
X534428Y914702D03*
X530727D03*
X541830Y921080D03*
X543680Y924269D03*
X541830Y914702D03*
X543680Y917891D03*
X539979Y924269D03*
X538129Y914702D03*
X530727Y927458D03*
X534428D03*
X536279Y937025D03*
X530727Y940214D03*
X534428D03*
Y933836D03*
X530727D03*
X536279Y930647D03*
X541830Y927458D03*
X543680Y930647D03*
X541830Y940214D03*
Y933836D03*
X543680Y937025D03*
X538129Y933836D03*
X536279Y943403D03*
X530727Y946592D03*
X534428D03*
X536279Y956159D03*
X534428Y952970D03*
X530727D03*
X536279Y949781D03*
X543680Y943403D03*
X541830Y946592D03*
X543680Y949781D03*
X541830Y952970D03*
X543680Y956159D03*
X538129Y952970D03*
X539979Y943403D03*
X536279Y962537D03*
X530727Y965726D03*
X534428D03*
X530727Y959348D03*
X534428D03*
X536279Y968915D03*
X541830Y965726D03*
X543680Y968915D03*
X541830Y959348D03*
X543680Y962537D03*
X539979D03*
X530727Y984860D03*
X536279Y975293D03*
X530727Y978482D03*
X534428D03*
Y972104D03*
X530727D03*
X541830Y984860D03*
Y978482D03*
X543680Y981671D03*
X541830Y972104D03*
X543680Y975293D03*
X538129Y972104D03*
X539979Y981671D03*
X536279Y994427D03*
X534428Y997616D03*
X530727D03*
X536279Y1000805D03*
Y988049D03*
X530727Y991238D03*
X543680Y988049D03*
X541830Y997616D03*
X543680Y1000805D03*
X541830Y991238D03*
X539979Y1000805D03*
X538129Y991238D03*
X543680Y994427D03*
X534428Y991238D03*
Y1010372D03*
X536279Y1007183D03*
X534428Y1003994D03*
X530727D03*
X541830D03*
X543680Y1007183D03*
X538129Y1010372D03*
X530727D03*
X541830D03*
X531908Y1028056D03*
X543011D03*
X535609D03*
X530058Y1031245D03*
X531908Y1034434D03*
X535609D03*
X537460Y1037623D03*
X530058D03*
X531908Y1040812D03*
X535609D03*
X530058Y1044001D03*
X543011Y1034434D03*
Y1040812D03*
X541160Y1037623D03*
X537460Y1044001D03*
Y1031245D03*
X530058Y1050379D03*
X535609Y1059946D03*
X531908Y1047190D03*
X537460Y1050379D03*
X535609Y1053568D03*
X543011Y1047190D03*
X541160Y1056757D03*
X539310Y1047190D03*
X543011Y1053568D03*
X537460Y1056757D03*
X535609Y1047190D03*
X531908Y1053568D03*
X535609Y1072702D03*
X530058Y1063135D03*
X537460D03*
X531908Y1066324D03*
X530058Y1069513D03*
X537460D03*
X531908Y1072702D03*
X535609Y1066324D03*
X543011D03*
Y1072702D03*
X539310Y1066324D03*
X530058Y1075891D03*
X537460D03*
X531908Y1079080D03*
X535609D03*
X530058Y1082269D03*
X537460D03*
X531908Y1085458D03*
X537460Y1088647D03*
X530058D03*
X535609Y1085458D03*
X543011Y1079080D03*
Y1085458D03*
X539310D03*
X541160Y1075891D03*
X537460Y1101403D03*
X531908Y1104592D03*
X535609Y1091836D03*
X530058Y1095025D03*
X537460D03*
X531908Y1098214D03*
X535609D03*
X530058Y1101403D03*
X535609Y1104592D03*
X531908Y1091836D03*
X543011Y1104592D03*
Y1098214D03*
Y1091836D03*
X541160Y1095025D03*
X539310Y1104592D03*
X535609Y1110970D03*
X530058Y1114159D03*
X537460D03*
X531908Y1117348D03*
X535609D03*
X537460Y1107781D03*
X530058D03*
X531908Y1110970D03*
X543011Y1117348D03*
Y1110970D03*
X541160Y1114159D03*
X530058Y1120537D03*
X537460D03*
X531908Y1123726D03*
X535609Y1130103D03*
X530058Y1133293D03*
X537460D03*
Y1126915D03*
X530058D03*
X535609Y1123726D03*
X531908Y1130103D03*
X543011Y1123726D03*
Y1130103D03*
X539310Y1123726D03*
X541160Y1133293D03*
X531908Y1136481D03*
X535609D03*
X530058Y1139670D03*
X537460D03*
X531908Y1142859D03*
X535609Y1149237D03*
X537460Y1146048D03*
X530058D03*
X535609Y1142859D03*
X531908Y1149237D03*
X543011Y1136481D03*
Y1142859D03*
Y1149237D03*
X539310Y1142859D03*
X530058Y1152426D03*
X537460D03*
X531908Y1155615D03*
X541160Y1152426D03*
X531908Y1161993D03*
X535609D03*
X539310D03*
X537460Y1158804D03*
X541160D03*
X531001Y1514073D03*
X530945Y1516336D03*
X532310Y1536640D03*
X531926Y1534540D03*
X531537Y1531618D03*
X531208Y1528698D03*
X530711Y1538658D03*
X554783Y879624D03*
X556633Y889191D03*
X554783Y892380D03*
X556633Y895569D03*
X547381Y886002D03*
X549231Y889191D03*
Y895569D03*
X547381Y892380D03*
X556633Y882813D03*
X552932D03*
X554783Y911513D03*
X556633Y901947D03*
X554783Y905135D03*
X556633Y908325D03*
X554783Y898758D03*
X549231Y908325D03*
X547381Y898758D03*
X549231Y901947D03*
X547381Y905135D03*
Y911513D03*
X556633Y921080D03*
X554783Y924269D03*
X556633Y914702D03*
X554783Y917891D03*
X547381D03*
X549231Y921080D03*
X547381Y924269D03*
X549231Y914702D03*
X556633Y927458D03*
X554783Y930647D03*
X556633Y940214D03*
Y933836D03*
X554783Y937025D03*
X549231Y927458D03*
X547381Y937025D03*
X549231Y940214D03*
Y933836D03*
X547381Y930647D03*
X554783Y943403D03*
X556633Y946592D03*
X554783Y949781D03*
X556633Y952970D03*
X554783Y956159D03*
X547381Y943403D03*
X549231Y946592D03*
X547381Y956159D03*
X549231Y952970D03*
X547381Y949781D03*
X556633Y965726D03*
X554783Y968915D03*
X556633Y959348D03*
X554783Y962537D03*
X547381D03*
X549231Y965726D03*
Y959348D03*
X547381Y968915D03*
X556633Y984860D03*
Y978482D03*
X554783Y981671D03*
X556633Y972104D03*
X554783Y975293D03*
X547381D03*
X549231Y978482D03*
Y972104D03*
X554783Y988049D03*
X556633Y997616D03*
X554783Y1000805D03*
X556633Y991238D03*
X547381Y994427D03*
X549231Y997616D03*
X547381Y1000805D03*
Y988049D03*
X554782Y994427D03*
X549231Y991238D03*
X556633Y1003994D03*
X554783Y1007183D03*
X549231Y1010372D03*
X547381Y1007183D03*
X549231Y1003994D03*
X556633Y1010372D03*
X557814Y1028056D03*
X550412D03*
X555964Y1031245D03*
X557814Y1034434D03*
X555964Y1037623D03*
X557814Y1040812D03*
X555964Y1044001D03*
X544861Y1031245D03*
X550412Y1034434D03*
X548562Y1037623D03*
X544861D03*
X550412Y1040812D03*
X544861Y1044001D03*
X548562D03*
Y1031245D03*
X555964Y1050379D03*
X557814Y1047190D03*
X544861Y1050379D03*
X550412Y1059946D03*
X548562Y1050379D03*
X550412Y1053568D03*
X557814D03*
X548562Y1056757D03*
X550412Y1047190D03*
X555964Y1063135D03*
X557814Y1066324D03*
X555964Y1069513D03*
X557814Y1072702D03*
X550412D03*
X544861Y1063135D03*
X548562D03*
X544861Y1069513D03*
X548562D03*
X550412Y1066324D03*
X555964Y1075891D03*
X557814Y1079080D03*
X555964Y1082269D03*
X557814Y1085458D03*
X555964Y1088647D03*
X544861Y1075891D03*
X548562D03*
X550412Y1079080D03*
X544861Y1082269D03*
X548562D03*
Y1088647D03*
X544861D03*
X550412Y1085458D03*
X557814Y1104592D03*
X555964Y1095025D03*
X557814Y1098214D03*
X555964Y1101403D03*
X557814Y1091836D03*
X548562Y1101403D03*
X550412Y1091836D03*
X544861Y1095025D03*
X548562D03*
X550412Y1098214D03*
X544861Y1101403D03*
X550412Y1104592D03*
X555964Y1114159D03*
X557814Y1117348D03*
X555964Y1107781D03*
X557814Y1110970D03*
X550412D03*
X544861Y1114159D03*
X548562D03*
X550412Y1117348D03*
X548562Y1107781D03*
X544861D03*
X555964Y1120537D03*
X557814Y1123726D03*
X555964Y1133293D03*
Y1126915D03*
X557814Y1130103D03*
X544861Y1120537D03*
X548562D03*
X550412Y1130103D03*
X544861Y1133293D03*
X548562D03*
Y1126915D03*
X544861D03*
X550412Y1123726D03*
X557814Y1136481D03*
X555964Y1139670D03*
X557814Y1142859D03*
X555964Y1146048D03*
X557814Y1149237D03*
X550412Y1136481D03*
X544861Y1139670D03*
X548562D03*
X550412Y1149237D03*
X548562Y1146048D03*
X544861D03*
X550412Y1142859D03*
X546712Y1161993D03*
X555964Y1152426D03*
X557814Y1155615D03*
X544861Y1152426D03*
X548562D03*
X550412Y1155615D03*
X557814Y1161993D03*
X544861Y1158804D03*
X562184Y873246D03*
X565885Y879624D03*
X564034Y876435D03*
X573286Y879624D03*
X571436Y876435D03*
X569586Y879624D03*
X562184Y886002D03*
X560334Y889191D03*
Y895569D03*
X562184Y892380D03*
X564034Y895569D03*
X565885Y886002D03*
X567735Y882813D03*
X560334Y908325D03*
X562184Y898758D03*
X560334Y901947D03*
X562184Y905135D03*
Y911513D03*
X565885Y905135D03*
X562184Y917891D03*
X560334Y921080D03*
X562184Y924269D03*
X560334Y914702D03*
X565885Y924269D03*
X564034Y914702D03*
X560334Y927458D03*
X562184Y937025D03*
X560334Y940214D03*
Y933836D03*
X562184Y930647D03*
X564034Y933836D03*
X562184Y943403D03*
X560334Y946592D03*
X562184Y956159D03*
X560334Y952970D03*
X562184Y949781D03*
X564034Y952970D03*
X565885Y943403D03*
X562184Y962537D03*
X560334Y965726D03*
Y959348D03*
X562184Y968915D03*
X565885Y962537D03*
X562184Y975293D03*
X560334Y978482D03*
Y972104D03*
X565885Y981671D03*
X564034Y972104D03*
X562184Y994427D03*
X560334Y997616D03*
X562184Y1000805D03*
Y988049D03*
X565885Y1000805D03*
X564034Y991238D03*
X560334D03*
Y1010372D03*
X562184Y1007183D03*
X560334Y1003994D03*
X564034Y1010372D03*
X567735D03*
X568916Y1028056D03*
X561515D03*
Y1034434D03*
X563365Y1037623D03*
X561515Y1040812D03*
X567066Y1037623D03*
X563365Y1044001D03*
Y1031245D03*
X561515Y1059946D03*
X563365Y1050379D03*
X561515Y1053568D03*
X567066Y1056757D03*
X565215Y1047190D03*
X563365Y1056757D03*
X561515Y1047190D03*
Y1072702D03*
X563365Y1063135D03*
Y1069513D03*
X561515Y1066324D03*
X565215D03*
X563365Y1075891D03*
X561515Y1079080D03*
X563365Y1082269D03*
Y1088647D03*
X561515Y1085458D03*
X565215D03*
X567066Y1075891D03*
X563365Y1101403D03*
X561515Y1091836D03*
X563365Y1095025D03*
X561515Y1098214D03*
Y1104592D03*
X565215D03*
X567066Y1095025D03*
X561515Y1110970D03*
X563365Y1114159D03*
X561515Y1117348D03*
X563365Y1107781D03*
X567066Y1114159D03*
X563365Y1120537D03*
X561515Y1130103D03*
X563365Y1133293D03*
Y1126915D03*
X561515Y1123726D03*
X567066Y1133293D03*
X565215Y1123726D03*
X561515Y1136481D03*
X563365Y1139670D03*
X561515Y1149237D03*
X563365Y1146048D03*
X561515Y1142859D03*
X565215D03*
X567066Y1158804D03*
X563365Y1152426D03*
Y1158804D03*
X567066Y1152426D03*
X572617Y1161993D03*
X570767Y1165182D03*
X567066D03*
X568916Y1161993D03*
X570815Y1507509D03*
X573066Y1507460D03*
X570980Y1513218D03*
X569722Y1521612D03*
X569321Y1518121D03*
X569768Y1535698D03*
Y1537898D03*
X571215Y1540317D03*
X580390Y1516970D03*
X585114D03*
X581965Y1519698D03*
X586689D03*
X580390Y1530608D03*
X585114D03*
X581965Y1533336D03*
X586689D03*
X575286Y1544625D03*
X589839Y1516970D03*
X594563D03*
X599287D03*
X604012D03*
X591413Y1519698D03*
X596138D03*
X600862D03*
X589839Y1530608D03*
X594563D03*
X599287D03*
X604012D03*
X591413Y1533336D03*
X596138D03*
X600862D03*
X608736Y1516970D03*
X613461D03*
X618185D03*
X605587Y1519698D03*
X610311D03*
X615035D03*
X608736Y1530608D03*
X613461D03*
X618185D03*
X605587Y1533336D03*
X610311D03*
X615035D03*
X627634Y1516970D03*
X632358D03*
X622909D03*
X629209Y1519698D03*
X633933D03*
X619760D03*
X624484D03*
X627634Y1530608D03*
X632358D03*
X622909D03*
X629209Y1533336D03*
X633933D03*
X619760D03*
X624484D03*
X637083Y1516970D03*
X641807D03*
X646532D03*
X638657Y1519698D03*
X643382D03*
X648106D03*
X637083Y1530608D03*
X641807D03*
X646532D03*
X638657Y1533336D03*
X643382D03*
X648106D03*
X657656Y1507355D03*
X655556D03*
X651256Y1516970D03*
X652831Y1519698D03*
X659063Y1514073D03*
X659007Y1516336D03*
X651256Y1530608D03*
X652831Y1533336D03*
X659358Y1536640D03*
Y1534540D03*
X659359Y1531618D03*
X659270Y1528698D03*
X662353Y1534413D03*
X660877Y1530158D03*
X658773Y1538658D03*
X1184959Y1551121D03*
X1185360Y1554612D03*
X1185406Y1568698D03*
Y1570898D03*
X1196028Y1549970D03*
X1197603Y1552698D03*
X1188653Y1540509D03*
X1186453D03*
X1186618Y1546218D03*
X1196028Y1563608D03*
X1197603Y1566336D03*
X1186853Y1573317D03*
X1190924Y1577625D03*
X1200752Y1549970D03*
X1205477D03*
X1210201D03*
X1214925D03*
X1202327Y1552698D03*
X1207051D03*
X1211776D03*
X1200752Y1563608D03*
X1205477D03*
X1210201D03*
X1214925D03*
X1202327Y1566336D03*
X1207051D03*
X1211776D03*
X1219650Y1549970D03*
X1224374D03*
X1229099D03*
X1216500Y1552698D03*
X1221225D03*
X1225949D03*
X1219650Y1563608D03*
X1224374D03*
X1229099D03*
X1216500Y1566336D03*
X1221225D03*
X1225949D03*
X1243272Y1549970D03*
X1233823D03*
X1238547D03*
X1244847Y1552698D03*
X1230673D03*
X1235398D03*
X1240122D03*
X1243272Y1563608D03*
X1233823D03*
X1238547D03*
X1244847Y1566336D03*
X1230673D03*
X1235398D03*
X1240122D03*
X1247996Y1549970D03*
X1252721D03*
X1257445D03*
X1249571Y1552698D03*
X1254295D03*
X1259020D03*
X1247996Y1563608D03*
X1252721D03*
X1257445D03*
X1249571Y1566336D03*
X1254295D03*
X1259020D03*
X1262170Y1549970D03*
X1266894D03*
X1263744Y1552698D03*
X1268469D03*
X1273294Y1540355D03*
X1271194D03*
X1274701Y1547073D03*
X1274645Y1549336D03*
X1262170Y1563608D03*
X1266894D03*
X1263744Y1566336D03*
X1268469D03*
X1274996Y1567540D03*
X1274997Y1564618D03*
X1274908Y1561698D03*
X1274411Y1571658D03*
X1274996Y1569640D03*
X1288549Y876434D03*
X1288548Y1010371D03*
X1289729Y1028055D03*
X1297800Y879623D03*
X1299650Y876434D03*
X1290399Y879623D03*
X1303351Y882812D03*
X1294099Y886001D03*
X1299650Y889190D03*
X1295949D03*
X1301500Y892379D03*
X1295949Y895568D03*
X1299650D03*
X1294099Y892379D03*
X1292249Y895568D03*
X1299650Y882812D03*
X1295949Y908324D03*
X1301500Y911512D03*
X1294099Y898757D03*
X1299650Y901946D03*
X1295949D03*
X1301500Y905134D03*
X1294099D03*
X1299650Y908324D03*
X1294099Y911512D03*
X1301500Y898757D03*
X1290398Y905134D03*
X1294099Y917890D03*
X1299650Y921079D03*
X1295949D03*
X1301500Y924268D03*
X1294099D03*
X1295949Y914701D03*
X1299650D03*
X1301500Y917890D03*
X1292249Y914701D03*
X1290398Y924268D03*
X1299650Y927457D03*
X1295949D03*
X1301500Y930646D03*
X1294099Y937024D03*
X1299650Y940213D03*
X1295949D03*
Y933835D03*
X1299650D03*
X1294099Y930646D03*
X1301500Y937024D03*
X1292249Y933835D03*
X1301500Y943402D03*
X1294099D03*
X1299650Y946591D03*
X1295949D03*
X1301500Y949780D03*
X1294099Y956158D03*
X1295949Y952969D03*
X1299650D03*
X1294099Y949780D03*
X1301500Y956158D03*
X1292249Y952969D03*
X1290398Y943402D03*
X1294099Y962536D03*
X1299650Y965725D03*
X1295949D03*
X1301500Y968914D03*
X1299650Y959347D03*
X1295949D03*
X1301500Y962536D03*
X1294099Y968914D03*
X1290398Y962536D03*
X1299650Y984859D03*
X1294099Y975292D03*
X1299650Y978481D03*
X1295949D03*
X1301500Y981670D03*
X1295949Y972103D03*
X1299650D03*
X1301500Y975292D03*
X1292249Y972103D03*
X1290398Y981670D03*
X1301500Y988048D03*
X1294099Y994426D03*
X1295949Y997615D03*
X1299650D03*
X1301500Y1000804D03*
X1294099D03*
X1295949Y991237D03*
X1301500Y994426D03*
X1292249Y991237D03*
X1290398Y1000804D03*
X1299650Y991237D03*
X1294099Y988048D03*
X1295949Y1010371D03*
X1294099Y1007182D03*
X1295949Y1003993D03*
X1299650D03*
X1301500Y1007182D03*
X1299650Y1010371D03*
X1293430Y1028055D03*
X1300831D03*
X1297130D03*
X1302681Y1031244D03*
X1300831Y1034433D03*
X1297130D03*
X1295280Y1037622D03*
X1302681D03*
X1300831Y1040811D03*
X1297130D03*
X1295280Y1044000D03*
X1291579Y1037622D03*
X1302682Y1044000D03*
X1295280Y1031244D03*
X1302681Y1050378D03*
X1297130Y1059945D03*
X1300831Y1047189D03*
X1295280Y1050378D03*
X1297130Y1053567D03*
X1291579Y1056756D03*
X1293430Y1047189D03*
X1295280Y1056756D03*
X1297130Y1047189D03*
X1300831Y1053567D03*
X1297130Y1072701D03*
X1302681Y1063134D03*
X1295280D03*
X1300831Y1066323D03*
X1302681Y1069512D03*
X1295280D03*
X1300831Y1072701D03*
X1297130Y1066323D03*
X1293430D03*
X1302681Y1075890D03*
X1295280D03*
X1300831Y1079079D03*
X1297130D03*
X1302681Y1082268D03*
X1295280D03*
X1300831Y1085457D03*
X1295280Y1088646D03*
X1302681D03*
X1297130Y1085457D03*
X1293430D03*
X1291579Y1075890D03*
X1295280Y1101402D03*
X1300831Y1104591D03*
X1297130Y1091835D03*
X1302681Y1095024D03*
X1295280D03*
X1300831Y1098213D03*
X1297130D03*
X1302681Y1101402D03*
X1297130Y1104591D03*
X1300831Y1091835D03*
X1293430Y1104591D03*
X1291579Y1095024D03*
X1297130Y1110969D03*
X1302681Y1114158D03*
X1295280D03*
X1300831Y1117347D03*
X1297130D03*
X1295280Y1107780D03*
X1302681D03*
X1300831Y1110969D03*
X1291579Y1114158D03*
X1302681Y1120536D03*
X1295280D03*
X1300831Y1123725D03*
X1297130Y1130102D03*
X1302681Y1133292D03*
X1295280D03*
Y1126914D03*
X1302681D03*
X1297130Y1123725D03*
X1300831Y1130102D03*
X1291579Y1133292D03*
X1293430Y1123725D03*
X1300831Y1136480D03*
X1297130D03*
X1302681Y1139669D03*
X1295280D03*
X1300831Y1142858D03*
X1297130Y1149236D03*
X1295280Y1146047D03*
X1302681D03*
X1297130Y1142858D03*
X1300831Y1149236D03*
X1293430Y1142858D03*
X1291579Y1158803D03*
X1302681Y1152425D03*
X1295280D03*
X1300831Y1155614D03*
X1295280Y1158803D03*
X1291579Y1152425D03*
X1300831Y1161992D03*
X1302682Y1165181D03*
X1318154Y876434D03*
X1305201Y879623D03*
X1312603D03*
X1316304D03*
X1307052Y876434D03*
X1308902Y886001D03*
X1314453Y889190D03*
X1307052D03*
X1312603Y892379D03*
X1307052Y895568D03*
X1314453D03*
X1308902Y892379D03*
X1318154Y895568D03*
X1307052Y908324D03*
X1312603Y911512D03*
X1308902Y898757D03*
X1314453Y901946D03*
X1307052D03*
X1312603Y905134D03*
X1308902D03*
X1314453Y908324D03*
X1308902Y911512D03*
X1312603Y898757D03*
X1316304Y905134D03*
X1308902Y917890D03*
X1314453Y921079D03*
X1307052D03*
X1312603Y924268D03*
X1308902D03*
X1307052Y914701D03*
X1314453D03*
X1312603Y917890D03*
X1316304Y924268D03*
X1318154Y914701D03*
X1314453Y927457D03*
X1307052D03*
X1312603Y930646D03*
X1308902Y937024D03*
X1314453Y940213D03*
X1307052D03*
Y933835D03*
X1314453D03*
X1308902Y930646D03*
X1312603Y937024D03*
X1318154Y933835D03*
X1312603Y943402D03*
X1308902D03*
X1314453Y946591D03*
X1307052D03*
X1312603Y949780D03*
X1308902Y956158D03*
X1307052Y952969D03*
X1314453D03*
X1308902Y949780D03*
X1312603Y956158D03*
X1318154Y952969D03*
X1316304Y943402D03*
X1308902Y962536D03*
X1314453Y965725D03*
X1307052D03*
X1312603Y968914D03*
X1314453Y959347D03*
X1307052D03*
X1312603Y962536D03*
X1308902Y968914D03*
X1316304Y962536D03*
X1314453Y984859D03*
X1308902Y975292D03*
X1314453Y978481D03*
X1307052D03*
X1312603Y981670D03*
X1307052Y972103D03*
X1314453D03*
X1312603Y975292D03*
X1316304Y981670D03*
X1318154Y972103D03*
X1312603Y988048D03*
X1308902Y994426D03*
X1307052Y997615D03*
X1314453D03*
X1312603Y1000804D03*
X1308902D03*
X1307052Y991237D03*
X1312603Y994426D03*
X1316304Y1000804D03*
X1318154Y991237D03*
X1314453D03*
X1308902Y988048D03*
X1307052Y1010371D03*
X1308902Y1007182D03*
X1307052Y1003993D03*
X1314453D03*
X1312603Y1007182D03*
X1314453Y1010371D03*
X1319335Y1028055D03*
X1315634D03*
X1308233D03*
X1313784Y1031244D03*
X1315634Y1034433D03*
X1308233D03*
X1310083Y1037622D03*
X1313784D03*
X1315634Y1040811D03*
X1308233D03*
X1310083Y1044000D03*
X1317485Y1037622D03*
X1313784Y1044000D03*
X1310083Y1031244D03*
X1313784Y1050378D03*
X1308233Y1059945D03*
X1315634Y1047189D03*
X1310083Y1050378D03*
X1308233Y1053567D03*
X1317485Y1056756D03*
X1319335Y1047189D03*
X1310083Y1056756D03*
X1308233Y1047189D03*
X1315634Y1053567D03*
X1308233Y1072701D03*
X1313784Y1063134D03*
X1310083D03*
X1315634Y1066323D03*
X1313784Y1069512D03*
X1310083D03*
X1315634Y1072701D03*
X1308233Y1066323D03*
X1319335D03*
X1313784Y1075890D03*
X1310083D03*
X1315634Y1079079D03*
X1308233D03*
X1313784Y1082268D03*
X1310083D03*
X1315634Y1085457D03*
X1310083Y1088646D03*
X1313784D03*
X1308233Y1085457D03*
X1319335D03*
X1317485Y1075890D03*
X1310083Y1101402D03*
X1315634Y1104591D03*
X1308233Y1091835D03*
X1313784Y1095024D03*
X1310083D03*
X1315634Y1098213D03*
X1308233D03*
X1313784Y1101402D03*
X1308233Y1104591D03*
X1315634Y1091835D03*
X1319335Y1104591D03*
X1317485Y1095024D03*
X1308233Y1110969D03*
X1313784Y1114158D03*
X1310083D03*
X1315634Y1117347D03*
X1308233D03*
X1310083Y1107780D03*
X1313784D03*
X1315634Y1110969D03*
X1317485Y1114158D03*
X1313784Y1120536D03*
X1310083D03*
X1315634Y1123725D03*
X1308233Y1130102D03*
X1313784Y1133292D03*
X1310083D03*
Y1126914D03*
X1313784D03*
X1308233Y1123725D03*
X1315634Y1130102D03*
X1317485Y1133292D03*
X1319335Y1123725D03*
X1315634Y1136480D03*
X1308233D03*
X1313784Y1139669D03*
X1310083D03*
X1315634Y1142858D03*
X1308233Y1149236D03*
X1310083Y1146047D03*
X1313784D03*
X1308233Y1142858D03*
X1315634Y1149236D03*
X1319335Y1142858D03*
X1313784Y1152425D03*
X1310083D03*
X1308233Y1155614D03*
X1317485Y1152425D03*
X1308233Y1161992D03*
X1310083Y1165181D03*
X1317485D03*
X1315634Y1161992D03*
X1316766Y1540460D03*
X1314515Y1540509D03*
X1314680Y1546218D03*
X1313021Y1551121D03*
X1313422Y1554612D03*
X1313468Y1568698D03*
Y1570898D03*
X1318986Y1577625D03*
X1314915Y1573317D03*
X1323705Y879623D03*
X1327406D03*
X1321855Y876434D03*
X1332957D03*
X1329256D03*
X1334807Y879623D03*
X1320004Y886001D03*
X1325556Y889190D03*
X1321855D03*
X1327406Y892379D03*
X1321855Y895568D03*
X1325556D03*
X1320004Y892379D03*
X1334807Y886001D03*
X1332957Y889190D03*
Y895568D03*
X1334807Y892379D03*
X1321855Y908324D03*
X1327406Y911512D03*
X1320004Y898757D03*
X1325556Y901946D03*
X1321855D03*
X1327406Y905134D03*
X1320004D03*
X1325556Y908324D03*
X1320004Y911512D03*
X1327406Y898757D03*
X1332957Y908324D03*
X1334807Y898757D03*
X1332957Y901946D03*
X1334807Y905134D03*
Y911512D03*
X1320004Y917890D03*
X1325556Y921079D03*
X1321855D03*
X1327406Y924268D03*
X1320004D03*
X1321855Y914701D03*
X1325556D03*
X1327406Y917890D03*
X1334807D03*
X1332957Y921079D03*
X1334807Y924268D03*
X1332957Y914701D03*
X1325556Y927457D03*
X1321855D03*
X1327406Y930646D03*
X1320004Y937024D03*
X1325556Y940213D03*
X1321855D03*
Y933835D03*
X1325556D03*
X1320004Y930646D03*
X1327406Y937024D03*
X1332957Y927457D03*
X1334807Y937024D03*
X1332957Y940213D03*
Y933835D03*
X1334807Y930646D03*
X1327406Y943402D03*
X1320004D03*
X1325556Y946591D03*
X1321855D03*
X1327406Y949780D03*
X1320004Y956158D03*
X1321855Y952969D03*
X1325556D03*
X1320004Y949780D03*
X1327406Y956158D03*
X1334807Y943402D03*
X1332957Y946591D03*
X1334807Y956158D03*
X1332957Y952969D03*
X1334807Y949780D03*
X1320004Y962536D03*
X1325556Y965725D03*
X1321855D03*
X1327406Y968914D03*
X1325556Y959347D03*
X1321855D03*
X1327406Y962536D03*
X1320004Y968914D03*
X1334807Y962536D03*
X1332957Y965725D03*
Y959347D03*
X1334807Y968914D03*
X1325556Y984859D03*
X1320004Y975292D03*
X1325556Y978481D03*
X1321855D03*
X1327406Y981670D03*
X1321855Y972103D03*
X1325556D03*
X1327406Y975292D03*
X1334807D03*
X1332957Y978481D03*
Y972103D03*
X1327406Y988048D03*
X1320004Y994426D03*
X1321855Y997615D03*
X1325556D03*
X1327406Y1000804D03*
X1320004D03*
X1321855Y991237D03*
X1327406Y994426D03*
X1334807D03*
X1332957Y997615D03*
X1334807Y1000804D03*
X1332957Y991237D03*
X1334808Y988048D03*
X1325556Y991237D03*
X1320004Y988048D03*
X1321855Y1010371D03*
X1320004Y1007182D03*
X1321855Y1003993D03*
X1325556D03*
X1327406Y1007182D03*
X1332957Y1010371D03*
X1334807Y1007182D03*
X1332957Y1003993D03*
X1325556Y1010371D03*
X1326737Y1028055D03*
X1334138D03*
X1323036D03*
X1328587Y1031244D03*
X1326737Y1034433D03*
X1323036D03*
X1321185Y1037622D03*
X1328587D03*
X1326737Y1040811D03*
X1323036D03*
X1321185Y1044000D03*
X1334138Y1034433D03*
Y1040811D03*
X1328587Y1044000D03*
X1321185Y1031244D03*
X1328587Y1050378D03*
X1323036Y1059945D03*
X1326737Y1047189D03*
X1321185Y1050378D03*
X1323036Y1053567D03*
X1334138Y1059945D03*
Y1053567D03*
Y1047189D03*
X1321185Y1056756D03*
X1323036Y1047189D03*
X1326737Y1053567D03*
X1323036Y1072701D03*
X1328587Y1063134D03*
X1321185D03*
X1326737Y1066323D03*
X1328587Y1069512D03*
X1321185D03*
X1326737Y1072701D03*
X1323036Y1066323D03*
X1334138Y1072701D03*
Y1066323D03*
X1328587Y1075890D03*
X1321185D03*
X1326737Y1079079D03*
X1323036D03*
X1328587Y1082268D03*
X1321185D03*
X1326737Y1085457D03*
X1321185Y1088646D03*
X1328587D03*
X1323036Y1085457D03*
X1334138Y1079079D03*
Y1085457D03*
X1321185Y1101402D03*
X1326737Y1104591D03*
X1323036Y1091835D03*
X1328587Y1095024D03*
X1321185D03*
X1326737Y1098213D03*
X1323036D03*
X1328587Y1101402D03*
X1323036Y1104591D03*
X1326737Y1091835D03*
X1334138D03*
Y1098213D03*
Y1104591D03*
X1323036Y1110969D03*
X1328587Y1114158D03*
X1321185D03*
X1326737Y1117347D03*
X1323036D03*
X1321185Y1107780D03*
X1328587D03*
X1326737Y1110969D03*
X1334138D03*
Y1117347D03*
X1328587Y1120536D03*
X1321185D03*
X1326737Y1123725D03*
X1323036Y1130102D03*
X1328587Y1133292D03*
X1321185D03*
Y1126914D03*
X1328587D03*
X1323036Y1123725D03*
X1326737Y1130102D03*
X1334138D03*
Y1123725D03*
X1326737Y1136480D03*
X1323036D03*
X1328587Y1139669D03*
X1321185D03*
X1326737Y1142858D03*
X1323036Y1149236D03*
X1321185Y1146047D03*
X1328587D03*
X1323036Y1142858D03*
X1326737Y1149236D03*
X1334138Y1136480D03*
Y1149236D03*
Y1142858D03*
X1328587Y1152425D03*
X1321185D03*
X1326737Y1155614D03*
X1334138D03*
X1321185Y1158803D03*
X1334138Y1161992D03*
X1324090Y1549970D03*
X1328814D03*
X1333539D03*
X1325665Y1552698D03*
X1330389D03*
X1324090Y1563608D03*
X1328814D03*
X1333539D03*
X1325665Y1566336D03*
X1330389D03*
X1344059Y876434D03*
X1347760D03*
X1340359D03*
Y889190D03*
X1338508Y892379D03*
X1340359Y895568D03*
X1347760Y882812D03*
X1344059Y895568D03*
X1338508Y911512D03*
X1340359Y901946D03*
X1338508Y905134D03*
X1340359Y908324D03*
X1338508Y898757D03*
X1342209Y905134D03*
X1340359Y921079D03*
X1338508Y924268D03*
X1340359Y914701D03*
X1338508Y917890D03*
X1344059Y914701D03*
X1342209Y924268D03*
X1340359Y927457D03*
X1338508Y930646D03*
X1340359Y940213D03*
Y933835D03*
X1338508Y937024D03*
X1344059Y933835D03*
X1338508Y943402D03*
X1340359Y946591D03*
X1338508Y949780D03*
X1340359Y952969D03*
X1338508Y956158D03*
X1342209Y943402D03*
X1344059Y952969D03*
X1340359Y965725D03*
X1338508Y968914D03*
X1340359Y959347D03*
X1338508Y962536D03*
X1342209D03*
X1340359Y984859D03*
Y978481D03*
X1338508Y981670D03*
X1340359Y972103D03*
X1338508Y975292D03*
X1342209Y981670D03*
X1344059Y972103D03*
X1338508Y988048D03*
X1340359Y997615D03*
X1338508Y1000804D03*
Y994426D03*
X1344059Y991237D03*
X1342209Y1000804D03*
X1340359Y991237D03*
X1345910Y988048D03*
X1340359Y1003993D03*
X1338508Y1007182D03*
X1340359Y1010371D03*
X1345241Y1028055D03*
X1341540D03*
X1348941D03*
X1339689Y1031244D03*
X1341540Y1034433D03*
X1335989Y1037622D03*
X1339689D03*
X1341540Y1040811D03*
X1335989Y1044000D03*
X1343390Y1037622D03*
X1339689Y1044000D03*
X1335989Y1031244D03*
X1347091D03*
X1339689Y1050378D03*
X1341540Y1047189D03*
X1335989Y1050378D03*
X1345241Y1047189D03*
X1343390Y1056756D03*
X1335989D03*
X1341540Y1053567D03*
X1347091Y1056756D03*
X1348941Y1047189D03*
X1339689Y1063134D03*
X1335989D03*
X1341540Y1066323D03*
X1339689Y1069512D03*
X1335989D03*
X1341540Y1072701D03*
X1345241Y1066323D03*
X1339689Y1075890D03*
X1335989D03*
X1341540Y1079079D03*
X1339689Y1082268D03*
X1335989D03*
X1341540Y1085457D03*
X1335989Y1088646D03*
X1339689D03*
X1343390Y1075890D03*
X1345241Y1085457D03*
X1335989Y1101402D03*
X1341540Y1104591D03*
X1339689Y1095024D03*
X1335989D03*
X1341540Y1098213D03*
X1339689Y1101402D03*
X1341540Y1091835D03*
X1343390Y1095024D03*
X1345241Y1104591D03*
X1339689Y1114158D03*
X1335989D03*
X1341540Y1117347D03*
X1335989Y1107780D03*
X1339689D03*
X1341540Y1110969D03*
X1343390Y1114158D03*
X1339689Y1120536D03*
X1335989D03*
X1341540Y1123725D03*
X1339689Y1133292D03*
X1335989D03*
Y1126914D03*
X1339689D03*
X1341540Y1130102D03*
X1343390Y1133292D03*
X1345241Y1123725D03*
X1341540Y1136480D03*
X1339689Y1139669D03*
X1335989D03*
X1341540Y1142858D03*
X1335989Y1146047D03*
X1339689D03*
X1341540Y1149236D03*
X1345241Y1142858D03*
X1339689Y1152425D03*
X1335989D03*
X1347091Y1158803D03*
X1348941Y1161992D03*
X1345241D03*
X1343390Y1152425D03*
X1335989Y1165181D03*
X1343390Y1158803D03*
X1341540Y1161992D03*
X1338263Y1549970D03*
X1342987D03*
X1347712D03*
X1335113Y1552698D03*
X1339838D03*
X1344562D03*
X1349287D03*
X1338263Y1563608D03*
X1342987D03*
X1347712D03*
X1335113Y1566336D03*
X1339838D03*
X1344562D03*
X1349287D03*
X1358863Y876434D03*
X1355162D03*
X1364414Y892379D03*
X1360713D03*
X1351461Y882812D03*
X1357012Y886001D03*
X1362563Y895568D03*
X1358863D03*
X1355162Y889190D03*
X1364414Y905134D03*
Y898757D03*
Y911512D03*
X1360713Y905134D03*
Y898757D03*
Y911512D03*
X1362563Y908324D03*
X1358863D03*
X1355162Y901946D03*
X1364414Y917890D03*
Y924268D03*
X1360713Y917890D03*
Y924268D03*
X1358863Y921079D03*
X1362563D03*
X1355162Y914701D03*
X1364414Y930646D03*
X1360713D03*
X1362563Y940213D03*
X1358863D03*
X1357012Y937024D03*
X1355162Y927457D03*
X1364414Y937024D03*
X1360713D03*
Y956158D03*
Y943402D03*
Y949780D03*
X1364414Y956158D03*
Y943402D03*
Y949780D03*
X1362563Y952969D03*
X1358863D03*
X1355162Y946591D03*
X1360713Y962536D03*
Y968914D03*
X1364414Y962536D03*
Y968914D03*
X1362563Y965725D03*
X1358863D03*
X1355162Y959347D03*
X1360713Y975292D03*
X1364414D03*
X1357012Y981670D03*
X1364414D03*
X1358863Y984859D03*
X1362563Y978481D03*
X1358863D03*
X1355162Y972103D03*
X1357012Y988048D03*
X1358863Y997615D03*
X1357012Y994426D03*
X1358863Y991237D03*
X1364414Y988048D03*
Y994426D03*
X1357012Y1000804D03*
X1364414D03*
X1351461Y991237D03*
X1357012Y1007182D03*
X1358863Y1003993D03*
X1364414Y1007182D03*
X1355162Y1010371D03*
X1362563D03*
X1351461D03*
X1360044Y1028055D03*
X1352642D03*
X1358193Y1031244D03*
X1360044Y1040811D03*
Y1034433D03*
X1358193Y1037622D03*
Y1044000D03*
X1354493D03*
X1363745Y1059945D03*
X1360044D03*
Y1047189D03*
X1358193Y1050378D03*
X1360044Y1053567D03*
X1361894Y1056756D03*
X1358193D03*
X1352642Y1053567D03*
X1361894Y1069512D03*
Y1063134D03*
X1363745Y1072701D03*
X1360044D03*
X1356343Y1066323D03*
X1361894Y1075890D03*
Y1088646D03*
Y1082268D03*
X1363745Y1085457D03*
X1360044D03*
X1356343Y1079079D03*
X1361894Y1095024D03*
X1363745Y1098213D03*
X1360044D03*
X1356343Y1091835D03*
X1358193Y1101402D03*
X1361894D03*
Y1114158D03*
Y1107780D03*
X1363745Y1117347D03*
X1360044D03*
X1356343Y1110969D03*
X1361894Y1120536D03*
Y1126914D03*
Y1133292D03*
X1363745Y1130102D03*
X1360044D03*
X1356343Y1123725D03*
X1361894Y1139669D03*
Y1146047D03*
X1360044Y1142858D03*
X1363745D03*
X1356343Y1149236D03*
Y1136480D03*
X1358193Y1152425D03*
X1356343Y1161992D03*
X1360044D03*
X1352436Y1549970D03*
X1357161D03*
X1361885D03*
X1354011Y1552698D03*
X1358735D03*
X1363460D03*
X1352436Y1563608D03*
X1357161D03*
X1361885D03*
X1354011Y1566336D03*
X1358735D03*
X1363460D03*
X1369965Y876434D03*
X1366264D03*
X1377367D03*
X1368115Y879623D03*
X1371815D03*
X1375516Y892379D03*
X1371815D03*
X1368115Y886001D03*
X1369965Y895568D03*
X1373666D03*
X1366264Y889190D03*
X1377366D03*
X1379216Y886001D03*
X1371815D03*
X1375516D03*
Y898757D03*
Y905134D03*
X1371815Y898757D03*
Y905134D03*
X1375516Y911512D03*
X1371815D03*
X1369965Y908324D03*
X1373666D03*
X1375516Y917890D03*
Y924268D03*
X1371815Y917890D03*
Y924268D03*
X1369965Y921079D03*
X1373666D03*
X1375516Y930646D03*
X1371815D03*
X1369965Y940213D03*
X1373666D03*
X1371815Y937024D03*
X1379217D03*
X1368115D03*
X1375516D03*
X1371815Y956158D03*
Y943402D03*
Y949780D03*
X1375516Y956158D03*
Y943402D03*
Y949780D03*
X1369965Y952969D03*
X1373666D03*
X1371815Y962536D03*
Y968914D03*
X1375516Y962536D03*
Y968914D03*
X1369965Y965725D03*
X1373666D03*
X1371815Y975292D03*
X1375516D03*
X1366264Y984859D03*
X1369965Y978481D03*
X1373666D03*
X1371815Y981670D03*
X1379217D03*
X1373666Y984859D03*
Y991237D03*
X1371815Y988048D03*
Y994426D03*
Y1000804D03*
X1366264Y997615D03*
Y991237D03*
X1379217Y988048D03*
Y994426D03*
X1373666Y997615D03*
X1379217Y1000804D03*
X1366264Y1003993D03*
X1379217Y1007182D03*
X1377367Y1010371D03*
X1373666Y1003993D03*
X1369965Y1010371D03*
X1378548Y1028055D03*
X1367445D03*
X1374847Y1040811D03*
X1378548Y1034433D03*
X1372997Y1037622D03*
Y1044000D03*
X1367445Y1040811D03*
Y1034433D03*
X1365595Y1031244D03*
Y1037622D03*
Y1044000D03*
X1372997Y1031244D03*
X1374847Y1047189D03*
Y1053567D03*
X1371146Y1059945D03*
X1372997Y1056756D03*
Y1050378D03*
X1374847Y1059945D03*
X1365595Y1056756D03*
X1367445Y1047189D03*
Y1053567D03*
X1365595Y1050378D03*
X1372997Y1069512D03*
Y1063134D03*
X1365595Y1069512D03*
Y1063134D03*
X1376697Y1069512D03*
Y1063134D03*
X1371146Y1072701D03*
X1374847D03*
X1372997Y1075890D03*
X1365595D03*
X1376697D03*
X1372997Y1088646D03*
Y1082268D03*
X1365595Y1088646D03*
Y1082268D03*
X1376697Y1088646D03*
Y1082268D03*
X1374847Y1085457D03*
X1371146D03*
X1372997Y1095024D03*
X1365595D03*
X1376697D03*
X1374847Y1098213D03*
X1371146D03*
X1372997Y1101402D03*
X1376697D03*
X1369296D03*
X1365595D03*
Y1114158D03*
Y1107780D03*
X1376697Y1114158D03*
Y1107780D03*
X1372997Y1114158D03*
Y1107780D03*
X1374847Y1117347D03*
X1371146D03*
X1365595Y1120536D03*
X1376697D03*
Y1126914D03*
X1372997Y1120536D03*
Y1126914D03*
X1365595D03*
Y1133292D03*
X1376697D03*
X1372997D03*
X1371146Y1130102D03*
X1374847D03*
X1365595Y1139669D03*
Y1146047D03*
X1376697Y1139669D03*
Y1146047D03*
X1372997Y1139669D03*
Y1146047D03*
X1374847Y1142858D03*
X1371146D03*
X1378548Y1149236D03*
X1367445D03*
X1369296Y1152425D03*
X1371146Y1161992D03*
X1378548D03*
X1367445D03*
X1371334Y1549970D03*
X1376058D03*
X1366609D03*
X1372909Y1552698D03*
X1377633D03*
X1368184D03*
X1371334Y1563608D03*
X1376058D03*
X1366609D03*
X1372909Y1566336D03*
X1377633D03*
X1368184D03*
X1388469Y876434D03*
X1392170D03*
X1381067D03*
X1390320Y879623D03*
X1394021D03*
X1386619Y892379D03*
X1394020D03*
X1382918D03*
X1381067Y895568D03*
X1384768D03*
X1390319Y886001D03*
X1392170Y895568D03*
X1388469Y889190D03*
X1394021Y886001D03*
X1386619Y905134D03*
Y898757D03*
X1394020Y905134D03*
Y898757D03*
X1382918Y905134D03*
Y898757D03*
X1386619Y911512D03*
X1394020D03*
X1382918D03*
X1384768Y908324D03*
X1392170D03*
X1381067Y908323D03*
X1386619Y924268D03*
Y917890D03*
X1394020Y924268D03*
Y917890D03*
X1382918Y924268D03*
Y917890D03*
X1384768Y921079D03*
X1381067D03*
X1392170D03*
X1394020Y937024D03*
X1382918Y930646D03*
X1386619D03*
X1384768Y940213D03*
X1381067D03*
X1394020Y930646D03*
X1392170Y940213D03*
X1381067Y933835D03*
X1386619Y937024D03*
X1384768Y933835D03*
X1382918Y937024D03*
X1394020Y956158D03*
Y943402D03*
Y949780D03*
X1382918Y956158D03*
Y943402D03*
Y949780D03*
X1386619Y956158D03*
Y943402D03*
Y949780D03*
X1384768Y952969D03*
X1381067D03*
X1392170D03*
X1394020Y962536D03*
Y968914D03*
X1382918Y962536D03*
Y968914D03*
X1386619Y962536D03*
Y968914D03*
X1384768Y965725D03*
X1381067D03*
X1392170D03*
X1394020Y975292D03*
X1382918D03*
X1386619D03*
X1381067Y978481D03*
X1384768D03*
X1386619Y981670D03*
X1381067Y984859D03*
X1392170Y978481D03*
X1394020Y981670D03*
X1388469Y984859D03*
X1386619Y988048D03*
X1394020D03*
X1381067Y991237D03*
X1388457Y997607D03*
X1388469Y991237D03*
X1382905Y1007174D03*
X1382236Y1028063D03*
X1380398Y1044000D03*
X1382246Y1040819D03*
X1389638D03*
X1382236Y1034441D03*
X1380398Y1037622D03*
Y1031244D03*
X1382249Y1047189D03*
X1389650D03*
X1380398Y1050378D03*
X1382249Y1059945D03*
Y1053567D03*
X1385949Y1059945D03*
X1380398Y1056756D03*
X1387800D03*
X1393351Y1059945D03*
X1387800Y1050378D03*
X1389650Y1053567D03*
X1384099Y1069512D03*
Y1063134D03*
X1387800Y1069512D03*
Y1063134D03*
X1382249Y1072701D03*
X1385949D03*
X1393351D03*
X1384099Y1075890D03*
X1387800D03*
X1384099Y1088646D03*
Y1082268D03*
X1387800Y1088646D03*
Y1082268D03*
X1382249Y1085457D03*
X1385949D03*
X1393351D03*
X1384099Y1095024D03*
X1387800D03*
X1382249Y1098213D03*
X1385949D03*
X1393351D03*
X1385949Y1104591D03*
X1384099Y1101402D03*
X1380398D03*
X1382249Y1104591D03*
X1387800Y1101402D03*
Y1114158D03*
X1384099D03*
Y1107780D03*
X1382249Y1117347D03*
X1385949D03*
X1387800Y1107780D03*
X1393351Y1117347D03*
X1387800Y1120536D03*
Y1126914D03*
X1384099Y1120536D03*
Y1126914D03*
X1387800Y1133292D03*
X1384099D03*
X1385949Y1130102D03*
X1382249D03*
X1393351D03*
X1387800Y1139669D03*
Y1146047D03*
X1384099Y1139669D03*
Y1146047D03*
X1382249Y1142858D03*
X1385949D03*
X1393351D03*
X1389650Y1149236D03*
X1380398Y1152425D03*
X1382249Y1161992D03*
X1391500Y1152425D03*
X1393351Y1161992D03*
X1389650D03*
X1380783Y1549970D03*
X1385507D03*
X1390232D03*
X1382357Y1552698D03*
X1387082D03*
X1391806D03*
X1380783Y1563608D03*
X1385507D03*
X1390232D03*
X1382357Y1566336D03*
X1387082D03*
X1391806D03*
X1399571Y876434D03*
X1403272D03*
X1405123Y879623D03*
X1401423D03*
X1406973Y895568D03*
X1397721Y892379D03*
X1403272Y895568D03*
X1401422Y886001D03*
X1395871Y895568D03*
X1399571Y889190D03*
X1408823Y892379D03*
X1405123D03*
X1397722Y886001D03*
X1408824D03*
X1405123D03*
X1406973Y908324D03*
Y901946D03*
X1397721Y905134D03*
Y898757D03*
X1403272Y908324D03*
Y901946D03*
X1397721Y911512D03*
X1395871Y908324D03*
X1408823Y911512D03*
X1405123D03*
X1408823Y898757D03*
X1405123D03*
X1406973Y921079D03*
Y914701D03*
X1397721Y924268D03*
Y917890D03*
X1403272Y921079D03*
Y914701D03*
X1395871Y921079D03*
X1408823Y924268D03*
X1405123D03*
X1403272Y940213D03*
X1406973D03*
X1397721Y937024D03*
X1406973Y927457D03*
X1403272D03*
X1397721Y930646D03*
X1395871Y940213D03*
X1406973Y933835D03*
X1403272D03*
Y952969D03*
Y946591D03*
X1406973Y952969D03*
Y946591D03*
X1397721Y956158D03*
Y943402D03*
Y949780D03*
X1395871Y952969D03*
X1405123Y943402D03*
X1408823D03*
X1405123Y956158D03*
X1408823D03*
X1403272Y959347D03*
Y965725D03*
X1406973Y959347D03*
Y965725D03*
X1397721Y962536D03*
Y968914D03*
X1405123D03*
X1395871Y965725D03*
X1408823Y968914D03*
X1403272Y978481D03*
Y972103D03*
X1406973Y978481D03*
Y972103D03*
X1397721Y975292D03*
X1395871Y978481D03*
X1401422Y981670D03*
X1395871Y984859D03*
X1408823Y981670D03*
X1403272Y984859D03*
X1401422Y988048D03*
X1395858Y997607D03*
X1395871Y991237D03*
X1403260Y997607D03*
X1408823Y988048D03*
X1403272Y991237D03*
X1397039Y1040819D03*
X1404441D03*
X1404453Y1059945D03*
X1408154D03*
X1397052Y1047189D03*
X1404453D03*
X1395201Y1050378D03*
X1402603Y1056756D03*
Y1050378D03*
X1395201Y1056756D03*
X1397052Y1059945D03*
Y1053567D03*
X1404453D03*
X1395201Y1063134D03*
X1404453Y1072701D03*
Y1066323D03*
X1395201Y1069512D03*
X1398902Y1063134D03*
X1408154Y1072701D03*
Y1066323D03*
X1398902Y1069512D03*
X1406304D03*
X1397052Y1072701D03*
X1395201Y1075890D03*
X1404453Y1079079D03*
X1398902Y1075890D03*
X1408154Y1079079D03*
X1395201Y1082268D03*
X1404453Y1085457D03*
X1395201Y1088646D03*
X1398902Y1082268D03*
X1408154Y1085457D03*
X1398902Y1088646D03*
X1397052Y1085457D03*
X1406304Y1082268D03*
X1395201Y1095024D03*
Y1101402D03*
X1404453Y1098213D03*
Y1091835D03*
X1398902Y1095024D03*
Y1101402D03*
X1408154Y1098213D03*
Y1091835D03*
X1397052Y1098213D03*
X1406304Y1095024D03*
X1408154Y1104591D03*
X1404453D03*
X1398902Y1114158D03*
X1408154Y1117347D03*
Y1110969D03*
X1395201Y1114158D03*
X1404453Y1117347D03*
Y1110969D03*
X1398902Y1107780D03*
X1395201D03*
X1397052Y1117347D03*
X1406304Y1114158D03*
X1398902Y1120536D03*
Y1126914D03*
X1408154Y1123725D03*
X1395201Y1120536D03*
Y1126914D03*
X1404453Y1123725D03*
X1398902Y1133292D03*
X1408154Y1130102D03*
X1395201Y1133292D03*
X1404453Y1130102D03*
X1397052D03*
X1406304Y1126914D03*
X1398902Y1139669D03*
Y1146047D03*
X1408154Y1142858D03*
Y1136480D03*
X1395201Y1139669D03*
Y1146047D03*
X1404453Y1142858D03*
Y1136480D03*
X1397052Y1142858D03*
X1400752Y1149236D03*
X1406304Y1139669D03*
Y1146047D03*
X1402603Y1152425D03*
X1400752Y1161992D03*
X1406304Y1152425D03*
X1404453Y1161992D03*
X1408154Y1155614D03*
X1394956Y1549970D03*
X1396531Y1552698D03*
X1399256Y1540355D03*
X1401356D03*
X1402763Y1547073D03*
X1402707Y1549336D03*
X1394956Y1563608D03*
X1396531Y1566336D03*
X1403058Y1567540D03*
X1403059Y1564618D03*
X1402970Y1561698D03*
X1402473Y1571658D03*
X1423602Y892379D03*
Y911512D03*
Y898757D03*
Y924268D03*
Y943402D03*
Y956158D03*
Y968914D03*
X1410674Y984859D03*
X1410661Y997607D03*
X1410674Y991237D03*
X1411855Y1047189D03*
X1410004Y1050378D03*
X1411855Y1053567D03*
X1410004Y1056756D03*
Y1069512D03*
Y1082268D03*
Y1095024D03*
Y1114158D03*
Y1126914D03*
Y1139669D03*
Y1146047D03*
Y1152425D03*
Y1158803D03*
X1438405Y879623D03*
X1431003Y873245D03*
X1434704Y879623D03*
Y873245D03*
X1438405D03*
X1429153Y876434D03*
X1432854D03*
X1436554Y882812D03*
X1431003Y886001D03*
X1427302D03*
Y892379D03*
X1432854Y889190D03*
X1436554Y895568D03*
X1438405Y886001D03*
X1434704Y911512D03*
X1438405D03*
X1427302D03*
X1436554Y908324D03*
X1427302Y898757D03*
X1434704Y917890D03*
Y924268D03*
X1425452Y914701D03*
Y921079D03*
X1438405Y917890D03*
Y924268D03*
X1429153Y914701D03*
Y921079D03*
X1427302Y924268D03*
X1436554Y921079D03*
X1438405Y937024D03*
X1429153Y940213D03*
X1434704Y937024D03*
X1425452Y940213D03*
Y927457D03*
X1429153D03*
Y933835D03*
X1425452D03*
X1434704Y930646D03*
X1438405D03*
X1436554Y940213D03*
X1438405Y943402D03*
Y956158D03*
X1429153Y946591D03*
Y952969D03*
X1438405Y949780D03*
X1434704Y943402D03*
Y956158D03*
X1425452Y946591D03*
Y952969D03*
X1434704Y949780D03*
X1427302Y943402D03*
Y956158D03*
X1436554Y952969D03*
X1438405Y962536D03*
X1429153Y965725D03*
Y959347D03*
X1438405Y968914D03*
X1434704Y962536D03*
X1425452Y965725D03*
Y959347D03*
X1434704Y968914D03*
X1427302D03*
X1436554Y965725D03*
X1438405Y975292D03*
X1429153Y972103D03*
Y978481D03*
X1434704Y975292D03*
X1425452Y972103D03*
Y978481D03*
X1427302Y981670D03*
X1434704D03*
X1425452Y984859D03*
X1432854D03*
X1436554Y978481D03*
X1434704Y988048D03*
X1425465Y997607D03*
X1432866D03*
X1427302Y988048D03*
X1425452Y991237D03*
X1432854D03*
X1434047Y1040819D03*
X1430334Y1059945D03*
X1426633D03*
X1434035Y1047189D03*
X1426633D03*
X1435885Y1050378D03*
X1428483D03*
X1437735Y1059945D03*
X1435885Y1056756D03*
X1428483D03*
X1426633Y1053567D03*
X1434035D03*
X1430334Y1066323D03*
Y1072701D03*
X1426633Y1066323D03*
Y1072701D03*
X1435885Y1063134D03*
Y1069512D03*
X1428483D03*
X1424783D03*
X1437735Y1072701D03*
X1430334Y1079079D03*
X1426633D03*
X1435885Y1075890D03*
Y1088646D03*
X1428483Y1082268D03*
X1424783D03*
X1437735Y1085457D03*
X1430334D03*
X1426633D03*
X1435885Y1082268D03*
Y1101402D03*
Y1095024D03*
X1428483D03*
X1424783D03*
X1430334Y1104591D03*
X1426633D03*
X1437735Y1098213D03*
X1430334Y1091835D03*
Y1098213D03*
X1426633Y1091835D03*
Y1098213D03*
Y1110969D03*
Y1117347D03*
X1435885Y1114158D03*
X1430334Y1110969D03*
Y1117347D03*
X1428483Y1114158D03*
X1424783D03*
X1435885Y1107780D03*
X1437735Y1117347D03*
X1430334Y1130102D03*
X1426633D03*
Y1123725D03*
X1435885Y1126914D03*
Y1120536D03*
X1430334Y1123725D03*
X1424783Y1126914D03*
X1428483D03*
X1437735Y1130102D03*
X1435885Y1133292D03*
Y1146047D03*
Y1139669D03*
X1428483D03*
X1424783D03*
X1434035Y1149236D03*
X1428483Y1146047D03*
X1424783D03*
X1437735Y1142858D03*
X1426633Y1136480D03*
Y1142858D03*
X1430334Y1136480D03*
Y1142858D03*
X1426633Y1161992D03*
X1424783Y1152425D03*
X1426633Y1155614D03*
X1428483Y1152425D03*
X1432184D03*
X1434035Y1161992D03*
X1430334D03*
X1424783Y1158803D03*
X1432184D03*
X1434035Y1155614D03*
X1428484Y1158803D03*
X1437735Y1155614D03*
X1443956Y876434D03*
X1440255D03*
X1451358D03*
X1449507Y873245D03*
X1453208D03*
X1440255Y882812D03*
X1442106Y886001D03*
X1443956Y889190D03*
X1447657Y895568D03*
X1440255D03*
X1453208Y886001D03*
X1451358Y895568D03*
X1445806Y911512D03*
X1449507D03*
X1447657Y908324D03*
X1440255D03*
X1451357D03*
X1445806Y917890D03*
Y924268D03*
X1449507Y917890D03*
Y924268D03*
X1447657Y921079D03*
X1440255D03*
X1451357D03*
X1445806Y930646D03*
X1449507D03*
X1447657Y940213D03*
X1440255D03*
X1451357D03*
X1442106Y930646D03*
X1453208Y937024D03*
X1445806D03*
X1451357Y933835D03*
X1447657D03*
X1449507Y937024D03*
Y949780D03*
Y943402D03*
Y956158D03*
X1445806Y949780D03*
Y943402D03*
Y956158D03*
X1447657Y952969D03*
X1440255D03*
X1451357D03*
X1449507Y968914D03*
Y962536D03*
X1445806Y968914D03*
Y962536D03*
X1440255Y965725D03*
X1447657D03*
X1451357D03*
X1449507Y975292D03*
X1445806D03*
X1440255Y978481D03*
X1447657D03*
X1442106Y981670D03*
X1449507D03*
X1447657Y984859D03*
X1440255D03*
X1451357Y978481D03*
X1449507Y988048D03*
X1440268Y997607D03*
X1447669D03*
X1442106Y988048D03*
X1440255Y991237D03*
X1447657D03*
X1441449Y1040819D03*
X1448850D03*
X1441436Y1047189D03*
X1448838D03*
X1450688Y1050378D03*
Y1056756D03*
X1441436Y1059945D03*
Y1053567D03*
X1443287Y1056756D03*
X1448838Y1053567D03*
X1443287Y1050378D03*
X1448838Y1059945D03*
X1452539D03*
X1439586Y1063134D03*
Y1069512D03*
X1450688Y1063134D03*
Y1069512D03*
X1446987Y1063134D03*
Y1069512D03*
X1441436Y1072701D03*
X1448838D03*
X1452539D03*
X1439586Y1075890D03*
X1450688D03*
X1446987D03*
X1439586Y1088646D03*
X1450688Y1082268D03*
X1446987D03*
X1448838Y1085457D03*
X1441436D03*
X1452539D03*
X1439586Y1082268D03*
X1450688Y1088646D03*
X1446987D03*
X1439586Y1101402D03*
Y1095024D03*
X1448838Y1098213D03*
X1441436D03*
X1452539D03*
X1448838Y1104591D03*
X1452539D03*
X1446987Y1101402D03*
X1450688D03*
Y1095024D03*
X1446987D03*
Y1114158D03*
X1439586D03*
X1450688D03*
Y1107780D03*
X1446987D03*
X1439586D03*
X1448838Y1117347D03*
X1441436D03*
X1452539D03*
X1446987Y1126914D03*
Y1120536D03*
X1439586Y1126914D03*
Y1120536D03*
X1450688Y1126914D03*
Y1120536D03*
X1446987Y1133292D03*
X1450688D03*
X1448838Y1130102D03*
X1441436D03*
X1452539Y1130103D03*
X1439586Y1133292D03*
X1446987Y1139669D03*
X1450688D03*
X1446987Y1146047D03*
X1439586D03*
Y1139669D03*
X1450688Y1146047D03*
X1448838Y1142858D03*
X1441436D03*
X1445137Y1149236D03*
X1452539Y1142858D03*
X1446987Y1152425D03*
X1443287Y1165181D03*
X1439586Y1158803D03*
X1443287Y1152425D03*
X1452539Y1161992D03*
X1441436D03*
X1445137D03*
X1448838Y1155614D03*
X1439586Y1152425D03*
X1445137Y1155614D03*
X1443287Y1158803D03*
X1450627Y1540509D03*
X1452827D03*
X1450792Y1546218D03*
X1449133Y1551121D03*
X1449534Y1554612D03*
X1449580Y1568698D03*
Y1570898D03*
X1451027Y1573317D03*
X1462460Y876434D03*
X1455058D03*
X1466161D03*
X1464310Y873245D03*
X1460609D03*
Y879623D03*
X1464310D03*
Y886001D03*
X1458759Y895568D03*
X1462460D03*
X1466161Y889190D03*
X1455058D03*
X1460609Y886001D03*
X1456909D03*
X1468011D03*
X1456909Y911512D03*
X1460609D03*
X1458759Y908324D03*
X1462460D03*
X1468011Y924268D03*
Y917890D03*
X1456909Y924268D03*
Y917890D03*
X1460609Y924268D03*
Y917890D03*
X1458759Y921079D03*
X1462460D03*
X1468011Y930646D03*
X1456909D03*
X1460609D03*
X1462460Y940213D03*
X1458759D03*
X1456909Y937024D03*
X1464310D03*
X1460609D03*
X1468011D03*
X1460609Y949780D03*
Y943402D03*
Y956158D03*
X1468011Y949780D03*
Y943402D03*
Y956158D03*
X1456909Y949780D03*
Y943402D03*
Y956158D03*
X1458759Y952969D03*
X1462460D03*
X1460609Y968914D03*
Y962536D03*
X1468011Y968914D03*
Y962536D03*
X1456909Y968914D03*
Y962536D03*
X1462460Y965725D03*
X1458759D03*
X1460609Y975292D03*
X1468011D03*
X1456909D03*
X1462460Y978481D03*
X1458759D03*
X1464310Y981670D03*
X1456909D03*
X1462460Y984859D03*
X1455058D03*
X1464310Y988048D03*
Y994426D03*
X1456909Y988048D03*
Y994426D03*
X1462460Y997615D03*
Y991237D03*
X1455058Y997615D03*
Y991237D03*
X1456909Y1000804D03*
X1464310D03*
Y1007182D03*
X1456909D03*
X1462460Y1010371D03*
Y1003993D03*
X1455058Y1010371D03*
Y1003993D03*
X1459940Y1028055D03*
X1467342D03*
X1458090Y1037622D03*
Y1044000D03*
X1465491Y1037622D03*
Y1044000D03*
X1463641Y1040811D03*
X1456239D03*
X1459940Y1034433D03*
X1461791Y1031244D03*
X1454389D03*
X1467342Y1034433D03*
X1463641Y1047189D03*
X1456239D03*
X1465491Y1050378D03*
X1456239Y1053567D03*
X1463641D03*
X1458090Y1056756D03*
X1463641Y1059945D03*
X1465491Y1056756D03*
X1458090Y1050378D03*
X1459940Y1059945D03*
X1461791Y1063134D03*
Y1069512D03*
X1458090Y1063134D03*
Y1069512D03*
X1463641Y1072701D03*
X1459940D03*
X1461791Y1075890D03*
X1458090D03*
X1463641Y1085457D03*
X1459940D03*
X1461791Y1082268D03*
Y1088646D03*
X1458090Y1082268D03*
Y1088646D03*
X1463641Y1098213D03*
X1459940D03*
X1454389Y1101402D03*
X1461791D03*
X1458090D03*
X1465491D03*
X1461791Y1095024D03*
X1458090D03*
Y1114158D03*
Y1107780D03*
X1461791Y1114158D03*
Y1107780D03*
X1459940Y1117347D03*
X1463641D03*
X1458090Y1133292D03*
X1461791D03*
X1458090Y1126914D03*
Y1120536D03*
X1461791Y1126914D03*
Y1120536D03*
X1459940Y1130102D03*
X1463641D03*
X1458090Y1146047D03*
Y1139669D03*
X1461791Y1146047D03*
Y1139669D03*
X1463641Y1142858D03*
X1459940D03*
X1456239Y1149236D03*
X1467342D03*
X1454389Y1158803D03*
X1467342Y1155614D03*
X1465491Y1158803D03*
X1459940Y1155614D03*
X1465491Y1152425D03*
X1454389D03*
X1467342Y1161992D03*
X1463641D03*
X1456239D03*
X1461791Y1165181D03*
X1458090Y1152425D03*
X1461791Y1158803D03*
X1456239Y1155614D03*
X1461777Y1552698D03*
X1460202Y1549970D03*
X1464926D03*
X1466501Y1552698D03*
X1460202Y1563608D03*
X1464926D03*
X1461777Y1566336D03*
X1466501D03*
X1455098Y1577625D03*
X1475413Y879623D03*
X1482814D03*
X1473562Y876434D03*
X1477263D03*
X1471712Y873245D03*
X1475413D03*
X1480964Y876434D03*
X1475413Y886001D03*
X1477263Y889190D03*
X1473562Y895568D03*
X1469861D03*
X1471712Y886001D03*
X1469861Y908324D03*
X1473562D03*
X1477263Y901946D03*
X1471712Y924268D03*
Y917890D03*
X1473562Y921079D03*
X1469861D03*
X1477263Y914701D03*
X1471712Y930646D03*
X1469861Y940213D03*
X1473562D03*
X1477263Y927457D03*
X1475413Y937024D03*
X1471712D03*
Y949780D03*
Y943402D03*
Y956158D03*
X1473562Y952969D03*
X1469861D03*
X1477263Y946591D03*
X1471712Y968914D03*
Y962536D03*
X1473562Y965725D03*
X1469861D03*
X1477263Y959347D03*
X1471712Y975292D03*
Y981670D03*
X1473562Y978481D03*
X1469861D03*
Y984859D03*
X1477263Y972103D03*
Y984859D03*
Y991237D03*
X1469861Y997615D03*
Y991237D03*
X1471712Y988048D03*
Y994426D03*
X1477263Y997615D03*
X1471712Y1000804D03*
X1479113Y994426D03*
X1471712Y1007182D03*
X1477263Y1010371D03*
Y1003993D03*
X1469861Y1010371D03*
Y1003993D03*
X1480964Y1010371D03*
X1474743Y1028055D03*
X1482145D03*
X1478444Y1040811D03*
X1471043D03*
X1472893Y1037622D03*
Y1044000D03*
X1474743Y1034433D03*
X1476594Y1031244D03*
X1469192D03*
X1472893Y1050378D03*
X1478444Y1047189D03*
X1471043D03*
X1478444Y1053567D03*
X1472893Y1056756D03*
X1471043Y1053567D03*
X1474743Y1059945D03*
X1471043D03*
X1482145Y1053567D03*
X1472893Y1063134D03*
Y1069512D03*
X1469192Y1063134D03*
Y1069512D03*
X1478444Y1066323D03*
X1471043Y1072701D03*
X1474743D03*
X1472893Y1075890D03*
X1469192D03*
X1478444Y1079079D03*
X1474743Y1085457D03*
X1471043D03*
X1472893Y1082268D03*
Y1088646D03*
X1469192Y1082268D03*
Y1088646D03*
X1478444Y1091835D03*
X1476594Y1101402D03*
X1474743Y1098213D03*
X1471043D03*
X1469192Y1101402D03*
X1472893Y1095024D03*
X1469192D03*
Y1107780D03*
Y1114158D03*
X1472893Y1107780D03*
Y1114158D03*
X1478444Y1110969D03*
X1474743Y1117347D03*
X1471043D03*
X1469192Y1120536D03*
X1472893D03*
X1478444Y1123725D03*
X1474743Y1130102D03*
X1471043D03*
X1469192Y1133292D03*
Y1126914D03*
X1472893Y1133292D03*
Y1126914D03*
X1478444Y1136480D03*
X1474743Y1142858D03*
X1471043D03*
X1478444Y1149236D03*
X1469192Y1146047D03*
Y1139669D03*
X1472893Y1146047D03*
Y1139669D03*
Y1158803D03*
X1471043Y1155614D03*
Y1161992D03*
X1469192Y1152425D03*
X1476594D03*
X1478444Y1161992D03*
X1474743D03*
X1476594Y1158803D03*
X1476778Y1165778D03*
X1479099Y1549970D03*
X1483824D03*
X1480674Y1552698D03*
X1469651Y1549970D03*
X1474375D03*
X1471225Y1552698D03*
X1475950D03*
X1469651Y1563608D03*
X1474375D03*
X1479099D03*
X1483824D03*
X1471225Y1566336D03*
X1475950D03*
X1480674D03*
X1486515Y879623D03*
X1490216D03*
X1484665Y876434D03*
X1488365D03*
X1497617Y886001D03*
X1492066Y889190D03*
X1493917Y892379D03*
X1492066Y895568D03*
X1497617Y892379D03*
X1488365Y895568D03*
X1492066Y882812D03*
X1493917Y911512D03*
X1497617Y898757D03*
X1492066Y901946D03*
X1493917Y905134D03*
X1497617D03*
X1492066Y908324D03*
X1497617Y911512D03*
X1493917Y898757D03*
X1490216Y905134D03*
X1497617Y917890D03*
X1492066Y921079D03*
X1493917Y924268D03*
X1497617D03*
X1492066Y914701D03*
X1493917Y917890D03*
X1488365Y914701D03*
X1490216Y924268D03*
X1492066Y927457D03*
X1493917Y930646D03*
X1497617Y937024D03*
X1492066Y940213D03*
Y933835D03*
X1497617Y930646D03*
X1493917Y937024D03*
X1488365Y933835D03*
X1493917Y943402D03*
X1497617D03*
X1492066Y946591D03*
X1493917Y949780D03*
X1497617Y956158D03*
X1492066Y952969D03*
X1497617Y949780D03*
X1493917Y956158D03*
X1490216Y943402D03*
X1488365Y952969D03*
X1497617Y962536D03*
X1492066Y965725D03*
X1493917Y968914D03*
X1492066Y959347D03*
X1493917Y962536D03*
X1497617Y968914D03*
X1490216Y962536D03*
X1492066Y984859D03*
X1497617Y975292D03*
X1492066Y978481D03*
X1493917Y981670D03*
X1492066Y972103D03*
X1493917Y975292D03*
X1490216Y981670D03*
X1488365Y972103D03*
X1493917Y988048D03*
X1497617Y994426D03*
X1492066Y997615D03*
X1493917Y1000804D03*
X1497617D03*
Y988048D03*
X1492066Y991237D03*
X1488365D03*
X1490216Y1000804D03*
X1493917Y994426D03*
X1484665Y991237D03*
X1497617Y1007182D03*
X1492066Y1003993D03*
X1493917Y1007182D03*
X1488365Y1010371D03*
X1492066D03*
X1493247Y1028055D03*
X1485846D03*
X1495098Y1031244D03*
X1493247Y1034433D03*
X1498799Y1037622D03*
X1495098D03*
X1493247Y1040811D03*
X1495098Y1044000D03*
X1491397Y1037622D03*
X1498798Y1044000D03*
Y1031244D03*
X1487696Y1044000D03*
Y1031244D03*
X1495098Y1050378D03*
X1493247Y1047189D03*
X1498799Y1050378D03*
X1489547Y1047189D03*
X1491397Y1056756D03*
X1498798D03*
X1493247Y1053567D03*
X1487696Y1056756D03*
X1485846Y1047189D03*
X1495098Y1063134D03*
X1498799D03*
X1493247Y1066323D03*
X1495098Y1069512D03*
X1498799D03*
X1493247Y1072701D03*
X1489547Y1066323D03*
X1495098Y1075890D03*
X1498799D03*
X1493247Y1079079D03*
X1495098Y1082268D03*
X1498799D03*
X1493247Y1085457D03*
X1498799Y1088646D03*
X1495098D03*
X1491397Y1075890D03*
X1489547Y1085457D03*
X1498799Y1101402D03*
X1493247Y1104591D03*
X1495098Y1095024D03*
X1498799D03*
X1493247Y1098213D03*
X1495098Y1101402D03*
X1493247Y1091835D03*
X1491397Y1095024D03*
X1489547Y1104591D03*
X1495098Y1114158D03*
X1498799D03*
X1493247Y1117347D03*
X1498799Y1107780D03*
X1495098D03*
X1493247Y1110969D03*
X1491397Y1114158D03*
X1495098Y1120536D03*
X1498799D03*
X1493247Y1123725D03*
X1495098Y1133292D03*
X1498799D03*
Y1126914D03*
X1495098D03*
X1493247Y1130102D03*
X1491397Y1133292D03*
X1489547Y1123725D03*
X1493247Y1136480D03*
X1495098Y1139669D03*
X1498799D03*
X1493247Y1142858D03*
X1498799Y1146047D03*
X1495098D03*
X1493247Y1149236D03*
X1489547Y1142858D03*
X1495098Y1152425D03*
X1498799D03*
X1491397D03*
X1489547Y1161992D03*
X1485846D03*
X1487696Y1158803D03*
X1497997Y1549970D03*
X1488548D03*
X1493273D03*
X1485399Y1552698D03*
X1490123D03*
X1494847D03*
X1488548Y1563608D03*
X1493273D03*
X1497997D03*
X1485399Y1566336D03*
X1490123D03*
X1494847D03*
X1506869Y876434D03*
X1512421Y879623D03*
X1505019D03*
X1512421Y886001D03*
X1506869Y889190D03*
X1510570D03*
X1505019Y892379D03*
X1510570Y895568D03*
X1506869D03*
X1512421Y892379D03*
X1499468Y889190D03*
Y895568D03*
X1506869Y882812D03*
X1510570Y908324D03*
X1505019Y911512D03*
X1512421Y898757D03*
X1506869Y901946D03*
X1510570D03*
X1505019Y905134D03*
X1512421D03*
X1506869Y908324D03*
X1512421Y911512D03*
X1505019Y898757D03*
X1499468Y908324D03*
Y901946D03*
X1512421Y917890D03*
X1506869Y921079D03*
X1510570D03*
X1505019Y924268D03*
X1512421D03*
X1510570Y914701D03*
X1506869D03*
X1505019Y917890D03*
X1499468Y921079D03*
Y914701D03*
X1506869Y927457D03*
X1510570D03*
X1505019Y930646D03*
X1512421Y937024D03*
X1506869Y940213D03*
X1510570D03*
Y933835D03*
X1506869D03*
X1512421Y930646D03*
X1505019Y937024D03*
X1499468Y927457D03*
Y940213D03*
Y933835D03*
X1505019Y943402D03*
X1512421D03*
X1506869Y946591D03*
X1510570D03*
X1505019Y949780D03*
X1512421Y956158D03*
X1510570Y952969D03*
X1506869D03*
X1512421Y949780D03*
X1505019Y956158D03*
X1499468Y946591D03*
Y952969D03*
X1512421Y962536D03*
X1506869Y965725D03*
X1510570D03*
X1505019Y968914D03*
X1506869Y959347D03*
X1510570D03*
X1505019Y962536D03*
X1512421Y968914D03*
X1499468Y965725D03*
Y959347D03*
X1506869Y984859D03*
X1512421Y975292D03*
X1506869Y978481D03*
X1510570D03*
X1505019Y981670D03*
X1510570Y972103D03*
X1506869D03*
X1505019Y975292D03*
X1499468Y978481D03*
Y972103D03*
X1505019Y988048D03*
X1512421Y994426D03*
X1510570Y997615D03*
X1506869D03*
X1505019Y1000804D03*
X1512421D03*
Y988048D03*
X1506869Y991237D03*
X1499468Y997615D03*
Y991237D03*
X1505019Y994426D03*
X1510570Y991237D03*
Y1010371D03*
X1512421Y1007182D03*
X1510570Y1003993D03*
X1506869D03*
X1505019Y1007182D03*
X1499468Y1010371D03*
Y1003993D03*
X1506869Y1010371D03*
X1508050Y1028055D03*
X1500649D03*
X1511751D03*
X1506200Y1031244D03*
X1508050Y1034433D03*
X1511751D03*
X1513602Y1037622D03*
X1506200D03*
X1508050Y1040811D03*
X1511751D03*
X1506200Y1044000D03*
X1500649Y1034433D03*
Y1040811D03*
X1513602Y1044000D03*
Y1031244D03*
X1506200Y1050378D03*
X1511751Y1059945D03*
X1508050Y1047189D03*
X1513602Y1050378D03*
X1511751Y1053567D03*
X1500649Y1059945D03*
Y1053567D03*
Y1047189D03*
X1513602Y1056756D03*
X1511751Y1047189D03*
X1508050Y1053567D03*
X1511751Y1072701D03*
X1506200Y1063134D03*
X1513602D03*
X1508050Y1066323D03*
X1506200Y1069512D03*
X1513602D03*
X1508050Y1072701D03*
X1511751Y1066323D03*
X1500649Y1072701D03*
Y1066323D03*
X1506200Y1075890D03*
X1513602D03*
X1508050Y1079079D03*
X1511751D03*
X1506200Y1082268D03*
X1513602D03*
X1508050Y1085457D03*
X1513602Y1088646D03*
X1506200D03*
X1511751Y1085457D03*
X1500649Y1079079D03*
Y1085457D03*
X1513602Y1101402D03*
X1508050Y1104591D03*
X1511751Y1091835D03*
X1506200Y1095024D03*
X1513602D03*
X1508050Y1098213D03*
X1511751D03*
X1506200Y1101402D03*
X1511751Y1104591D03*
X1508050Y1091835D03*
X1500649D03*
Y1098213D03*
Y1104591D03*
X1511751Y1110969D03*
X1506200Y1114158D03*
X1513602D03*
X1508050Y1117347D03*
X1511751D03*
X1513602Y1107780D03*
X1506200D03*
X1508050Y1110969D03*
X1500649D03*
Y1117347D03*
X1506200Y1120536D03*
X1513602D03*
X1508050Y1123725D03*
X1511751Y1130102D03*
X1506200Y1133292D03*
X1513602D03*
Y1126914D03*
X1506200D03*
X1511751Y1123725D03*
X1508050Y1130102D03*
X1500649D03*
Y1123725D03*
X1508050Y1136480D03*
X1511751D03*
X1506200Y1139669D03*
X1513602D03*
X1508050Y1142858D03*
X1511751Y1149236D03*
X1513602Y1146047D03*
X1506200D03*
X1511751Y1142858D03*
X1508050Y1149236D03*
X1500649Y1136480D03*
Y1149236D03*
Y1142858D03*
X1506200Y1152425D03*
X1513602D03*
X1508050Y1155614D03*
X1500649D03*
X1513602Y1158803D03*
X1500649Y1161992D03*
X1504350D03*
X1507446Y1549970D03*
X1512170D03*
X1502721D03*
X1509021Y1552698D03*
X1513745D03*
X1499572D03*
X1504296D03*
X1507446Y1563608D03*
X1512170D03*
X1502721D03*
X1509021Y1566336D03*
X1513745D03*
X1499572D03*
X1504296D03*
X1527224Y873245D03*
X1516121D03*
X1519822D03*
X1514271Y876434D03*
X1523523Y879623D03*
X1525373Y876434D03*
X1523523Y886001D03*
X1517972Y889190D03*
X1525373D03*
X1519822Y892379D03*
X1525373Y895568D03*
X1517972D03*
X1523523Y892379D03*
X1516121Y886001D03*
X1514271Y895568D03*
X1525373Y908324D03*
X1519822Y911512D03*
X1523523Y898757D03*
X1517972Y901946D03*
X1525373D03*
X1519822Y905134D03*
X1523523D03*
X1517972Y908324D03*
X1523523Y911512D03*
X1519822Y898757D03*
X1516121Y905134D03*
X1523523Y917890D03*
X1517972Y921079D03*
X1525373D03*
X1519822Y924268D03*
X1523523D03*
X1525373Y914701D03*
X1517972D03*
X1519822Y917890D03*
X1516121Y924268D03*
X1514271Y914701D03*
X1517972Y927457D03*
X1525373D03*
X1519822Y930646D03*
X1523523Y937024D03*
X1517972Y940213D03*
X1525373D03*
Y933835D03*
X1517972D03*
X1523523Y930646D03*
X1519822Y937024D03*
X1514271Y933835D03*
X1519822Y943402D03*
X1523523D03*
X1517972Y946591D03*
X1525373D03*
X1519822Y949780D03*
X1523523Y956158D03*
X1525373Y952969D03*
X1517972D03*
X1523523Y949780D03*
X1519822Y956158D03*
X1516121Y943402D03*
X1514271Y952969D03*
X1523523Y962536D03*
X1517972Y965725D03*
X1525373D03*
X1519822Y968914D03*
X1517972Y959347D03*
X1525373D03*
X1519822Y962536D03*
X1523523Y968914D03*
X1516121Y962536D03*
X1517972Y984859D03*
X1523523Y975292D03*
X1517972Y978481D03*
X1525373D03*
X1519822Y981670D03*
X1525373Y972103D03*
X1517972D03*
X1519822Y975292D03*
X1516121Y981670D03*
X1514271Y972103D03*
X1519822Y988048D03*
X1523523Y994426D03*
X1525373Y997615D03*
X1517972D03*
X1519822Y1000804D03*
X1523523D03*
Y988048D03*
X1517972Y991237D03*
X1516121Y1000804D03*
X1514271Y991237D03*
X1519822Y994426D03*
X1525373Y991237D03*
Y1010371D03*
X1523523Y1007182D03*
X1525373Y1003993D03*
X1517972D03*
X1519822Y1007182D03*
X1514271Y1010371D03*
X1517972D03*
X1519153Y1028055D03*
X1526554D03*
X1521003Y1031244D03*
X1519153Y1034433D03*
X1526554D03*
X1524704Y1037622D03*
X1521003D03*
X1519153Y1040811D03*
X1526554D03*
X1521003Y1044000D03*
X1517302Y1037622D03*
X1524704Y1044000D03*
Y1031244D03*
X1521003Y1050378D03*
X1526554Y1059945D03*
X1519153Y1047189D03*
X1524704Y1050378D03*
X1526554Y1053567D03*
X1517302Y1056756D03*
X1515452Y1047189D03*
X1524704Y1056756D03*
X1526554Y1047189D03*
X1519153Y1053567D03*
X1526554Y1072701D03*
X1521003Y1063134D03*
X1524704D03*
X1519153Y1066323D03*
X1521003Y1069512D03*
X1524704D03*
X1519153Y1072701D03*
X1526554Y1066323D03*
X1515452D03*
X1521003Y1075890D03*
X1524704D03*
X1519153Y1079079D03*
X1526554D03*
X1521003Y1082268D03*
X1524704D03*
X1519153Y1085457D03*
X1524704Y1088646D03*
X1521003D03*
X1526554Y1085457D03*
X1515452D03*
X1517302Y1075890D03*
X1524704Y1101402D03*
X1519153Y1104591D03*
X1526554Y1091835D03*
X1521003Y1095024D03*
X1524704D03*
X1519153Y1098213D03*
X1526554D03*
X1521003Y1101402D03*
X1526554Y1104591D03*
X1519153Y1091835D03*
X1515452Y1104591D03*
X1517302Y1095024D03*
X1526554Y1110969D03*
X1521003Y1114158D03*
X1524704D03*
X1519153Y1117347D03*
X1526554D03*
X1524704Y1107780D03*
X1521003D03*
X1519153Y1110969D03*
X1517302Y1114158D03*
X1521003Y1120536D03*
X1524704D03*
X1519153Y1123725D03*
X1526554Y1130102D03*
X1521003Y1133292D03*
X1524704D03*
Y1126914D03*
X1521003D03*
X1526554Y1123725D03*
X1519153Y1130102D03*
X1517302Y1133292D03*
X1515452Y1123725D03*
X1519153Y1136480D03*
X1526554D03*
X1521003Y1139669D03*
X1524704D03*
X1519153Y1142858D03*
X1526554Y1149236D03*
X1524704Y1146047D03*
X1521003D03*
X1526554Y1142858D03*
X1519153Y1149236D03*
X1515452Y1142858D03*
X1521003Y1152425D03*
X1524704D03*
X1526554Y1155614D03*
X1517302Y1152425D03*
X1521003Y1158803D03*
X1515452Y1161992D03*
X1516895Y1549970D03*
X1521619D03*
X1526344D03*
X1518469Y1552698D03*
X1523194D03*
X1527918D03*
X1516895Y1563608D03*
X1521619D03*
X1526344D03*
X1518469Y1566336D03*
X1523194D03*
X1527918D03*
X1542027Y879623D03*
X1540176Y876434D03*
X1530924Y873245D03*
X1534625Y879623D03*
X1536476Y876434D03*
X1538326Y886001D03*
X1532775Y889190D03*
X1536476D03*
X1530925Y892379D03*
X1536476Y895568D03*
X1532775D03*
X1538326Y892379D03*
X1540176Y895568D03*
X1542027Y886001D03*
X1532775Y882812D03*
X1536476Y908324D03*
X1530925Y911512D03*
X1538326Y898757D03*
X1532775Y901946D03*
X1536476D03*
X1530925Y905134D03*
X1538326D03*
X1532775Y908324D03*
X1538326Y911512D03*
X1530925Y898757D03*
X1542027Y905134D03*
X1538326Y917890D03*
X1532775Y921079D03*
X1536476D03*
X1530925Y924268D03*
X1538326D03*
X1536476Y914701D03*
X1532775D03*
X1530925Y917890D03*
X1542027Y924268D03*
X1540176Y914701D03*
X1532775Y927457D03*
X1536476D03*
X1530925Y930646D03*
X1538326Y937024D03*
X1532775Y940213D03*
X1536476D03*
Y933835D03*
X1532775D03*
X1538326Y930646D03*
X1530925Y937024D03*
X1540176Y933835D03*
X1530925Y943402D03*
X1538326D03*
X1532775Y946591D03*
X1536476D03*
X1530925Y949780D03*
X1538326Y956158D03*
X1536476Y952969D03*
X1532775D03*
X1538326Y949780D03*
X1530925Y956158D03*
X1540176Y952969D03*
X1542027Y943402D03*
X1538326Y962536D03*
X1532775Y965725D03*
X1536476D03*
X1530925Y968914D03*
X1532775Y959347D03*
X1536476D03*
X1530925Y962536D03*
X1538326Y968914D03*
X1542027Y962536D03*
X1532775Y984859D03*
X1538326Y975292D03*
X1532775Y978481D03*
X1536476D03*
X1530925Y981670D03*
X1536476Y972103D03*
X1532775D03*
X1530925Y975292D03*
X1542027Y981670D03*
X1540176Y972103D03*
X1530925Y988048D03*
X1538326Y994426D03*
X1536476Y997615D03*
X1532775D03*
X1530925Y1000804D03*
X1538326D03*
Y988048D03*
X1532775Y991237D03*
X1542027Y1000804D03*
X1540176Y991237D03*
X1530924Y994426D03*
X1536476Y991237D03*
Y1010371D03*
X1538326Y1007182D03*
X1536476Y1003993D03*
X1532775D03*
X1530925Y1007182D03*
X1540176Y1010371D03*
X1532775D03*
X1533956Y1028055D03*
X1537657D03*
X1532106Y1031244D03*
X1533956Y1034433D03*
X1537657D03*
X1539507Y1037622D03*
X1532106D03*
X1533956Y1040811D03*
X1537657D03*
X1532106Y1044000D03*
X1543208Y1037622D03*
X1539507Y1044000D03*
Y1031244D03*
X1532106Y1050378D03*
X1537657Y1059945D03*
X1533956Y1047189D03*
X1539507Y1050378D03*
X1537657Y1053567D03*
X1543208Y1056756D03*
X1541357Y1047189D03*
X1539507Y1056756D03*
X1537657Y1047189D03*
X1533956Y1053567D03*
X1537657Y1072701D03*
X1532106Y1063134D03*
X1539507D03*
X1533956Y1066323D03*
X1532106Y1069512D03*
X1539507D03*
X1533956Y1072701D03*
X1537657Y1066323D03*
X1541357D03*
X1532106Y1075890D03*
X1539507D03*
X1533956Y1079079D03*
X1537657D03*
X1532106Y1082268D03*
X1539507D03*
X1533956Y1085457D03*
X1539507Y1088646D03*
X1532106D03*
X1537657Y1085457D03*
X1541357D03*
X1543208Y1075890D03*
X1539507Y1101402D03*
X1533956Y1104591D03*
X1537657Y1091835D03*
X1532106Y1095024D03*
X1539507D03*
X1533956Y1098213D03*
X1537657D03*
X1532106Y1101402D03*
X1537657Y1104591D03*
X1533956Y1091835D03*
X1541357Y1104591D03*
X1543208Y1095024D03*
X1537657Y1110969D03*
X1532106Y1114158D03*
X1539507D03*
X1533956Y1117347D03*
X1537657D03*
X1539507Y1107780D03*
X1532106D03*
X1533956Y1110969D03*
X1543208Y1114158D03*
X1532106Y1120536D03*
X1539507D03*
X1533956Y1123725D03*
X1537657Y1130102D03*
X1532106Y1133292D03*
X1539507D03*
Y1126914D03*
X1532106D03*
X1537657Y1123725D03*
X1533956Y1130102D03*
X1543208Y1133292D03*
X1541357Y1123725D03*
X1533956Y1136480D03*
X1537657D03*
X1532106Y1139669D03*
X1539507D03*
X1533956Y1142858D03*
X1537657Y1149236D03*
X1539507Y1146047D03*
X1532106D03*
X1537657Y1142858D03*
X1533956Y1149236D03*
X1541357Y1142858D03*
X1533956Y1161992D03*
X1543208Y1158803D03*
X1532106Y1152425D03*
X1539507D03*
X1533956Y1155614D03*
X1539507Y1158803D03*
X1543208Y1152425D03*
X1537657Y1161992D03*
X1530255D03*
X1531068Y1549970D03*
X1532643Y1552698D03*
X1535368Y1540355D03*
X1537468D03*
X1538875Y1547073D03*
X1538819Y1549336D03*
X1531068Y1563608D03*
X1532643Y1566336D03*
X1539170Y1567540D03*
X1539171Y1564618D03*
X1539082Y1561698D03*
X1538585Y1571658D03*
X1539170Y1569640D03*
X1549428Y879623D03*
X1545728D03*
X1543877Y1010371D03*
X1545058Y1028055D03*
X1548759Y1161992D03*
X1546909Y1165181D03*
X1588264Y1549970D03*
X1580940Y1540460D03*
X1578689Y1540509D03*
X1578854Y1546218D03*
X1577195Y1551121D03*
X1588264Y1563608D03*
X1577596Y1554612D03*
X1577642Y1568698D03*
Y1570898D03*
X1583160Y1577625D03*
X1579089Y1573317D03*
X1592988Y1549970D03*
X1597713D03*
X1602437D03*
X1589839Y1552698D03*
X1594563D03*
X1599287D03*
X1592988Y1563608D03*
X1597713D03*
X1602437D03*
X1589839Y1566336D03*
X1594563D03*
X1599287D03*
X1607161Y1549970D03*
X1611886D03*
X1616610D03*
X1604012Y1552698D03*
X1608736D03*
X1613461D03*
X1607161Y1563608D03*
X1611886D03*
X1616610D03*
X1604012Y1566336D03*
X1608736D03*
X1613461D03*
X1621335Y1549970D03*
X1626059D03*
X1630783D03*
X1618185Y1552698D03*
X1622909D03*
X1627634D03*
X1632358D03*
X1621335Y1563608D03*
X1626059D03*
X1630783D03*
X1618185Y1566336D03*
X1622909D03*
X1627634D03*
X1632358D03*
X1635508Y1549970D03*
X1640232D03*
X1644957D03*
X1637083Y1552698D03*
X1641807D03*
X1646531D03*
X1635508Y1563608D03*
X1640232D03*
X1644957D03*
X1637083Y1566336D03*
X1641807D03*
X1646531D03*
X1649681Y1549970D03*
X1654406D03*
X1659130D03*
X1651256Y1552698D03*
X1655980D03*
X1660705D03*
X1649681Y1563608D03*
X1654406D03*
X1659130D03*
X1651256Y1566336D03*
X1655980D03*
X1660705D03*
X1663430Y1540355D03*
X1665530D03*
X1666937Y1547073D03*
X1666881Y1549336D03*
X1667231Y1567540D03*
X1667232Y1564618D03*
X1667143Y1561698D03*
X1670227Y1567413D03*
X1668750Y1563158D03*
X1666647Y1571658D03*
X1667231Y1569640D03*
G54D39*
X326731Y653394D03*
X363731D03*
X433624Y594259D03*
X754645Y1426892D03*
X766889Y1486756D03*
Y1530256D03*
X1166535Y1412479D03*
X1291146Y1375715D03*
X1320516D03*
X1415690Y601230D03*
X1487677Y640145D03*
X1524437Y640365D03*
X1701285Y198612D03*
X1700840Y1424519D03*
X1731660Y198612D03*
X1770442Y284934D03*
X1800002D03*
G54D25*
X79729Y289822D03*
Y310256D03*
X89729Y289822D03*
X99729D03*
X89729Y310256D03*
X99729D03*
X757184Y1712772D03*
Y1722772D03*
X1072863Y1419176D03*
Y1429176D03*
X1080970Y1650958D03*
Y1660958D03*
X1299439Y92812D03*
Y102812D03*
X1530377Y581353D03*
X1540377D03*
G54D67*
X1233404Y60384D03*
X1241278D03*
X1249152D03*
X1439049Y87432D03*
X1431175D03*
X1446923D03*
G54D23*
X64823Y756832D03*
Y760178D03*
X73933Y768706D03*
X73960Y766090D03*
X69323Y780257D03*
Y786950D03*
Y803682D03*
Y793643D03*
Y796989D03*
Y817068D03*
Y810375D03*
Y823761D03*
Y830454D03*
Y833800D03*
Y840493D03*
Y847186D03*
Y853879D03*
Y860572D03*
Y877304D03*
Y867265D03*
Y870611D03*
Y883997D03*
Y890690D03*
Y897383D03*
Y904076D03*
Y907423D03*
Y914115D03*
Y920808D03*
Y927501D03*
Y934194D03*
Y940887D03*
Y950926D03*
Y944234D03*
Y964312D03*
Y957619D03*
Y971005D03*
Y977698D03*
Y984391D03*
Y1001123D03*
Y997777D03*
Y991084D03*
Y1031241D03*
Y1037934D03*
Y1044627D03*
Y1058013D03*
Y1051320D03*
Y1074745D03*
Y1068052D03*
Y1064706D03*
Y1081438D03*
Y1088131D03*
Y1098171D03*
Y1104863D03*
Y1091478D03*
Y1111556D03*
Y1118249D03*
Y1134982D03*
Y1124942D03*
Y1128289D03*
Y1148367D03*
Y1141675D03*
Y1155060D03*
Y1161753D03*
Y1165100D03*
Y1171793D03*
Y1178486D03*
Y1185178D03*
Y1191871D03*
Y1208604D03*
Y1198564D03*
Y1201911D03*
Y1215297D03*
Y1221989D03*
Y1228682D03*
Y1235375D03*
Y1238722D03*
Y1245415D03*
Y1252108D03*
X94524Y760178D03*
Y756832D03*
X89965D03*
X90015Y766871D03*
X85465Y776911D03*
X89965Y763525D03*
X94474D03*
X90015Y770218D03*
X85465Y783604D03*
Y790297D03*
Y800336D03*
Y807029D03*
Y793643D03*
Y813722D03*
Y820415D03*
Y837147D03*
Y830454D03*
Y827108D03*
Y843840D03*
Y850533D03*
Y857226D03*
Y863919D03*
Y873958D03*
Y880651D03*
Y867265D03*
Y887344D03*
Y894037D03*
Y910769D03*
Y904076D03*
Y900730D03*
Y924155D03*
Y917462D03*
Y930848D03*
Y940887D03*
Y937541D03*
Y947580D03*
Y954273D03*
Y960966D03*
Y967659D03*
Y974352D03*
Y981045D03*
Y987737D03*
Y994430D03*
Y1001123D03*
Y1027895D03*
Y1034588D03*
Y1041281D03*
Y1047974D03*
Y1054667D03*
Y1061360D03*
Y1071399D03*
Y1064706D03*
Y1078092D03*
Y1088131D03*
Y1084785D03*
Y1094824D03*
Y1101517D03*
Y1108210D03*
Y1114903D03*
Y1131635D03*
Y1124942D03*
Y1121596D03*
Y1138328D03*
Y1145021D03*
Y1151714D03*
Y1161753D03*
Y1158407D03*
Y1168446D03*
Y1175139D03*
Y1181832D03*
Y1188525D03*
Y1205257D03*
Y1198564D03*
Y1195218D03*
Y1211950D03*
Y1218643D03*
Y1225336D03*
Y1235375D03*
Y1232029D03*
Y1242068D03*
Y1248761D03*
X103574Y763766D03*
X99024Y780257D03*
Y786950D03*
Y803682D03*
Y793643D03*
Y796989D03*
Y817068D03*
Y810375D03*
Y823761D03*
Y830454D03*
Y833800D03*
Y840493D03*
Y847186D03*
Y853879D03*
Y860572D03*
Y877304D03*
Y867265D03*
Y870611D03*
Y883997D03*
Y890690D03*
Y897383D03*
Y904076D03*
Y907423D03*
Y914115D03*
Y920808D03*
Y927501D03*
Y934194D03*
Y940887D03*
Y950926D03*
Y944234D03*
Y964312D03*
Y957619D03*
Y971005D03*
Y977698D03*
Y984391D03*
Y1001123D03*
Y997777D03*
Y991084D03*
Y1031241D03*
Y1037934D03*
Y1044627D03*
Y1058013D03*
Y1051320D03*
Y1074745D03*
Y1068052D03*
Y1064706D03*
Y1081438D03*
Y1088131D03*
Y1098171D03*
Y1104863D03*
Y1091478D03*
Y1111556D03*
Y1118249D03*
Y1134982D03*
Y1124942D03*
Y1128289D03*
Y1148367D03*
Y1141675D03*
Y1155060D03*
Y1161753D03*
Y1165100D03*
Y1171793D03*
Y1178486D03*
Y1185178D03*
Y1191871D03*
Y1208604D03*
Y1198564D03*
Y1201911D03*
Y1215297D03*
Y1221989D03*
Y1228682D03*
Y1235375D03*
Y1238722D03*
Y1245415D03*
Y1252108D03*
X124224Y760178D03*
Y756832D03*
X119666D03*
X119616Y767166D03*
X115166Y776911D03*
X119666Y763525D03*
X124174D03*
X119716Y770218D03*
X115166Y783604D03*
Y790297D03*
Y800336D03*
Y807029D03*
Y793643D03*
Y813722D03*
Y820415D03*
Y837147D03*
Y830454D03*
Y827108D03*
Y843840D03*
Y850533D03*
Y857226D03*
Y863919D03*
Y873958D03*
Y880651D03*
Y867265D03*
Y887344D03*
Y894037D03*
Y910769D03*
Y904076D03*
Y900730D03*
Y924155D03*
Y917462D03*
Y930848D03*
Y940887D03*
Y937541D03*
Y947580D03*
Y954273D03*
Y960966D03*
Y967659D03*
Y974352D03*
Y981045D03*
Y987737D03*
Y994430D03*
Y1001123D03*
Y1027895D03*
Y1034588D03*
Y1041281D03*
Y1047974D03*
Y1054667D03*
Y1061360D03*
Y1071399D03*
Y1064706D03*
Y1078092D03*
Y1088131D03*
Y1084785D03*
Y1094824D03*
Y1101517D03*
Y1108210D03*
Y1114903D03*
Y1131635D03*
Y1124942D03*
Y1121596D03*
Y1138328D03*
Y1145021D03*
Y1151714D03*
Y1161753D03*
Y1158407D03*
Y1168446D03*
Y1175139D03*
Y1181832D03*
Y1188525D03*
Y1205257D03*
Y1198564D03*
Y1195218D03*
Y1211950D03*
Y1218643D03*
Y1225336D03*
Y1235375D03*
Y1232029D03*
Y1242068D03*
Y1248761D03*
X133124Y763766D03*
X128724Y780257D03*
Y786950D03*
Y803682D03*
Y793643D03*
Y796989D03*
Y817068D03*
Y810375D03*
Y823761D03*
Y830454D03*
Y833800D03*
Y840493D03*
Y847186D03*
Y853879D03*
Y860572D03*
Y877304D03*
Y867265D03*
Y870611D03*
Y883997D03*
Y890690D03*
Y897383D03*
Y904076D03*
Y907423D03*
Y914115D03*
Y920808D03*
Y927501D03*
Y934194D03*
Y940887D03*
Y950926D03*
Y944234D03*
Y964312D03*
Y957619D03*
Y971005D03*
Y977698D03*
Y984391D03*
Y1001123D03*
Y997777D03*
Y991084D03*
Y1031241D03*
Y1037934D03*
Y1044627D03*
Y1058013D03*
Y1051320D03*
Y1074745D03*
Y1068052D03*
Y1064706D03*
Y1081438D03*
Y1088131D03*
Y1098171D03*
Y1104863D03*
Y1091478D03*
Y1111556D03*
Y1118249D03*
Y1134982D03*
Y1124942D03*
Y1128289D03*
Y1148367D03*
Y1141675D03*
Y1155060D03*
Y1161753D03*
Y1165100D03*
Y1171793D03*
Y1178486D03*
Y1185178D03*
Y1191871D03*
Y1208604D03*
Y1198564D03*
Y1201911D03*
Y1215297D03*
Y1221989D03*
Y1228682D03*
Y1235375D03*
Y1238722D03*
Y1245415D03*
Y1252108D03*
X153925Y760178D03*
Y756832D03*
X149366D03*
X149416Y766871D03*
X144866Y776911D03*
X149366Y763525D03*
X153875D03*
X149416Y770218D03*
X144866Y783604D03*
Y790297D03*
Y800336D03*
Y807029D03*
Y793643D03*
Y813722D03*
Y820415D03*
Y837147D03*
Y830454D03*
Y827108D03*
Y843840D03*
Y850533D03*
Y857226D03*
Y863919D03*
Y873958D03*
Y880651D03*
Y867265D03*
Y887344D03*
Y894037D03*
Y910769D03*
Y904076D03*
Y900730D03*
Y924155D03*
Y917462D03*
Y930848D03*
Y940887D03*
Y937541D03*
Y947580D03*
Y954273D03*
Y960966D03*
Y967659D03*
Y974352D03*
Y981045D03*
Y987737D03*
Y994430D03*
Y1001123D03*
Y1027895D03*
Y1034588D03*
Y1041281D03*
Y1047974D03*
Y1054667D03*
Y1061360D03*
Y1071399D03*
Y1064706D03*
Y1078092D03*
Y1088131D03*
Y1084785D03*
Y1094824D03*
Y1101517D03*
Y1108210D03*
Y1114903D03*
Y1131635D03*
Y1124942D03*
Y1121596D03*
Y1138328D03*
Y1145021D03*
Y1151714D03*
Y1161753D03*
Y1158407D03*
Y1168446D03*
Y1175139D03*
Y1181832D03*
Y1188525D03*
Y1205257D03*
Y1198564D03*
Y1195218D03*
Y1211950D03*
Y1218643D03*
Y1225336D03*
Y1235375D03*
Y1232029D03*
Y1242068D03*
Y1248761D03*
X162975Y763766D03*
X158425Y1068052D03*
Y1064706D03*
X183626Y760178D03*
Y756832D03*
X179067D03*
X179117Y766871D03*
X179067Y763525D03*
X183576D03*
X179117Y770218D03*
X174567Y960966D03*
X180067D03*
X186530Y1523953D03*
X192676Y763766D03*
X188126Y780257D03*
Y786950D03*
Y803682D03*
Y793643D03*
Y796989D03*
Y817068D03*
Y810375D03*
Y823761D03*
Y830454D03*
Y833800D03*
Y840493D03*
Y847186D03*
Y853879D03*
Y860572D03*
Y877304D03*
Y867265D03*
Y870611D03*
Y883997D03*
Y890690D03*
Y897383D03*
Y904076D03*
Y907423D03*
Y914115D03*
Y920808D03*
Y927501D03*
Y934194D03*
Y940887D03*
Y950926D03*
Y944234D03*
Y964312D03*
Y957619D03*
Y971005D03*
Y977698D03*
Y984391D03*
Y1001123D03*
Y997777D03*
Y991084D03*
Y1031241D03*
Y1037934D03*
Y1044627D03*
Y1058013D03*
Y1051320D03*
Y1074745D03*
Y1068052D03*
Y1064706D03*
Y1081438D03*
Y1088131D03*
Y1098171D03*
Y1104863D03*
Y1091478D03*
Y1111556D03*
Y1118249D03*
Y1134982D03*
Y1124942D03*
Y1128289D03*
Y1148367D03*
Y1141675D03*
Y1155060D03*
Y1161753D03*
Y1165100D03*
Y1171793D03*
Y1178486D03*
Y1185178D03*
Y1191871D03*
Y1208604D03*
Y1198564D03*
Y1201911D03*
Y1215297D03*
Y1221989D03*
Y1228682D03*
Y1235375D03*
Y1238722D03*
Y1245415D03*
Y1252108D03*
X195979Y1523953D03*
X196530Y1526353D03*
X191805D03*
X187081D03*
X200703Y1523953D03*
X201254Y1526353D03*
X191254Y1523953D03*
X188254Y1544997D03*
X192978D03*
X197703D03*
X188254Y1548397D03*
X192978D03*
X197703D03*
X188166Y1592380D03*
X200226D03*
X191566D03*
X188166Y1624292D03*
X200226D03*
X191566D03*
X213327Y760178D03*
Y756832D03*
X208768D03*
X204268Y776911D03*
X208768Y763525D03*
X212772Y766871D03*
X213277Y763525D03*
X208818Y770218D03*
X204268Y783604D03*
Y790297D03*
Y800336D03*
Y807029D03*
Y793643D03*
Y813722D03*
Y820415D03*
Y837147D03*
Y830454D03*
Y827108D03*
Y843840D03*
Y850533D03*
Y857226D03*
Y863919D03*
Y873958D03*
Y880651D03*
Y867265D03*
Y887344D03*
Y894037D03*
Y910769D03*
Y904076D03*
Y900730D03*
Y924155D03*
Y917462D03*
Y930848D03*
Y940887D03*
Y937541D03*
Y947580D03*
Y954273D03*
Y960966D03*
Y967659D03*
Y974352D03*
Y981045D03*
Y987737D03*
Y994430D03*
Y1001123D03*
Y1027895D03*
Y1034588D03*
Y1041281D03*
Y1047974D03*
Y1054667D03*
Y1061360D03*
Y1071399D03*
Y1064706D03*
Y1078092D03*
Y1088131D03*
Y1084785D03*
Y1094824D03*
Y1101517D03*
Y1108210D03*
Y1114903D03*
Y1131635D03*
Y1124942D03*
Y1121596D03*
Y1138328D03*
Y1145021D03*
Y1151714D03*
Y1161753D03*
Y1158407D03*
Y1168446D03*
Y1175139D03*
Y1181832D03*
Y1188525D03*
Y1205257D03*
Y1198564D03*
Y1195218D03*
Y1211950D03*
Y1218643D03*
Y1225336D03*
Y1235375D03*
Y1232029D03*
Y1242068D03*
Y1248761D03*
X205427Y1523953D03*
X205978Y1526353D03*
X210703D03*
X210152Y1523953D03*
X214876D03*
X215427Y1526353D03*
X202427Y1544997D03*
X207152D03*
X211876D03*
X216601D03*
X202427Y1548397D03*
X207152D03*
X211876D03*
X216601D03*
X212286Y1592380D03*
X203626D03*
X215686D03*
X212286Y1624292D03*
X203626D03*
X215686D03*
X222377Y763766D03*
X227540Y960966D03*
X220152Y1526353D03*
X224876D03*
X224325Y1523953D03*
X219601D03*
X229049D03*
X229600Y1526353D03*
X221325Y1544997D03*
X226050D03*
X230774D03*
X221325Y1548397D03*
X226050D03*
X230774D03*
X224346Y1592380D03*
X227746D03*
X224346Y1624292D03*
X227746D03*
X238469Y756832D03*
Y763525D03*
X238519Y770218D03*
X233969Y960966D03*
X243223Y1523953D03*
X243774Y1526353D03*
X238498Y1523953D03*
X239049Y1526353D03*
X233774Y1523953D03*
X234325Y1526353D03*
X235499Y1544997D03*
X240223D03*
X244947D03*
X235499Y1548397D03*
X240223D03*
X244947D03*
X236406Y1592380D03*
X239806D03*
X236406Y1624292D03*
X239806D03*
X257396Y1523953D03*
X253223Y1526353D03*
X252672Y1523953D03*
X257947Y1526353D03*
X248498D03*
X247947Y1523953D03*
X249671Y1544997D03*
X254396D03*
X259120D03*
X249671Y1548397D03*
X254396D03*
X259120D03*
X248466Y1592380D03*
X260526D03*
X251866D03*
X248466Y1624292D03*
X260526D03*
X251866D03*
X272525Y108556D03*
X268981D03*
Y111056D03*
X265438Y108556D03*
X261895D03*
Y111056D03*
X265438D03*
X272525D03*
X272586Y1592380D03*
X263926D03*
X275986D03*
X272586Y1624292D03*
X263926D03*
X275986D03*
X284646Y1592380D03*
X288046D03*
X284646Y1624292D03*
X288046D03*
X296706Y1592380D03*
X300106D03*
X296706Y1624292D03*
X300106D03*
X306694Y1507279D03*
X319867Y1526353D03*
X315143D03*
X319316Y1523953D03*
X314592D03*
X316316Y1544997D03*
X321040D03*
X316316Y1548397D03*
X321040D03*
X308766Y1592380D03*
X320826D03*
X312166D03*
X308766Y1624292D03*
X320826D03*
X312166D03*
X324041Y1523953D03*
X324592Y1526353D03*
X328765Y1523953D03*
X329316Y1526353D03*
X334040D03*
X333489Y1523953D03*
X325765Y1544997D03*
X330489D03*
X335214D03*
X325765Y1548397D03*
X330489D03*
X335214D03*
X332886Y1592380D03*
X324226D03*
X332886Y1624292D03*
X324226D03*
X338765Y1526353D03*
X338214Y1523953D03*
X347663D03*
X348214Y1526353D03*
X343489D03*
X342938Y1523953D03*
X339938Y1544997D03*
X344663D03*
X349387D03*
X339938Y1548397D03*
X344663D03*
X349387D03*
X344946Y1592380D03*
X336286D03*
X348346D03*
X344946Y1624292D03*
X336286D03*
X348346D03*
X362387Y1526353D03*
X361836Y1523953D03*
X352387D03*
X352938Y1526353D03*
X357662D03*
X357111Y1523953D03*
X363561Y1544997D03*
X354112D03*
X358836D03*
X363561Y1548397D03*
X354112D03*
X358836D03*
X357006Y1592380D03*
X360406D03*
X357006Y1624292D03*
X360406D03*
X380734Y1523953D03*
X376560Y1526353D03*
X376009Y1523953D03*
X371285D03*
X371836Y1526353D03*
X367111D03*
X366560Y1523953D03*
X368285Y1544997D03*
X373009D03*
X377733D03*
X368285Y1548397D03*
X373009D03*
X377733D03*
X369066Y1592380D03*
X372466D03*
X369066Y1624292D03*
X372466D03*
X385458Y1523953D03*
X381285Y1526353D03*
X386009D03*
X382458Y1544997D03*
X387182D03*
X382458Y1548397D03*
X387182D03*
X450703Y1523953D03*
X451254Y1526353D03*
X452427Y1544997D03*
Y1548397D03*
X452339Y1592380D03*
Y1624292D03*
X464876Y1523953D03*
X460703Y1526353D03*
X455978D03*
X465427D03*
X455427Y1523953D03*
X460152D03*
X469600D03*
X470151Y1526353D03*
X457151Y1544997D03*
X461876D03*
X466600D03*
X457151Y1548397D03*
X461876D03*
X466600D03*
X464399Y1592380D03*
X455739D03*
X467799D03*
X464399Y1624292D03*
X455739D03*
X467799D03*
X474325Y1523953D03*
X474876Y1526353D03*
X483774Y1523953D03*
X484325Y1526353D03*
X479049Y1523953D03*
X479600Y1526353D03*
X471325Y1544997D03*
X476049D03*
X480774D03*
X471325Y1548397D03*
X476049D03*
X480774D03*
X476459Y1592380D03*
X479859D03*
X476459Y1624292D03*
X479859D03*
X497947Y1523953D03*
X498498Y1526353D03*
X488498Y1523953D03*
X489049Y1526353D03*
X493222Y1523953D03*
X493773Y1526353D03*
X499672Y1544997D03*
X485498D03*
X490223D03*
X494947D03*
X499672Y1548397D03*
X485498D03*
X490223D03*
X494947D03*
X488519Y1592380D03*
X491919D03*
X488519Y1624292D03*
X491919D03*
X507947Y1526353D03*
X507396Y1523953D03*
X512120D03*
X512671Y1526353D03*
X503222D03*
X502671Y1523953D03*
X504396Y1544997D03*
X509120D03*
X513844D03*
X504396Y1548397D03*
X509120D03*
X513844D03*
X500579Y1592380D03*
X512639D03*
X503979D03*
X500579Y1624292D03*
X512639D03*
X503979D03*
X521569Y1523953D03*
X522120Y1526353D03*
X517396D03*
X516845Y1523953D03*
X518569Y1544997D03*
X523293D03*
X518569Y1548397D03*
X523293D03*
X524699Y1592380D03*
X516039D03*
X528099D03*
X524699Y1624292D03*
X516039D03*
X528099D03*
X536759Y1592380D03*
X540159D03*
X536759Y1624292D03*
X540159D03*
X548819Y1592380D03*
X552219D03*
X548819Y1624292D03*
X552219D03*
X572939Y1592380D03*
X560879D03*
X564279D03*
X572939Y1624292D03*
X560879D03*
X564279D03*
X588765Y1526353D03*
X588214Y1523953D03*
X578765D03*
X583489D03*
X579316Y1526353D03*
X584040D03*
X580489Y1544997D03*
X585213D03*
X580489Y1548397D03*
X585213D03*
X584999Y1592380D03*
X576339D03*
X588399D03*
X584999Y1624292D03*
X576339D03*
X588399D03*
X602387Y1523953D03*
X602938Y1526353D03*
X592938Y1523953D03*
X593489Y1526353D03*
X598213D03*
X597662Y1523953D03*
X589938Y1544997D03*
X594662D03*
X599387D03*
X604111D03*
X589938Y1548397D03*
X594662D03*
X599387D03*
X604111D03*
X597059Y1592380D03*
X600459D03*
X597059Y1624292D03*
X600459D03*
X616560Y1523953D03*
X617111Y1526353D03*
X607111Y1523953D03*
X607662Y1526353D03*
X612387D03*
X611836Y1523953D03*
X608836Y1544997D03*
X613560D03*
X618285D03*
X608836Y1548397D03*
X613560D03*
X618285D03*
X609119Y1592380D03*
X612519D03*
X609119Y1624292D03*
X612519D03*
X626009Y1523953D03*
X626560Y1526353D03*
X631284D03*
X630733Y1523953D03*
X621835Y1526353D03*
X621284Y1523953D03*
X627734Y1544997D03*
X632458D03*
X623009D03*
X627734Y1548397D03*
X632458D03*
X623009D03*
X621179Y1592380D03*
X633239D03*
X624579D03*
X621179Y1624292D03*
X633239D03*
X624579D03*
X642854Y760178D03*
Y756832D03*
X642804Y763525D03*
X644907Y1523953D03*
X640733Y1526353D03*
X640182Y1523953D03*
X635458D03*
X636009Y1526353D03*
X645458D03*
X637182Y1544997D03*
X641906D03*
X646631D03*
X637182Y1548397D03*
X641906D03*
X646631D03*
X636639Y1592380D03*
Y1624292D03*
X651905Y763766D03*
X663496Y960966D03*
X657996D03*
X650182Y1526353D03*
X649631Y1523953D03*
X651355Y1544997D03*
Y1548397D03*
X664634Y449952D03*
X667996Y756832D03*
X672555D03*
Y760178D03*
X668046Y766871D03*
X667996Y763525D03*
X672505D03*
X668046Y770218D03*
X677055Y780257D03*
Y786950D03*
Y803682D03*
Y793643D03*
Y796989D03*
Y817068D03*
Y810375D03*
Y823761D03*
Y830454D03*
Y833800D03*
Y840493D03*
Y847186D03*
Y853879D03*
Y860572D03*
Y877304D03*
Y867265D03*
Y870611D03*
Y883997D03*
Y890690D03*
Y897383D03*
Y904076D03*
Y907423D03*
Y914115D03*
Y920808D03*
Y927501D03*
Y934194D03*
Y940887D03*
Y950926D03*
Y944234D03*
Y964312D03*
Y957619D03*
Y971005D03*
Y977698D03*
Y984391D03*
Y1001123D03*
Y997777D03*
Y991084D03*
Y1031241D03*
Y1037934D03*
Y1044627D03*
Y1058013D03*
Y1051320D03*
Y1074745D03*
Y1068052D03*
Y1064706D03*
Y1081438D03*
Y1088131D03*
Y1098171D03*
Y1104863D03*
Y1091478D03*
Y1111556D03*
Y1118249D03*
Y1134982D03*
Y1124942D03*
Y1128289D03*
Y1148367D03*
Y1141675D03*
Y1155060D03*
Y1161753D03*
Y1165100D03*
Y1171793D03*
Y1178486D03*
Y1185178D03*
Y1191871D03*
Y1208604D03*
Y1198564D03*
Y1201911D03*
Y1215297D03*
Y1221989D03*
Y1228682D03*
Y1235375D03*
Y1238722D03*
Y1245415D03*
Y1252108D03*
X695796Y430957D03*
Y437256D03*
Y468672D03*
X693197Y776911D03*
X681606Y763766D03*
X693197Y783604D03*
Y790297D03*
Y800336D03*
Y807029D03*
Y793643D03*
Y813722D03*
Y820415D03*
Y837147D03*
Y830454D03*
Y827108D03*
Y843840D03*
Y850533D03*
Y857226D03*
Y863919D03*
Y873958D03*
Y880651D03*
Y867265D03*
Y887344D03*
Y894037D03*
Y910769D03*
Y904076D03*
Y900730D03*
Y924155D03*
Y917462D03*
Y930848D03*
Y940887D03*
Y937541D03*
Y947580D03*
Y954273D03*
Y960966D03*
Y967659D03*
Y974352D03*
Y981045D03*
Y987737D03*
Y994430D03*
Y1001123D03*
Y1027895D03*
Y1034588D03*
Y1041281D03*
Y1047974D03*
Y1054667D03*
Y1061360D03*
Y1071399D03*
Y1064706D03*
Y1078092D03*
Y1088131D03*
Y1084785D03*
Y1094824D03*
Y1101517D03*
Y1108210D03*
Y1114903D03*
Y1131635D03*
Y1124942D03*
Y1121596D03*
Y1138328D03*
Y1145021D03*
Y1151714D03*
Y1161753D03*
Y1158407D03*
Y1168446D03*
Y1175139D03*
Y1181832D03*
Y1188525D03*
Y1205257D03*
Y1198564D03*
Y1195218D03*
Y1211950D03*
Y1218643D03*
Y1225336D03*
Y1235375D03*
Y1232029D03*
Y1242068D03*
Y1248761D03*
X698599Y115178D03*
X705686D03*
X702142D03*
X698599Y112678D03*
X705686D03*
X702142D03*
X695056D03*
Y115178D03*
X708395Y427807D03*
Y424657D03*
X705245D03*
Y427807D03*
X702095D03*
X708395Y434106D03*
X705245Y430957D03*
X702095Y434106D03*
X698946Y427807D03*
X705245Y437256D03*
X698946Y430957D03*
X705245Y434106D03*
X702095Y430957D03*
X705245Y446705D03*
X708395Y440405D03*
Y443555D03*
X702095Y446705D03*
X705245Y443555D03*
X702095Y437256D03*
Y440405D03*
Y443555D03*
X705245Y440405D03*
X708395Y437256D03*
X698946Y446705D03*
X708395D03*
X698946Y449854D03*
X708395Y462373D03*
Y449854D03*
X705245Y459223D03*
X702095Y456074D03*
Y459223D03*
X708395Y456074D03*
X705245Y462373D03*
X702095D03*
X705245Y456074D03*
X695796Y449854D03*
X708395Y459223D03*
Y465523D03*
X705245Y468672D03*
X702095D03*
X698946Y471822D03*
X702095Y465523D03*
X695796Y471822D03*
X708395Y478121D03*
X705245Y471822D03*
X695796Y465523D03*
X702095Y478121D03*
X705245Y474971D03*
X708395Y471822D03*
Y468672D03*
X705245Y465523D03*
X702095Y471822D03*
X698946Y465523D03*
X705245Y478121D03*
X702095Y474971D03*
X698946Y487570D03*
Y481271D03*
Y484420D03*
X705245Y481271D03*
X702095D03*
X695796Y484420D03*
X708395D03*
Y481271D03*
X697697Y756832D03*
X702256D03*
Y760178D03*
X697747Y766871D03*
X697697Y763525D03*
X702206D03*
X697747Y770218D03*
X706756Y1068052D03*
Y1064706D03*
X720993Y418358D03*
X717843D03*
Y421508D03*
X720993Y430957D03*
X711544D03*
X714694D03*
X717843Y434106D03*
X720993D03*
X717843Y430957D03*
X720993Y421508D03*
X711544Y434106D03*
X714694D03*
X720993Y424657D03*
X717843D03*
Y427807D03*
X714694Y424657D03*
Y427807D03*
X711544Y424657D03*
Y427807D03*
X720993D03*
X717843Y437256D03*
X720993D03*
X714694D03*
X711544D03*
Y443555D03*
X717843D03*
X714694Y446705D03*
Y440405D03*
X720993D03*
X711544D03*
X714694Y443555D03*
X711544Y446705D03*
Y459223D03*
X714694D03*
X717843Y462373D03*
Y456074D03*
Y449854D03*
X714694Y462373D03*
X711544D03*
X714694Y449854D03*
X711544D03*
X714694Y456074D03*
X711544D03*
X720993Y471822D03*
Y468672D03*
X711544Y478121D03*
X717843Y474971D03*
X724143Y471822D03*
X720993Y478121D03*
X717843D03*
X720993Y474971D03*
X714694Y465523D03*
X717843Y471822D03*
Y468672D03*
X714694Y471822D03*
X711544D03*
X714694Y468672D03*
X711544D03*
X720993Y465523D03*
X711544Y474971D03*
X714694Y478121D03*
Y474971D03*
X724143Y481271D03*
X711544Y465523D03*
X717843Y481271D03*
X714694D03*
X720993D03*
X711544D03*
X720993Y484420D03*
X711307Y763766D03*
X722898Y960966D03*
X717398D03*
X731208Y398737D03*
X733512Y418358D03*
X727292D03*
X724143D03*
X736661Y424657D03*
Y430957D03*
Y434106D03*
X733512D03*
Y421508D03*
Y424657D03*
Y430957D03*
X727292D03*
Y434106D03*
X724143Y430957D03*
X727292Y427807D03*
X736661D03*
X727292Y424657D03*
X724143Y434106D03*
Y421508D03*
X739811Y430957D03*
X724143Y427807D03*
Y424657D03*
X733512Y437256D03*
X727292Y440405D03*
X724143Y446705D03*
X736661D03*
X733512Y440405D03*
X736661D03*
X727292Y437256D03*
X724143Y440405D03*
Y437256D03*
X736661D03*
Y459223D03*
Y456074D03*
X733512D03*
Y449854D03*
X736661D03*
X727292Y456074D03*
X724143Y459223D03*
Y456074D03*
X727292Y449854D03*
X724143D03*
X727292Y471822D03*
X724143Y468672D03*
X727292D03*
X736661D03*
X724143Y474971D03*
X733512Y478121D03*
X724143Y465523D03*
X727292D03*
X733512D03*
X736661D03*
X733512Y474971D03*
Y468672D03*
X736661Y478121D03*
Y471822D03*
X724143Y478121D03*
X727292D03*
X733512Y471822D03*
X736661Y474971D03*
Y487570D03*
Y481271D03*
X733512D03*
X727292D03*
X724143Y487570D03*
X727292Y484420D03*
Y487570D03*
X727398Y756832D03*
X731957D03*
Y760178D03*
X727398Y763525D03*
X731462Y766871D03*
X731907Y763525D03*
X727448Y770218D03*
X736457Y780257D03*
Y786950D03*
Y803682D03*
Y793643D03*
Y796989D03*
Y817068D03*
Y810375D03*
Y823761D03*
Y830454D03*
Y833800D03*
Y840493D03*
Y847186D03*
Y853879D03*
Y860572D03*
Y877304D03*
Y867265D03*
Y870611D03*
Y883997D03*
Y890690D03*
Y897383D03*
Y904076D03*
Y907423D03*
Y914115D03*
Y920808D03*
Y927501D03*
Y934194D03*
Y940887D03*
Y950926D03*
Y944234D03*
Y964312D03*
Y957619D03*
Y971005D03*
Y977698D03*
Y984391D03*
Y1001123D03*
Y997777D03*
Y991084D03*
Y1031241D03*
Y1037934D03*
Y1044627D03*
Y1058013D03*
Y1051320D03*
Y1074745D03*
Y1068052D03*
Y1064706D03*
Y1081438D03*
Y1088131D03*
Y1098171D03*
Y1104863D03*
Y1091478D03*
Y1111556D03*
Y1118249D03*
Y1134982D03*
Y1124942D03*
Y1128289D03*
Y1148367D03*
Y1141675D03*
Y1155060D03*
Y1161753D03*
Y1165100D03*
Y1171793D03*
Y1178486D03*
Y1185178D03*
Y1191871D03*
Y1208604D03*
Y1198564D03*
Y1201911D03*
Y1215297D03*
Y1221989D03*
Y1228682D03*
Y1235375D03*
Y1238722D03*
Y1245415D03*
Y1252108D03*
X755559Y421508D03*
X739811Y424657D03*
Y427807D03*
X742961Y424657D03*
Y427807D03*
X746110Y424657D03*
Y427807D03*
X752409Y430957D03*
Y434106D03*
X749260D03*
X752409Y424657D03*
X749260D03*
X746110Y430957D03*
X749260D03*
X742961D03*
X752409Y427807D03*
X749260D03*
X739811Y434106D03*
X742961D03*
X746110D03*
X752409Y443555D03*
X739811Y437256D03*
X746110D03*
X742961D03*
X746110Y440405D03*
X749260Y437256D03*
X739811Y440405D03*
X742961Y443555D03*
Y446705D03*
X752409Y440405D03*
X749260D03*
Y446705D03*
X752409Y437256D03*
Y446705D03*
X746110D03*
Y443555D03*
X749260D03*
X742961Y459223D03*
Y462373D03*
Y456074D03*
Y449854D03*
X752409Y456074D03*
X749260Y449854D03*
X746110Y459223D03*
X752409Y462373D03*
Y459223D03*
X749260D03*
X746110Y456074D03*
Y449854D03*
Y462373D03*
X749260D03*
X752409Y449854D03*
X749260Y456074D03*
X742961Y474971D03*
Y468672D03*
X739811Y478121D03*
Y474971D03*
Y471822D03*
X749260D03*
X739811Y468672D03*
X749260D03*
Y474971D03*
X742961Y471822D03*
X749260Y478121D03*
X746110Y474971D03*
X752409Y468672D03*
X742961Y478121D03*
X746110Y468672D03*
X739811Y465523D03*
X752409Y478121D03*
Y471822D03*
Y465523D03*
X746110D03*
X749260D03*
X752409Y474971D03*
X746110Y478121D03*
Y471822D03*
X749260Y481271D03*
X742961Y484420D03*
X739811Y481271D03*
X746110Y484420D03*
X749260D03*
X752409Y487570D03*
X742961D03*
Y490070D03*
X746110Y481271D03*
X752409D03*
X742961D03*
X752599Y776911D03*
X741007Y763766D03*
X752599Y783604D03*
Y790297D03*
Y800336D03*
Y807029D03*
Y793643D03*
Y813722D03*
Y820415D03*
Y837147D03*
Y830454D03*
Y827108D03*
Y843840D03*
Y850533D03*
Y857226D03*
Y863919D03*
Y873958D03*
Y880651D03*
Y867265D03*
Y887344D03*
Y894037D03*
Y910769D03*
Y904076D03*
Y900730D03*
Y924155D03*
Y917462D03*
Y930848D03*
Y940887D03*
Y937541D03*
Y947580D03*
Y954273D03*
Y960966D03*
Y967659D03*
Y974352D03*
Y981045D03*
Y987737D03*
Y994430D03*
Y1001123D03*
Y1027895D03*
Y1034588D03*
Y1041281D03*
Y1047974D03*
Y1054667D03*
Y1061360D03*
Y1071399D03*
Y1064706D03*
Y1078092D03*
Y1088131D03*
Y1084785D03*
Y1094824D03*
Y1101517D03*
Y1108210D03*
Y1114903D03*
Y1131635D03*
Y1124942D03*
Y1121596D03*
Y1138328D03*
Y1145021D03*
Y1151714D03*
Y1161753D03*
Y1158407D03*
Y1168446D03*
Y1175139D03*
Y1181832D03*
Y1188525D03*
Y1205257D03*
Y1198564D03*
Y1195218D03*
Y1211950D03*
Y1218643D03*
Y1225336D03*
Y1235375D03*
Y1232029D03*
Y1242068D03*
Y1248761D03*
X755559Y418358D03*
X758709D03*
X761858D03*
X755559Y427807D03*
Y430957D03*
X758709Y427807D03*
Y430957D03*
X765008Y424657D03*
X755559D03*
X758709D03*
Y421508D03*
X761858Y424657D03*
X765008Y430957D03*
X755559Y434106D03*
X761858Y430957D03*
Y427807D03*
X758709Y434106D03*
X765008Y427807D03*
Y446705D03*
X758709D03*
X755559Y443555D03*
Y446705D03*
Y437256D03*
X758709Y440405D03*
X755559D03*
X758709Y443555D03*
X761858Y446705D03*
X755559Y449854D03*
Y459223D03*
X765008Y456074D03*
X758709Y465523D03*
X755559Y462373D03*
X758709Y459223D03*
Y462373D03*
Y456074D03*
Y449854D03*
X755559Y478121D03*
Y468672D03*
Y471822D03*
X758709D03*
X761858Y478121D03*
Y474971D03*
Y471822D03*
X758709Y474971D03*
X765008Y471822D03*
Y474971D03*
Y465523D03*
X758709Y478121D03*
X761858Y468672D03*
Y465523D03*
X765008Y468672D03*
X755559Y465523D03*
Y474971D03*
Y481271D03*
Y484420D03*
X765008Y481271D03*
X761858D03*
X758709D03*
X757099Y756832D03*
X761658D03*
Y760178D03*
X757149Y766871D03*
X757099Y763525D03*
X761608D03*
X757149Y770218D03*
X766158Y780257D03*
Y786950D03*
Y803682D03*
Y793643D03*
Y796989D03*
Y817068D03*
Y810375D03*
Y823761D03*
Y830454D03*
Y833800D03*
Y840493D03*
Y847186D03*
Y853879D03*
Y860572D03*
Y877304D03*
Y867265D03*
Y870611D03*
Y883997D03*
Y890690D03*
Y897383D03*
Y904076D03*
Y907423D03*
Y914115D03*
Y920808D03*
Y927501D03*
Y934194D03*
Y940887D03*
Y950926D03*
Y944234D03*
Y964312D03*
Y957619D03*
Y971005D03*
Y977698D03*
Y984391D03*
Y1001123D03*
Y997777D03*
Y991084D03*
Y1031241D03*
Y1037934D03*
Y1044627D03*
Y1058013D03*
Y1051320D03*
Y1074745D03*
Y1068052D03*
Y1064706D03*
Y1081438D03*
Y1088131D03*
Y1098171D03*
Y1104863D03*
Y1091478D03*
Y1111556D03*
Y1118249D03*
Y1134982D03*
Y1124942D03*
Y1128289D03*
Y1148367D03*
Y1141675D03*
Y1155060D03*
Y1161753D03*
Y1165100D03*
Y1171793D03*
Y1178486D03*
Y1185178D03*
Y1191871D03*
Y1208604D03*
Y1198564D03*
Y1201911D03*
Y1215297D03*
Y1221989D03*
Y1228682D03*
Y1235375D03*
Y1238722D03*
Y1245415D03*
Y1252108D03*
X782300Y776911D03*
X770708Y763766D03*
X782300Y783604D03*
Y790297D03*
Y800336D03*
Y807029D03*
Y793643D03*
Y813722D03*
Y820415D03*
Y837147D03*
Y830454D03*
Y827108D03*
Y843840D03*
Y850533D03*
Y857226D03*
Y863919D03*
Y873958D03*
Y880651D03*
Y867265D03*
Y887344D03*
Y894037D03*
Y910769D03*
Y904076D03*
Y900730D03*
Y924155D03*
Y917462D03*
Y930848D03*
Y940887D03*
Y937541D03*
Y947580D03*
Y954273D03*
Y960966D03*
Y967659D03*
Y974352D03*
Y981045D03*
Y987737D03*
Y994430D03*
Y1001123D03*
Y1027895D03*
Y1034588D03*
Y1041281D03*
Y1047974D03*
Y1054667D03*
Y1061360D03*
Y1071399D03*
Y1064706D03*
Y1078092D03*
Y1088131D03*
Y1084785D03*
Y1094824D03*
Y1101517D03*
Y1108210D03*
Y1114903D03*
Y1131635D03*
Y1124942D03*
Y1121596D03*
Y1138328D03*
Y1145021D03*
Y1151714D03*
Y1161753D03*
Y1158407D03*
Y1168446D03*
Y1175139D03*
Y1181832D03*
Y1188525D03*
Y1205257D03*
Y1198564D03*
Y1195218D03*
Y1211950D03*
Y1218643D03*
Y1225336D03*
Y1235375D03*
Y1232029D03*
Y1242068D03*
Y1248761D03*
X786800Y756832D03*
X791358Y760178D03*
Y756832D03*
X786850Y766871D03*
X786800Y763525D03*
X791308D03*
X786850Y770218D03*
X795858Y780257D03*
Y786950D03*
Y803682D03*
Y793643D03*
Y796989D03*
Y817068D03*
Y810375D03*
Y823761D03*
Y830454D03*
Y833800D03*
Y840493D03*
Y847186D03*
Y853879D03*
Y860572D03*
Y877304D03*
Y867265D03*
Y870611D03*
Y883997D03*
Y890690D03*
Y897383D03*
Y904076D03*
Y907423D03*
Y914115D03*
Y920808D03*
Y927501D03*
Y934194D03*
Y940887D03*
Y950926D03*
Y944234D03*
Y964312D03*
Y957619D03*
Y971005D03*
Y977698D03*
Y984391D03*
Y1001123D03*
Y997777D03*
Y991084D03*
Y1031241D03*
Y1037934D03*
Y1044627D03*
Y1058013D03*
Y1051320D03*
Y1074745D03*
Y1068052D03*
Y1064706D03*
Y1081438D03*
Y1088131D03*
Y1098171D03*
Y1104863D03*
Y1091478D03*
Y1111556D03*
Y1118249D03*
Y1134982D03*
Y1124942D03*
Y1128289D03*
Y1148367D03*
Y1141675D03*
Y1155060D03*
Y1161753D03*
Y1165100D03*
Y1171793D03*
Y1178486D03*
Y1185178D03*
Y1191871D03*
Y1208604D03*
Y1198564D03*
Y1201911D03*
Y1215297D03*
Y1221989D03*
Y1228682D03*
Y1235375D03*
Y1238722D03*
Y1245415D03*
Y1252108D03*
X812000Y776911D03*
X800409Y763765D03*
X812000Y783604D03*
Y790297D03*
Y800336D03*
Y807029D03*
Y793643D03*
Y813722D03*
Y820415D03*
Y837147D03*
Y830454D03*
Y827108D03*
Y843840D03*
Y850533D03*
Y857226D03*
Y863919D03*
Y873958D03*
Y880651D03*
Y867265D03*
Y887344D03*
Y894037D03*
Y910769D03*
Y904076D03*
Y900730D03*
Y924155D03*
Y917462D03*
Y930848D03*
Y940887D03*
Y937541D03*
Y947580D03*
Y954273D03*
Y960966D03*
Y967659D03*
Y974352D03*
Y981045D03*
Y987737D03*
Y994430D03*
Y1001123D03*
Y1027895D03*
Y1034588D03*
Y1041281D03*
Y1047974D03*
Y1054667D03*
Y1061360D03*
Y1071399D03*
Y1064706D03*
Y1078092D03*
Y1088131D03*
Y1084785D03*
Y1094824D03*
Y1101517D03*
Y1108210D03*
Y1114903D03*
Y1131635D03*
Y1124942D03*
Y1121596D03*
Y1138328D03*
Y1145021D03*
Y1151714D03*
Y1161753D03*
Y1158407D03*
Y1168446D03*
Y1175139D03*
Y1181832D03*
Y1188525D03*
Y1205257D03*
Y1198564D03*
Y1195218D03*
Y1211950D03*
Y1218643D03*
Y1225336D03*
Y1235375D03*
Y1232029D03*
Y1242068D03*
Y1248761D03*
X816500Y756832D03*
X816550Y770218D03*
X816500Y763525D03*
X998206Y196191D03*
X1000706D03*
X998206Y199735D03*
X1000706D03*
X998206Y206821D03*
X1000706D03*
X998206Y203278D03*
X1000706D03*
X1040965Y756831D03*
Y760177D03*
X1050015Y763765D03*
X1040915Y763524D03*
X1045465Y780256D03*
Y786949D03*
Y803681D03*
Y793642D03*
Y796988D03*
Y817067D03*
Y810374D03*
Y823760D03*
Y830453D03*
Y833799D03*
Y840492D03*
Y847185D03*
Y853878D03*
Y860571D03*
Y877303D03*
Y867264D03*
Y870610D03*
Y883996D03*
Y890689D03*
Y897382D03*
Y904075D03*
Y907422D03*
Y914114D03*
Y920807D03*
Y927500D03*
Y934193D03*
Y940886D03*
Y950925D03*
Y944233D03*
Y964311D03*
Y957618D03*
Y971004D03*
Y977697D03*
Y984390D03*
Y1001122D03*
Y997776D03*
Y991083D03*
Y1031240D03*
Y1037933D03*
Y1044626D03*
Y1058012D03*
Y1051319D03*
Y1074744D03*
Y1068051D03*
Y1064705D03*
Y1081437D03*
Y1088130D03*
Y1098170D03*
Y1104862D03*
Y1091477D03*
Y1111555D03*
Y1118248D03*
Y1134981D03*
Y1124941D03*
Y1128288D03*
Y1148366D03*
Y1141674D03*
Y1155059D03*
Y1161752D03*
Y1165099D03*
Y1171792D03*
Y1178485D03*
Y1185177D03*
Y1191870D03*
Y1208603D03*
Y1198563D03*
Y1201910D03*
Y1215296D03*
Y1221988D03*
Y1228681D03*
Y1235374D03*
Y1238721D03*
Y1245414D03*
Y1252107D03*
X1066107Y756831D03*
X1066157Y766870D03*
X1061607Y776910D03*
X1066107Y763524D03*
X1066157Y770217D03*
X1061607Y783603D03*
Y790296D03*
Y800335D03*
Y807028D03*
Y793642D03*
Y813721D03*
Y820414D03*
Y837146D03*
Y830453D03*
Y827107D03*
Y843839D03*
Y850532D03*
Y857225D03*
Y863918D03*
Y873957D03*
Y880650D03*
Y867264D03*
Y887343D03*
Y894036D03*
Y910768D03*
Y904075D03*
Y900729D03*
Y924154D03*
Y917461D03*
Y930847D03*
Y940886D03*
Y937540D03*
Y947579D03*
Y954272D03*
Y960965D03*
Y967658D03*
Y974351D03*
Y981044D03*
Y987736D03*
Y994429D03*
Y1001122D03*
Y1027894D03*
Y1034587D03*
Y1041280D03*
Y1047973D03*
Y1054666D03*
Y1061359D03*
Y1071398D03*
Y1064705D03*
Y1078091D03*
Y1088130D03*
Y1084784D03*
Y1094823D03*
Y1101516D03*
Y1108209D03*
Y1114902D03*
Y1131634D03*
Y1124941D03*
Y1121595D03*
Y1138327D03*
Y1145020D03*
Y1151713D03*
Y1161752D03*
Y1158406D03*
Y1168445D03*
Y1175138D03*
Y1181831D03*
Y1188524D03*
Y1205256D03*
Y1198563D03*
Y1195217D03*
Y1211949D03*
Y1218642D03*
Y1225335D03*
Y1235374D03*
Y1232028D03*
Y1242067D03*
Y1248760D03*
X1070666Y756831D03*
Y760177D03*
X1079716Y763765D03*
X1070616Y763524D03*
X1075166Y780256D03*
Y786949D03*
Y803681D03*
Y793642D03*
Y796988D03*
Y817067D03*
Y810374D03*
Y823760D03*
Y830453D03*
Y833799D03*
Y840492D03*
Y847185D03*
Y853878D03*
Y860571D03*
Y877303D03*
Y867264D03*
Y870610D03*
Y883996D03*
Y890689D03*
Y897382D03*
Y904075D03*
Y907422D03*
Y914114D03*
Y920807D03*
Y927500D03*
Y934193D03*
Y940886D03*
Y950925D03*
Y944233D03*
Y964311D03*
Y957618D03*
Y971004D03*
Y977697D03*
Y984390D03*
Y1001122D03*
Y997776D03*
Y991083D03*
Y1031240D03*
Y1037933D03*
Y1044626D03*
Y1058012D03*
Y1051319D03*
Y1074744D03*
Y1068051D03*
Y1064705D03*
Y1081437D03*
Y1088130D03*
Y1098170D03*
Y1104862D03*
Y1091477D03*
Y1111555D03*
Y1118248D03*
Y1134981D03*
Y1124941D03*
Y1128288D03*
Y1148366D03*
Y1141674D03*
Y1155059D03*
Y1161752D03*
Y1165099D03*
Y1171792D03*
Y1178485D03*
Y1185177D03*
Y1191870D03*
Y1208603D03*
Y1198563D03*
Y1201910D03*
Y1215296D03*
Y1221988D03*
Y1228681D03*
Y1235374D03*
Y1238721D03*
Y1245414D03*
Y1252107D03*
X1095808Y756831D03*
X1095858Y766870D03*
X1091308Y776910D03*
X1095808Y763524D03*
X1095858Y770217D03*
X1091308Y783603D03*
Y790296D03*
Y800335D03*
Y807028D03*
Y793642D03*
Y813721D03*
Y820414D03*
Y837146D03*
Y830453D03*
Y827107D03*
Y843839D03*
Y850532D03*
Y857225D03*
Y863918D03*
Y873957D03*
Y880650D03*
Y867264D03*
Y887343D03*
Y894036D03*
Y910768D03*
Y904075D03*
Y900729D03*
Y924154D03*
Y917461D03*
Y930847D03*
Y940886D03*
Y937540D03*
Y947579D03*
Y954272D03*
Y960965D03*
Y967658D03*
Y974351D03*
Y981044D03*
Y987736D03*
Y994429D03*
Y1001122D03*
Y1027894D03*
Y1034587D03*
Y1041280D03*
Y1047973D03*
Y1054666D03*
Y1061359D03*
Y1071398D03*
Y1064705D03*
Y1078091D03*
Y1088130D03*
Y1084784D03*
Y1094823D03*
Y1101516D03*
Y1108209D03*
Y1114902D03*
Y1131634D03*
Y1124941D03*
Y1121595D03*
Y1138327D03*
Y1145020D03*
Y1151713D03*
Y1161752D03*
Y1158406D03*
Y1168445D03*
Y1175138D03*
Y1181831D03*
Y1188524D03*
Y1205256D03*
Y1198563D03*
Y1195217D03*
Y1211949D03*
Y1218642D03*
Y1225335D03*
Y1235374D03*
Y1232028D03*
Y1242067D03*
Y1248760D03*
X1100366Y756831D03*
Y760177D03*
X1109416Y763765D03*
X1100316Y763524D03*
X1104866Y780256D03*
Y786949D03*
Y803681D03*
Y793642D03*
Y796988D03*
Y817067D03*
Y810374D03*
Y823760D03*
Y830453D03*
Y833799D03*
Y840492D03*
Y847185D03*
Y853878D03*
Y860571D03*
Y877303D03*
Y867264D03*
Y870610D03*
Y883996D03*
Y890689D03*
Y897382D03*
Y904075D03*
Y907422D03*
Y914114D03*
Y920807D03*
Y927500D03*
Y934193D03*
Y940886D03*
Y950925D03*
Y944233D03*
Y964311D03*
Y957618D03*
Y971004D03*
Y977697D03*
Y984390D03*
Y1001122D03*
Y997776D03*
Y991083D03*
Y1031240D03*
Y1037933D03*
Y1044626D03*
Y1058012D03*
Y1051319D03*
Y1074744D03*
Y1068051D03*
Y1064705D03*
Y1081437D03*
Y1088130D03*
Y1098170D03*
Y1104862D03*
Y1091477D03*
Y1111555D03*
Y1118248D03*
Y1134981D03*
Y1124941D03*
Y1128288D03*
Y1148366D03*
Y1141674D03*
Y1155059D03*
Y1161752D03*
Y1165099D03*
Y1171792D03*
Y1178485D03*
Y1185177D03*
Y1191870D03*
Y1208603D03*
Y1198563D03*
Y1201910D03*
Y1215296D03*
Y1221988D03*
Y1228681D03*
Y1235374D03*
Y1238721D03*
Y1245414D03*
Y1252107D03*
X1125508Y756831D03*
X1125558Y766870D03*
X1121008Y776910D03*
X1125508Y763524D03*
X1125558Y770217D03*
X1121008Y783603D03*
Y790296D03*
Y800335D03*
Y807028D03*
Y793642D03*
Y813721D03*
Y820414D03*
Y837146D03*
Y830453D03*
Y827107D03*
Y843839D03*
Y850532D03*
Y857225D03*
Y863918D03*
Y873957D03*
Y880650D03*
Y867264D03*
Y887343D03*
Y894036D03*
Y910768D03*
Y904075D03*
Y900729D03*
Y924154D03*
Y917461D03*
Y930847D03*
Y940886D03*
Y937540D03*
Y947579D03*
Y954272D03*
Y960965D03*
Y967658D03*
Y974351D03*
Y981044D03*
Y987736D03*
Y994429D03*
Y1001122D03*
Y1027894D03*
Y1034587D03*
Y1041280D03*
Y1047973D03*
Y1054666D03*
Y1061359D03*
Y1071398D03*
Y1064705D03*
Y1078091D03*
Y1088130D03*
Y1084784D03*
Y1094823D03*
Y1101516D03*
Y1108209D03*
Y1114902D03*
Y1131634D03*
Y1124941D03*
Y1121595D03*
Y1138327D03*
Y1145020D03*
Y1151713D03*
Y1161752D03*
Y1158406D03*
Y1168445D03*
Y1175138D03*
Y1181831D03*
Y1188524D03*
Y1205256D03*
Y1198563D03*
Y1195217D03*
Y1211949D03*
Y1218642D03*
Y1225335D03*
Y1235374D03*
Y1232028D03*
Y1242067D03*
Y1248760D03*
X1130067Y756831D03*
Y760177D03*
X1139117Y763765D03*
X1130017Y763524D03*
X1134567Y1068051D03*
Y1064705D03*
X1155209Y756831D03*
Y763524D03*
X1155259Y770217D03*
X1150709Y960965D03*
X1159768Y756831D03*
Y760177D03*
X1168818Y763765D03*
X1159718Y763524D03*
X1164268Y780256D03*
Y786949D03*
Y803681D03*
Y793642D03*
Y796988D03*
Y817067D03*
Y810374D03*
Y823760D03*
Y830453D03*
Y833799D03*
Y840492D03*
Y847185D03*
Y853878D03*
Y860571D03*
Y877303D03*
Y867264D03*
Y870610D03*
Y883996D03*
Y890689D03*
Y897382D03*
Y904075D03*
Y907422D03*
Y914114D03*
Y920807D03*
Y927500D03*
Y934193D03*
Y940886D03*
Y950925D03*
Y944233D03*
Y964311D03*
Y957618D03*
Y971004D03*
X1156209Y960965D03*
X1164268Y977697D03*
Y984390D03*
Y1001122D03*
Y997776D03*
Y991083D03*
Y1031240D03*
Y1037933D03*
Y1044626D03*
Y1058012D03*
Y1051319D03*
Y1074744D03*
Y1068051D03*
Y1064705D03*
Y1081437D03*
Y1088130D03*
Y1098170D03*
Y1104862D03*
Y1091477D03*
Y1111555D03*
Y1118248D03*
Y1134981D03*
Y1124941D03*
Y1128288D03*
Y1148366D03*
Y1141674D03*
Y1155059D03*
Y1161752D03*
Y1165099D03*
Y1171792D03*
Y1178485D03*
Y1185177D03*
Y1191870D03*
Y1208603D03*
Y1198563D03*
Y1201910D03*
Y1215296D03*
Y1221988D03*
Y1228681D03*
Y1235374D03*
Y1238721D03*
Y1245414D03*
Y1252107D03*
X1184910Y756831D03*
X1180410Y776910D03*
X1184910Y763524D03*
X1184960Y770217D03*
X1180410Y783603D03*
Y790296D03*
Y800335D03*
Y807028D03*
Y793642D03*
Y813721D03*
Y820414D03*
Y837146D03*
Y830453D03*
Y827107D03*
Y843839D03*
Y850532D03*
Y857225D03*
Y863918D03*
Y873957D03*
Y880650D03*
Y867264D03*
Y887343D03*
Y894036D03*
Y910768D03*
Y904075D03*
Y900729D03*
Y924154D03*
Y917461D03*
Y930847D03*
Y940886D03*
Y937540D03*
Y947579D03*
Y954272D03*
Y960965D03*
Y967658D03*
Y974351D03*
Y981044D03*
Y987736D03*
Y994429D03*
Y1001122D03*
Y1027894D03*
Y1034587D03*
Y1041280D03*
Y1047973D03*
Y1054666D03*
Y1061359D03*
Y1071398D03*
Y1064705D03*
Y1078091D03*
Y1088130D03*
Y1084784D03*
Y1094823D03*
Y1101516D03*
Y1108209D03*
Y1114902D03*
Y1131634D03*
Y1124941D03*
Y1121595D03*
Y1138327D03*
Y1145020D03*
Y1151713D03*
Y1161752D03*
Y1158406D03*
Y1168445D03*
Y1175138D03*
Y1181831D03*
Y1188524D03*
Y1205256D03*
Y1198563D03*
Y1195217D03*
Y1211949D03*
Y1218642D03*
Y1225335D03*
Y1235374D03*
Y1232028D03*
Y1242067D03*
Y1248760D03*
X1189469Y760177D03*
Y756831D03*
X1198519Y763765D03*
X1188805Y766870D03*
X1189419Y763524D03*
X1194403Y1556953D03*
X1199678Y1559353D03*
X1194954D03*
X1199127Y1556953D03*
X1196127Y1577997D03*
Y1581397D03*
X1196039Y1625380D03*
X1199439D03*
X1196039Y1657292D03*
X1199439D03*
X1214600Y759562D03*
X1205448Y769914D03*
X1214661Y766870D03*
X1214611Y763524D03*
X1214841Y772277D03*
X1210111Y960965D03*
X1203682D03*
X1208576Y1556953D03*
X1204403Y1559353D03*
X1209127D03*
X1203852Y1556953D03*
X1213300D03*
X1213851Y1559353D03*
X1200851Y1577997D03*
X1205576D03*
X1210300D03*
X1215025D03*
X1200851Y1581397D03*
X1205576D03*
X1210300D03*
X1215025D03*
X1208099Y1625380D03*
X1211499D03*
X1208099Y1657292D03*
X1211499D03*
X1218025Y1556953D03*
X1218576Y1559353D03*
X1227474Y1556953D03*
X1228025Y1559353D03*
X1222749Y1556953D03*
X1223300Y1559353D03*
X1219749Y1577997D03*
X1224474D03*
X1229198D03*
X1219749Y1581397D03*
X1224474D03*
X1229198D03*
X1220159Y1625380D03*
X1223559D03*
X1220159Y1657292D03*
X1223559D03*
X1241647Y1556953D03*
X1242198Y1559353D03*
X1232198Y1556953D03*
X1232749Y1559353D03*
X1236922Y1556953D03*
X1237473Y1559353D03*
X1243372Y1577997D03*
X1233923D03*
X1238647D03*
X1243372Y1581397D03*
X1233923D03*
X1238647D03*
X1232219Y1625380D03*
X1244279D03*
X1235619D03*
X1232219Y1657292D03*
X1244279D03*
X1235619D03*
X1251647Y1559353D03*
X1251096Y1556953D03*
X1255820D03*
X1256371Y1559353D03*
X1246371Y1556953D03*
X1246922Y1559353D03*
X1248096Y1577997D03*
X1252820D03*
X1257544D03*
X1248096Y1581397D03*
X1252820D03*
X1257544D03*
X1256339Y1625380D03*
X1247679D03*
X1259739D03*
X1256339Y1657292D03*
X1247679D03*
X1259739D03*
X1265269Y1556953D03*
X1265820Y1559353D03*
X1261096D03*
X1260545Y1556953D03*
X1262269Y1577997D03*
X1266993D03*
X1262269Y1581397D03*
X1266993D03*
X1268399Y1625380D03*
X1271799D03*
X1268399Y1657292D03*
X1271799D03*
X1280459Y1625380D03*
X1283859D03*
X1280459Y1657292D03*
X1283859D03*
X1292519Y1625380D03*
X1304579D03*
X1295919D03*
X1292519Y1657292D03*
X1304579D03*
X1295919D03*
X1316639Y1625380D03*
X1320039D03*
X1307979D03*
X1316639Y1657292D03*
X1320039D03*
X1307979D03*
X1332465Y1559353D03*
X1331914Y1556953D03*
X1322465D03*
X1327189D03*
X1323016Y1559353D03*
X1327740D03*
X1324189Y1577997D03*
X1328913D03*
X1333638D03*
X1324189Y1581397D03*
X1328913D03*
X1333638D03*
X1328699Y1625380D03*
X1332099D03*
X1328699Y1657292D03*
X1332099D03*
X1346087Y1556953D03*
X1346638Y1559353D03*
X1336638Y1556953D03*
X1337189Y1559353D03*
X1341913D03*
X1341362Y1556953D03*
X1338362Y1577997D03*
X1343087D03*
X1347811D03*
X1338362Y1581397D03*
X1343087D03*
X1347811D03*
X1340759Y1625380D03*
X1344159D03*
X1340759Y1657292D03*
X1344159D03*
X1360260Y1556953D03*
X1360811Y1559353D03*
X1350811Y1556953D03*
X1351362Y1559353D03*
X1356087D03*
X1355536Y1556953D03*
X1352536Y1577997D03*
X1357260D03*
X1361985D03*
X1352536Y1581397D03*
X1357260D03*
X1361985D03*
X1352819Y1625380D03*
X1356219D03*
X1352819Y1657292D03*
X1356219D03*
X1369709Y1556953D03*
X1370260Y1559353D03*
X1379158Y1556953D03*
X1374984Y1559353D03*
X1374433Y1556953D03*
X1365535Y1559353D03*
X1364984Y1556953D03*
X1371434Y1577997D03*
X1376158D03*
X1366709D03*
X1371434Y1581397D03*
X1376158D03*
X1366709D03*
X1364879Y1625380D03*
X1376939D03*
X1368279D03*
X1364879Y1657292D03*
X1376939D03*
X1368279D03*
X1388607Y1556953D03*
X1384433Y1559353D03*
X1383882Y1556953D03*
X1379709Y1559353D03*
X1393882D03*
X1389158D03*
X1393331Y1556953D03*
X1380882Y1577997D03*
X1385606D03*
X1390331D03*
X1380882Y1581397D03*
X1385606D03*
X1390331D03*
X1380339Y1625380D03*
Y1657292D03*
X1395055Y1577997D03*
Y1581397D03*
X1458577Y1556953D03*
X1468577Y1559353D03*
X1463852D03*
X1459128D03*
X1463301Y1556953D03*
X1468026D03*
X1460301Y1577997D03*
X1465025D03*
X1460301Y1581397D03*
X1465025D03*
X1460213Y1625380D03*
X1463613D03*
X1460213Y1657292D03*
X1463613D03*
X1482199Y1556953D03*
X1482750Y1559353D03*
X1472750Y1556953D03*
X1473301Y1559353D03*
X1477474Y1556953D03*
X1478025Y1559353D03*
X1469750Y1577997D03*
X1474474D03*
X1479199D03*
X1483923D03*
X1469750Y1581397D03*
X1474474D03*
X1479199D03*
X1483923D03*
X1472273Y1625380D03*
X1475673D03*
X1472273Y1657292D03*
X1475673D03*
X1496372Y1556953D03*
X1491648D03*
X1496923Y1559353D03*
X1492199D03*
X1486923Y1556953D03*
X1487474Y1559353D03*
X1488648Y1577997D03*
X1493372D03*
X1498097D03*
X1488648Y1581397D03*
X1493372D03*
X1498097D03*
X1484333Y1625380D03*
X1496393D03*
X1487733D03*
X1484333Y1657292D03*
X1496393D03*
X1487733D03*
X1505821Y1556953D03*
X1506372Y1559353D03*
X1511096D03*
X1510545Y1556953D03*
X1501096D03*
X1501647Y1559353D03*
X1507546Y1577997D03*
X1512270D03*
X1502821D03*
X1507546Y1581397D03*
X1512270D03*
X1502821D03*
X1508453Y1625380D03*
X1499793D03*
X1511853D03*
X1508453Y1657292D03*
X1499793D03*
X1511853D03*
X1515821Y1559353D03*
X1515270Y1556953D03*
X1519994D03*
X1520545Y1559353D03*
X1525270D03*
X1524719Y1556953D03*
X1516994Y1577997D03*
X1521718D03*
X1526443D03*
X1516994Y1581397D03*
X1521718D03*
X1526443D03*
X1520513Y1625380D03*
X1523913D03*
X1520513Y1657292D03*
X1523913D03*
X1529443Y1556953D03*
X1529994Y1559353D03*
X1531167Y1577997D03*
Y1581397D03*
X1532573Y1625380D03*
X1535973D03*
X1532573Y1657292D03*
X1535973D03*
X1544633Y1625380D03*
X1556693D03*
X1548033D03*
X1544633Y1657292D03*
X1556693D03*
X1548033D03*
X1568753Y1625380D03*
X1560093D03*
X1572153D03*
X1568753Y1657292D03*
X1560093D03*
X1572153D03*
X1586639Y1556953D03*
X1587190Y1559353D03*
X1588363Y1577997D03*
Y1581397D03*
X1580813Y1625380D03*
X1584213D03*
X1580813Y1657292D03*
X1584213D03*
X1600812Y1556953D03*
X1596639Y1559353D03*
X1596088Y1556953D03*
X1601363Y1559353D03*
X1591363Y1556953D03*
X1591914Y1559353D03*
X1593087Y1577997D03*
X1597812D03*
X1602536D03*
X1593087Y1581397D03*
X1597812D03*
X1602536D03*
X1592873Y1625380D03*
X1596273D03*
X1592873Y1657292D03*
X1596273D03*
X1610261Y1556953D03*
X1610812Y1559353D03*
X1606087D03*
X1605536Y1556953D03*
X1614985D03*
X1615536Y1559353D03*
X1607261Y1577997D03*
X1611985D03*
X1616710D03*
X1607261Y1581397D03*
X1611985D03*
X1616710D03*
X1604933Y1625380D03*
X1616993D03*
X1608333D03*
X1604933Y1657292D03*
X1616993D03*
X1608333D03*
X1618996Y760177D03*
Y756831D03*
X1618946Y763524D03*
X1624434Y1556953D03*
X1624985Y1559353D03*
X1620261D03*
X1619710Y1556953D03*
X1629709Y1559353D03*
X1629158Y1556953D03*
X1621434Y1577997D03*
X1626159D03*
X1630883D03*
X1621434Y1581397D03*
X1626159D03*
X1630883D03*
X1629053Y1625380D03*
X1620393D03*
X1632453D03*
X1629053Y1657292D03*
X1620393D03*
X1632453D03*
X1644138Y756831D03*
Y763524D03*
X1644188Y770217D03*
X1639638Y960965D03*
X1634138D03*
X1633883Y1556953D03*
X1634434Y1559353D03*
X1643332Y1556953D03*
X1643883Y1559353D03*
X1639158D03*
X1638607Y1556953D03*
X1635608Y1577997D03*
X1640332D03*
X1645056D03*
X1635608Y1581397D03*
X1640332D03*
X1645056D03*
X1641113Y1625380D03*
X1644513D03*
X1641113Y1657292D03*
X1644513D03*
X1648697Y760177D03*
Y756831D03*
X1657747Y763765D03*
X1648647Y766870D03*
Y763524D03*
X1653197Y780256D03*
Y786949D03*
Y803681D03*
Y793642D03*
Y796988D03*
Y817067D03*
Y810374D03*
Y823760D03*
Y830453D03*
Y833799D03*
Y840492D03*
Y847185D03*
Y853878D03*
Y860571D03*
Y877303D03*
Y867264D03*
Y870610D03*
Y883996D03*
Y890689D03*
Y897382D03*
Y904075D03*
Y907422D03*
Y914114D03*
Y920807D03*
Y927500D03*
Y934193D03*
Y940886D03*
Y950925D03*
Y944233D03*
Y964311D03*
Y957618D03*
Y971004D03*
Y977697D03*
Y984390D03*
Y1001122D03*
Y997776D03*
Y991083D03*
Y1031240D03*
Y1037933D03*
Y1044626D03*
Y1058012D03*
Y1051319D03*
Y1074744D03*
Y1068051D03*
Y1064705D03*
Y1081437D03*
Y1088130D03*
Y1098170D03*
Y1104862D03*
Y1091477D03*
Y1111555D03*
Y1118248D03*
Y1134981D03*
Y1124941D03*
Y1128288D03*
Y1148366D03*
Y1141674D03*
Y1155059D03*
Y1161752D03*
Y1165099D03*
Y1171792D03*
Y1178485D03*
Y1185177D03*
Y1191870D03*
Y1208603D03*
Y1198563D03*
Y1201910D03*
Y1215296D03*
Y1221988D03*
Y1228681D03*
Y1235374D03*
Y1238721D03*
Y1245414D03*
Y1252107D03*
X1652781Y1556953D03*
X1648607Y1559353D03*
X1648056Y1556953D03*
X1658056Y1559353D03*
X1653332D03*
X1657505Y1556953D03*
X1649780Y1577997D03*
X1654505D03*
X1659229D03*
X1649780Y1581397D03*
X1654505D03*
X1659229D03*
X1673839Y756831D03*
X1669339Y776910D03*
X1673839Y763524D03*
X1673889Y770217D03*
X1669339Y783603D03*
Y790296D03*
Y800335D03*
Y807028D03*
Y793642D03*
Y813721D03*
Y820414D03*
Y837146D03*
Y830453D03*
Y827107D03*
Y843839D03*
Y850532D03*
Y857225D03*
Y863918D03*
Y873957D03*
Y880650D03*
Y867264D03*
Y887343D03*
Y894036D03*
Y910768D03*
Y904075D03*
Y900729D03*
Y924154D03*
Y917461D03*
Y930847D03*
Y940886D03*
Y937540D03*
Y947579D03*
Y954272D03*
Y960965D03*
Y967658D03*
Y974351D03*
Y981044D03*
Y987736D03*
Y994429D03*
Y1001122D03*
Y1027894D03*
Y1034587D03*
Y1041280D03*
Y1047973D03*
Y1054666D03*
Y1061359D03*
Y1071398D03*
Y1064705D03*
Y1078091D03*
Y1088130D03*
Y1084784D03*
Y1094823D03*
Y1101516D03*
Y1108209D03*
Y1114902D03*
Y1131634D03*
Y1124941D03*
Y1121595D03*
Y1138327D03*
Y1145020D03*
Y1151713D03*
Y1161752D03*
Y1158406D03*
Y1168445D03*
Y1175138D03*
Y1181831D03*
Y1188524D03*
Y1205256D03*
Y1198563D03*
Y1195217D03*
Y1211949D03*
Y1218642D03*
Y1225335D03*
Y1235374D03*
Y1232028D03*
Y1242067D03*
Y1248760D03*
X1678398Y760177D03*
Y756831D03*
X1687448Y763765D03*
X1678348Y766870D03*
Y763524D03*
X1682898Y1068051D03*
Y1064705D03*
X1703540Y756831D03*
X1703590Y766870D03*
X1703540Y763524D03*
X1703590Y770217D03*
X1699040Y960965D03*
X1693540D03*
X1708099Y760177D03*
Y756831D03*
X1717149Y763765D03*
X1708049Y763524D03*
X1712599Y780256D03*
Y786949D03*
Y803681D03*
Y793642D03*
Y796988D03*
Y817067D03*
Y810374D03*
Y823760D03*
Y830453D03*
Y833799D03*
Y840492D03*
Y847185D03*
Y853878D03*
Y860571D03*
Y877303D03*
Y867264D03*
Y870610D03*
Y883996D03*
Y890689D03*
Y897382D03*
Y904075D03*
Y907422D03*
Y914114D03*
Y920807D03*
Y927500D03*
Y934193D03*
Y940886D03*
Y950925D03*
Y944233D03*
Y964311D03*
Y957618D03*
Y971004D03*
Y977697D03*
Y984390D03*
Y1001122D03*
Y997776D03*
Y991083D03*
Y1031240D03*
Y1037933D03*
Y1044626D03*
Y1058012D03*
Y1051319D03*
Y1074744D03*
Y1068051D03*
Y1064705D03*
Y1081437D03*
Y1088130D03*
Y1098170D03*
Y1104862D03*
Y1091477D03*
Y1111555D03*
Y1118248D03*
Y1134981D03*
Y1124941D03*
Y1128288D03*
Y1148366D03*
Y1141674D03*
Y1155059D03*
Y1161752D03*
Y1165099D03*
Y1171792D03*
Y1178485D03*
Y1185177D03*
Y1191870D03*
Y1208603D03*
Y1198563D03*
Y1201910D03*
Y1215296D03*
Y1221988D03*
Y1228681D03*
Y1235374D03*
Y1238721D03*
Y1245414D03*
Y1252107D03*
X1736986Y109723D03*
Y112223D03*
X1733241Y756831D03*
X1733727Y766870D03*
X1728741Y776910D03*
X1733241Y763524D03*
X1733291Y770217D03*
X1728741Y783603D03*
Y790296D03*
Y800335D03*
Y807028D03*
Y793642D03*
Y813721D03*
Y820414D03*
Y837146D03*
Y830453D03*
Y827107D03*
Y843839D03*
Y850532D03*
Y857225D03*
Y863918D03*
Y873957D03*
Y880650D03*
Y867264D03*
Y887343D03*
Y894036D03*
Y910768D03*
Y904075D03*
Y900729D03*
Y924154D03*
Y917461D03*
Y930847D03*
Y940886D03*
Y937540D03*
Y947579D03*
Y954272D03*
Y960965D03*
Y967658D03*
Y974351D03*
Y981044D03*
Y987736D03*
Y994429D03*
Y1001122D03*
Y1027894D03*
Y1034587D03*
Y1041280D03*
Y1047973D03*
Y1054666D03*
Y1061359D03*
Y1071398D03*
Y1064705D03*
Y1078091D03*
Y1088130D03*
Y1084784D03*
Y1094823D03*
Y1101516D03*
Y1108209D03*
Y1114902D03*
Y1131634D03*
Y1124941D03*
Y1121595D03*
Y1138327D03*
Y1145020D03*
Y1151713D03*
Y1161752D03*
Y1158406D03*
Y1168445D03*
Y1175138D03*
Y1181831D03*
Y1188524D03*
Y1205256D03*
Y1198563D03*
Y1195217D03*
Y1211949D03*
Y1218642D03*
Y1225335D03*
Y1235374D03*
Y1232028D03*
Y1242067D03*
Y1248760D03*
X1740529Y112223D03*
Y109723D03*
X1744072Y112223D03*
Y109723D03*
X1747616Y112223D03*
Y109723D03*
X1737800Y756831D03*
Y760177D03*
X1746850Y763765D03*
X1737750Y763524D03*
X1742300Y780256D03*
Y786949D03*
Y803681D03*
Y793642D03*
Y796988D03*
Y817067D03*
Y810374D03*
Y823760D03*
Y830453D03*
Y833799D03*
Y840492D03*
Y847185D03*
Y853878D03*
Y860571D03*
Y877303D03*
Y867264D03*
Y870610D03*
Y883996D03*
Y890689D03*
Y897382D03*
Y904075D03*
Y907422D03*
Y914114D03*
Y920807D03*
Y927500D03*
Y934193D03*
Y940886D03*
Y950925D03*
Y944233D03*
Y964311D03*
Y957618D03*
Y971004D03*
Y977697D03*
Y984390D03*
Y1001122D03*
Y997776D03*
Y991083D03*
Y1031240D03*
Y1037933D03*
Y1044626D03*
Y1058012D03*
Y1051319D03*
Y1074744D03*
Y1068051D03*
Y1064705D03*
Y1081437D03*
Y1088130D03*
Y1098170D03*
Y1104862D03*
Y1091477D03*
Y1111555D03*
Y1118248D03*
Y1134981D03*
Y1124941D03*
Y1128288D03*
Y1148366D03*
Y1141674D03*
Y1155059D03*
Y1161752D03*
Y1165099D03*
Y1171792D03*
Y1178485D03*
Y1185177D03*
Y1191870D03*
Y1208603D03*
Y1198563D03*
Y1201910D03*
Y1215296D03*
Y1221988D03*
Y1228681D03*
Y1235374D03*
Y1238721D03*
Y1245414D03*
Y1252107D03*
X1762942Y756831D03*
X1762992Y766870D03*
X1758442Y776910D03*
X1762942Y763524D03*
X1762992Y770217D03*
X1758442Y783603D03*
Y790296D03*
Y800335D03*
Y807028D03*
Y793642D03*
Y813721D03*
Y820414D03*
Y837146D03*
Y830453D03*
Y827107D03*
Y843839D03*
Y850532D03*
Y857225D03*
Y863918D03*
Y873957D03*
Y880650D03*
Y867264D03*
Y887343D03*
Y894036D03*
Y910768D03*
Y904075D03*
Y900729D03*
Y924154D03*
Y917461D03*
Y930847D03*
Y940886D03*
Y937540D03*
Y947579D03*
Y954272D03*
Y960965D03*
Y967658D03*
Y974351D03*
Y981044D03*
Y987736D03*
Y994429D03*
Y1001122D03*
Y1027894D03*
Y1034587D03*
Y1041280D03*
Y1047973D03*
Y1054666D03*
Y1061359D03*
Y1071398D03*
Y1064705D03*
Y1078091D03*
Y1088130D03*
Y1084784D03*
Y1094823D03*
Y1101516D03*
Y1108209D03*
Y1114902D03*
Y1131634D03*
Y1124941D03*
Y1121595D03*
Y1138327D03*
Y1145020D03*
Y1151713D03*
Y1161752D03*
Y1158406D03*
Y1168445D03*
Y1175138D03*
Y1181831D03*
Y1188524D03*
Y1205256D03*
Y1198563D03*
Y1195217D03*
Y1211949D03*
Y1218642D03*
Y1225335D03*
Y1235374D03*
Y1232028D03*
Y1242067D03*
Y1248760D03*
X1767500Y760177D03*
Y756831D03*
X1767450Y763524D03*
X1772000Y780256D03*
Y786949D03*
Y803681D03*
Y793642D03*
Y796988D03*
Y817067D03*
Y810374D03*
Y823760D03*
Y830453D03*
Y833799D03*
Y840492D03*
Y847185D03*
Y853878D03*
Y860571D03*
Y877303D03*
Y867264D03*
Y870610D03*
Y883996D03*
Y890689D03*
Y897382D03*
Y904075D03*
Y907422D03*
Y914114D03*
Y920807D03*
Y927500D03*
Y934193D03*
Y940886D03*
Y950925D03*
Y944233D03*
Y964311D03*
Y957618D03*
Y971004D03*
Y977697D03*
Y984390D03*
Y1001122D03*
Y997776D03*
Y991083D03*
Y1031240D03*
Y1037933D03*
Y1044626D03*
Y1058012D03*
Y1051319D03*
Y1074744D03*
Y1068051D03*
Y1064705D03*
Y1081437D03*
Y1088130D03*
Y1098170D03*
Y1104862D03*
Y1091477D03*
Y1111555D03*
Y1118248D03*
Y1134981D03*
Y1124941D03*
Y1128288D03*
Y1148366D03*
Y1141674D03*
Y1155059D03*
Y1161752D03*
Y1165099D03*
Y1171792D03*
Y1178485D03*
Y1185177D03*
Y1191870D03*
Y1208603D03*
Y1198563D03*
Y1201910D03*
Y1215296D03*
Y1221988D03*
Y1228681D03*
Y1235374D03*
Y1238721D03*
Y1245414D03*
Y1252107D03*
X1792642Y756831D03*
X1788142Y776910D03*
X1792642Y763524D03*
X1792692Y770217D03*
X1788142Y783603D03*
Y790296D03*
Y800335D03*
Y807028D03*
Y793642D03*
Y813721D03*
Y820414D03*
Y837146D03*
Y830453D03*
Y827107D03*
Y843839D03*
Y850532D03*
Y857225D03*
Y863918D03*
Y873957D03*
Y880650D03*
Y867264D03*
Y887343D03*
Y894036D03*
Y910768D03*
Y904075D03*
Y900729D03*
Y924154D03*
Y917461D03*
Y930847D03*
Y940886D03*
Y937540D03*
Y947579D03*
Y954272D03*
Y960965D03*
Y967658D03*
Y974351D03*
Y981044D03*
Y987736D03*
Y994429D03*
Y1001122D03*
Y1027894D03*
Y1034587D03*
Y1041280D03*
Y1047973D03*
Y1054666D03*
Y1061359D03*
Y1071398D03*
Y1064705D03*
Y1078091D03*
Y1088130D03*
Y1084784D03*
Y1094823D03*
Y1101516D03*
Y1108209D03*
Y1114902D03*
Y1131634D03*
Y1124941D03*
Y1121595D03*
Y1138327D03*
Y1145020D03*
Y1151713D03*
Y1161752D03*
Y1158406D03*
Y1168445D03*
Y1175138D03*
Y1181831D03*
Y1188524D03*
Y1205256D03*
Y1198563D03*
Y1195217D03*
Y1211949D03*
Y1218642D03*
Y1225335D03*
Y1235374D03*
Y1232028D03*
Y1242067D03*
Y1248760D03*
G54D41*
X373673Y-28871D03*
Y-18871D03*
D03*
Y-8871D03*
X398673Y-28871D03*
Y-18871D03*
D03*
Y-8871D03*
X718093Y-28871D03*
Y-18871D03*
D03*
Y-8871D03*
X743093Y-28871D03*
Y-18871D03*
D03*
Y-8871D03*
X825152Y-35011D03*
Y-25011D03*
Y-15011D03*
Y-25011D03*
Y-15011D03*
Y-5011D03*
D03*
Y4989D03*
Y14989D03*
D03*
Y4989D03*
Y24989D03*
X850152Y-35011D03*
Y-25011D03*
Y-15011D03*
Y-25011D03*
Y-15011D03*
Y-5011D03*
D03*
Y4989D03*
Y14989D03*
D03*
Y4989D03*
Y24989D03*
X1169572Y-35011D03*
Y-15011D03*
Y-25011D03*
D03*
Y-15011D03*
Y-5011D03*
D03*
Y4989D03*
Y14989D03*
Y4989D03*
Y14989D03*
Y24989D03*
X1194572Y-35011D03*
Y-15011D03*
Y-25011D03*
D03*
Y-15011D03*
Y-5011D03*
D03*
Y4989D03*
Y14989D03*
Y4989D03*
Y14989D03*
Y24989D03*
X1228672Y-35011D03*
Y-25011D03*
Y-15011D03*
Y-25011D03*
Y-15011D03*
Y-5011D03*
D03*
Y4989D03*
Y14989D03*
D03*
Y4989D03*
Y24989D03*
X1253672Y-35011D03*
Y-25011D03*
Y-15011D03*
Y-25011D03*
Y-15011D03*
Y-5011D03*
D03*
Y4989D03*
Y14989D03*
D03*
Y4989D03*
Y24989D03*
X1428431Y-35011D03*
Y-15011D03*
Y-25011D03*
D03*
Y-15011D03*
Y-5011D03*
D03*
Y4989D03*
Y14989D03*
Y4989D03*
Y14989D03*
Y24989D03*
X1453431Y-35011D03*
Y-15011D03*
Y-25011D03*
D03*
Y-15011D03*
Y-5011D03*
D03*
Y4989D03*
Y14989D03*
Y4989D03*
Y14989D03*
Y24989D03*
X1521966Y-29212D03*
D03*
Y-39212D03*
Y-19212D03*
X1546966Y-29212D03*
D03*
Y-39212D03*
Y-19212D03*
X1721725Y-29212D03*
Y-39212D03*
Y-29212D03*
Y-19212D03*
X1746725Y-29212D03*
Y-39212D03*
Y-29212D03*
Y-19212D03*
G54D53*
X793879Y194881D03*
X789942Y204724D03*
X793879Y214567D03*
X805690Y188976D03*
Y220472D03*
X817501Y194881D03*
X821438Y204724D03*
X817501Y214567D03*
X828390Y1420331D03*
X841240Y1407481D03*
X832154Y1411245D03*
Y1429417D03*
X841240Y1433181D03*
X850326Y1411245D03*
Y1429417D03*
X854090Y1420331D03*
X1007154Y1411245D03*
X1003390Y1420331D03*
X1007154Y1429417D03*
X1016240Y1407481D03*
Y1433181D03*
X1025326Y1411245D03*
Y1429417D03*
X1029090Y1420331D03*
X1045848Y194881D03*
X1041911Y204724D03*
X1045848Y214567D03*
X1057659Y188976D03*
Y220472D03*
X1069470Y194881D03*
X1073407Y204724D03*
X1069470Y214567D03*
G54D10*
X3001Y61178D03*
Y127178D03*
Y149178D03*
Y171178D03*
Y193178D03*
Y215178D03*
Y237178D03*
Y259178D03*
Y281178D03*
Y303178D03*
X10875Y323721D03*
Y345721D03*
Y367721D03*
Y389721D03*
Y411721D03*
Y433721D03*
Y455721D03*
Y477721D03*
Y499721D03*
Y521721D03*
X20587Y523970D03*
X16342Y516951D03*
X16512Y533155D03*
X10875Y543721D03*
Y565721D03*
Y587721D03*
Y609721D03*
Y653721D03*
Y675721D03*
Y697721D03*
Y719721D03*
Y741721D03*
Y763721D03*
Y785721D03*
Y807721D03*
Y829721D03*
Y851721D03*
Y873721D03*
Y895721D03*
Y917721D03*
Y939721D03*
Y961721D03*
Y983721D03*
Y1005721D03*
Y1027721D03*
Y1049721D03*
Y1071721D03*
Y1093721D03*
Y1115721D03*
Y1137721D03*
Y1159721D03*
Y1181721D03*
Y1203721D03*
Y1225721D03*
Y1247721D03*
Y1269721D03*
Y1291721D03*
Y1445721D03*
Y1467721D03*
Y1489721D03*
Y1511721D03*
Y1533721D03*
Y1555721D03*
Y1577721D03*
X33184Y523285D03*
X36402Y528675D03*
X33257Y540370D03*
X26887Y541805D03*
X35133Y1603396D03*
X35167Y1610521D03*
X28592Y1617961D03*
X35233Y1623196D03*
X28592Y1639961D03*
Y1661961D03*
Y1683961D03*
X44600Y280357D03*
X50500Y311100D03*
X47602Y1622414D03*
X51333Y1640996D03*
X54584Y8335D03*
Y30335D03*
X58633Y1641388D03*
X85133Y1616396D03*
Y1620896D03*
Y1625396D03*
X85167Y1629905D03*
X101939Y1657742D03*
Y1662728D03*
X120891Y521216D03*
X144610Y429560D03*
X163113Y1486190D03*
X160513Y1479500D03*
Y1484280D03*
X165713Y1479500D03*
Y1484280D03*
X160513Y1501300D03*
Y1506080D03*
X165713D03*
X163113Y1507982D03*
X165713Y1501300D03*
X173488Y1510800D03*
Y1514420D03*
Y1518040D03*
X224055Y127146D03*
X262886Y147391D03*
X274201Y579478D03*
X280621Y1486682D03*
X291175Y1486190D03*
X288575Y1484280D03*
Y1479500D03*
X280621Y1500082D03*
X288575Y1506080D03*
Y1501300D03*
X291175Y1507990D03*
X301747Y121469D03*
Y127469D03*
Y124469D03*
X293775Y1484280D03*
Y1479500D03*
Y1506080D03*
Y1501300D03*
X304606Y1546333D03*
X297323Y1659772D03*
X311754Y121472D03*
Y124472D03*
Y127472D03*
X311476Y1552567D03*
X307255Y1649750D03*
X326475Y182855D03*
X349676Y276708D03*
X349695Y286712D03*
X380181Y236674D03*
X390461Y270694D03*
Y267694D03*
Y275194D03*
X387184Y494382D03*
X390082Y1549178D03*
X404743Y494451D03*
X408683Y1486682D03*
Y1500082D03*
X425555Y92014D03*
Y82014D03*
X412715Y254165D03*
X423730Y249570D03*
X412715Y262165D03*
Y270165D03*
X418543Y494374D03*
X418918Y1006025D03*
Y1013505D03*
Y1009765D03*
Y1024726D03*
Y1020986D03*
Y1028466D03*
Y1017245D03*
X415318Y1032206D03*
X424686Y1484280D03*
Y1479500D03*
Y1506080D03*
Y1501300D03*
X431299Y204145D03*
X432343Y494297D03*
X427286Y1486190D03*
X429886Y1484280D03*
Y1479500D03*
Y1506080D03*
Y1501300D03*
X427286Y1507990D03*
X438732Y1546977D03*
X444090Y116007D03*
X443400Y247880D03*
X448852Y283318D03*
X441159Y1055141D03*
X447587Y1552567D03*
X468228Y70016D03*
X457931Y212703D03*
X465699Y282833D03*
X469323Y306273D03*
X462093Y310123D03*
X467943Y311563D03*
X465153Y310123D03*
X467893Y308643D03*
X458873Y310173D03*
X455813D03*
X462365Y1006025D03*
Y1009765D03*
Y1013505D03*
Y1020986D03*
Y1028466D03*
Y1024726D03*
Y1017245D03*
Y1032206D03*
X462500Y1733500D03*
X480323Y291023D03*
X474691Y306073D03*
X471743Y304923D03*
X473643Y308683D03*
X471003Y311563D03*
X470953Y308643D03*
X484063Y313956D03*
X498776Y209285D03*
Y213285D03*
X500269Y225071D03*
X488908Y242754D03*
X503161Y149895D03*
X514418Y141171D03*
X515151Y220166D03*
X501718Y240558D03*
X508723Y280721D03*
X510223Y289035D03*
X507698D03*
Y297090D03*
X510223D03*
X507698Y305145D03*
X510223D03*
X510606Y314124D03*
X508081D03*
X523831Y95445D03*
Y102931D03*
X519579Y207435D03*
X530418Y141171D03*
X538567Y294777D03*
X542813Y319173D03*
X544794Y1486682D03*
Y1500082D03*
X549800Y147000D03*
X553300Y164500D03*
X556811Y152742D03*
X552699Y291833D03*
X556323Y315273D03*
X558743Y313923D03*
X545873Y319173D03*
X549093Y319123D03*
X558003Y320563D03*
X554943D03*
X552153Y319123D03*
X554893Y317643D03*
X557953D03*
X555348Y1486190D03*
X552748Y1484280D03*
Y1479500D03*
X557948Y1484280D03*
Y1479500D03*
X552748Y1506080D03*
Y1501300D03*
X557948Y1506080D03*
Y1501300D03*
X555348Y1507990D03*
X568472Y149226D03*
X563951Y160644D03*
X567323Y300023D03*
X561691Y315073D03*
X560643Y317683D03*
X568573Y321993D03*
X568779Y1546333D03*
X585685Y178125D03*
X578172Y231393D03*
X587140Y257630D03*
X575524Y261171D03*
X575649Y1552567D03*
X599678Y175534D03*
X595723Y289721D03*
X594698Y298035D03*
X597223D03*
X594698Y314145D03*
X597223D03*
X594698Y306090D03*
X597223D03*
Y322200D03*
X594698D03*
X600520Y401728D03*
X616654Y1382864D03*
X633805Y302289D03*
X642816Y574185D03*
X634529Y674890D03*
X640129D03*
X643649Y674781D03*
X649936Y574185D03*
X660062Y672761D03*
X654676Y674806D03*
X654005Y1548999D03*
X670000Y465844D03*
X672856Y1486682D03*
Y1500082D03*
X719195Y172873D03*
Y177865D03*
X714203Y172873D03*
Y177865D03*
X719195Y196373D03*
X714203D03*
X719195Y184873D03*
Y189865D03*
X714203Y184873D03*
Y189865D03*
Y208207D03*
X719195D03*
Y201365D03*
X714203D03*
Y213199D03*
X719195D03*
X744911Y166887D03*
X749261Y1628208D03*
X754286Y266319D03*
X754291Y269322D03*
X756692Y278942D03*
X765285Y276374D03*
X761510Y1638434D03*
X762030Y1668583D03*
X755408Y1672381D03*
X757557Y1684444D03*
X773457Y249792D03*
X774485Y286879D03*
X791341Y264848D03*
X784261Y1482049D03*
Y1534963D03*
X784277Y1528191D03*
X808469Y1356745D03*
Y1359245D03*
X811272Y1382752D03*
X811767Y1388154D03*
X836163Y279355D03*
X856397Y344669D03*
X865132Y333317D03*
X860152D03*
X861377Y344669D03*
X869406Y753541D03*
X874617Y1084657D03*
X877817D03*
Y1088057D03*
X874617D03*
X881217Y1084657D03*
Y1088057D03*
X874617Y1100957D03*
X877817D03*
Y1097557D03*
X874617D03*
X881217Y1100957D03*
Y1097557D03*
X889057Y1053133D03*
X897754Y1156119D03*
X916268Y277859D03*
X928224Y264072D03*
X942763Y272340D03*
X944820Y1156119D03*
X957421Y157699D03*
X960421D03*
X962243Y179917D03*
X947748Y1146553D03*
X964743Y179917D03*
X963985Y177154D03*
X965520Y1567570D03*
X962520D03*
X968520D03*
X965520Y1582570D03*
X962520D03*
Y1579570D03*
X965520D03*
Y1576570D03*
X962520D03*
X965520Y1573570D03*
X962520D03*
Y1570570D03*
X965520D03*
X968520Y1582570D03*
Y1579570D03*
Y1576570D03*
Y1573570D03*
Y1570570D03*
X965520Y1588570D03*
X962520D03*
Y1585570D03*
X965520D03*
X968520Y1588570D03*
Y1585570D03*
X991553Y216809D03*
X988460Y354725D03*
X992233Y373679D03*
X986356Y1087508D03*
X983156D03*
Y1084108D03*
X986356D03*
X989556Y1087508D03*
Y1084108D03*
X986356Y1097008D03*
X983156D03*
Y1100408D03*
X986356D03*
X989556Y1097008D03*
Y1100408D03*
X1002736Y157943D03*
X999736D03*
X993306Y174953D03*
X993206Y178053D03*
X1006436Y176843D03*
X999916Y184548D03*
X996416D03*
X992506Y184553D03*
X993460Y354725D03*
X998460D03*
X997488Y370287D03*
X994160Y1567710D03*
X997160D03*
X1000160D03*
X994160Y1582710D03*
X997160D03*
Y1579710D03*
X994160D03*
X997160Y1570710D03*
X994160D03*
Y1573710D03*
X997160D03*
X994160Y1576710D03*
X997160D03*
X1000160Y1582710D03*
Y1579710D03*
Y1570710D03*
Y1573710D03*
Y1576710D03*
X994160Y1588710D03*
X997160D03*
Y1585710D03*
X994160D03*
X1000160Y1588710D03*
Y1585710D03*
X1021899Y61590D03*
Y127590D03*
X1011358Y195324D03*
X1008068Y198387D03*
X1019936Y207333D03*
Y210463D03*
X1013306Y528942D03*
X1032354Y538201D03*
X1022686D03*
X1027520Y552724D03*
X1025750Y1567710D03*
X1031750D03*
X1028750D03*
X1025750Y1576710D03*
Y1573710D03*
Y1570710D03*
Y1579710D03*
Y1582710D03*
X1028750Y1576710D03*
Y1573710D03*
Y1570710D03*
Y1579710D03*
Y1582710D03*
X1031750Y1576710D03*
Y1573710D03*
Y1570710D03*
Y1579710D03*
Y1582710D03*
X1025750Y1585710D03*
Y1588710D03*
X1028750Y1585710D03*
Y1588710D03*
X1031750Y1585710D03*
Y1588710D03*
X1059055Y492537D03*
X1057219Y1567883D03*
X1060219D03*
X1063219D03*
X1066219D03*
X1057219Y1576883D03*
Y1573883D03*
Y1570883D03*
Y1579883D03*
Y1582883D03*
X1060219Y1576883D03*
Y1573883D03*
Y1570883D03*
Y1579883D03*
Y1582883D03*
X1063219Y1576883D03*
Y1573883D03*
Y1570883D03*
X1066219Y1576883D03*
Y1573883D03*
Y1570883D03*
Y1579883D03*
X1063219D03*
Y1582883D03*
X1066219D03*
X1057219Y1585883D03*
Y1588883D03*
X1060219Y1585883D03*
Y1588883D03*
X1066219Y1585883D03*
X1063219D03*
Y1588883D03*
X1066219D03*
X1094399Y1568043D03*
X1091399D03*
X1085399D03*
X1088399D03*
X1091399Y1580043D03*
X1094399D03*
Y1571043D03*
Y1574043D03*
Y1577043D03*
X1091399Y1571043D03*
Y1574043D03*
Y1577043D03*
X1088399Y1580043D03*
X1085399D03*
X1088399Y1571043D03*
X1085399D03*
Y1574043D03*
X1088399D03*
X1085399Y1577043D03*
X1088399D03*
X1094399Y1583043D03*
X1091399D03*
X1085399D03*
X1088399D03*
X1094399Y1589043D03*
X1091399D03*
Y1586043D03*
X1094399D03*
X1085399Y1589043D03*
X1088399D03*
Y1586043D03*
X1085399D03*
X1092030Y1715841D03*
Y1725991D03*
X1097399Y1568043D03*
Y1580043D03*
Y1571043D03*
Y1574043D03*
Y1577043D03*
Y1583043D03*
Y1589043D03*
Y1586043D03*
X1170986Y1519190D03*
X1168386Y1517280D03*
Y1512500D03*
Y1534300D03*
Y1539080D03*
X1170986Y1540990D03*
X1173586Y1517280D03*
Y1512500D03*
Y1534300D03*
Y1539080D03*
X1181361Y1543800D03*
Y1547420D03*
Y1551040D03*
X1172603Y1554561D03*
X1188472Y80165D03*
X1197980Y1688270D03*
X1213072Y1682899D03*
X1207770Y1717011D03*
Y1731011D03*
X1226094Y297066D03*
X1288494Y1519682D03*
Y1533082D03*
X1304705Y79807D03*
X1303266Y533713D03*
Y530413D03*
X1300200Y590600D03*
X1299048Y1519190D03*
X1296448Y1517280D03*
Y1512500D03*
X1301648Y1517280D03*
Y1512500D03*
X1296448Y1534300D03*
X1301648D03*
X1296448Y1539080D03*
X1301648D03*
X1299048Y1540990D03*
X1309185Y74748D03*
X1316266Y564514D03*
X1317266Y589522D03*
X1318300Y640000D03*
Y643000D03*
Y649000D03*
Y646000D03*
X1318363Y1411404D03*
X1312700Y1579596D03*
X1319349Y1585567D03*
X1330820Y525165D03*
X1330758Y521749D03*
X1330820Y518265D03*
X1330658Y538749D03*
X1330758Y528649D03*
X1330773Y531776D03*
X1330758Y535449D03*
X1329673Y552509D03*
X1332673D03*
X1326673Y544909D03*
X1329673Y545909D03*
Y549309D03*
X1330658Y542949D03*
X1332673Y545909D03*
Y549309D03*
X1329673Y558709D03*
Y555709D03*
X1332673D03*
X1325366Y589522D03*
X1321300Y643000D03*
Y640000D03*
Y649000D03*
Y646000D03*
X1326433Y1214334D03*
X1335260Y236594D03*
Y246594D03*
Y241594D03*
Y251594D03*
X1348611Y1212963D03*
Y1218463D03*
X1364239Y1207949D03*
X1391460Y1032205D03*
X1388918Y1687878D03*
X1382045Y1712038D03*
Y1708038D03*
X1384604Y1728318D03*
X1393179Y1733118D03*
X1404917Y109037D03*
X1395060Y1009764D03*
Y1006024D03*
Y1013504D03*
Y1020985D03*
Y1024725D03*
Y1028465D03*
Y1017244D03*
X1397955Y1582178D03*
X1405058Y1639607D03*
X1417301Y1055140D03*
X1416556Y1519682D03*
Y1533082D03*
X1418740Y1622902D03*
X1427973Y60409D03*
X1438507Y1006024D03*
Y1009764D03*
Y1013504D03*
Y1024725D03*
Y1020985D03*
Y1017244D03*
Y1028465D03*
Y1032205D03*
X1435160Y1519190D03*
X1432560Y1517280D03*
Y1512500D03*
X1437760Y1517280D03*
Y1512500D03*
X1432560Y1534300D03*
X1437760D03*
X1432560Y1539080D03*
X1437760D03*
X1435160Y1540990D03*
X1433979Y1655655D03*
X1441141Y53699D03*
X1448505Y1579725D03*
X1455461Y1585567D03*
X1528993Y4115D03*
Y26115D03*
X1534067Y1582178D03*
X1552668Y1519682D03*
Y1533082D03*
X1568176Y568423D03*
X1570676D03*
X1565676D03*
X1561376Y572258D03*
X1566010Y673210D03*
X1562730Y675180D03*
X1563222Y1519190D03*
X1560622Y1517280D03*
Y1512500D03*
X1565822Y1517280D03*
Y1512500D03*
X1560622Y1534300D03*
X1565822D03*
X1560622Y1539080D03*
X1565822D03*
X1563222Y1540990D03*
X1586291Y306746D03*
X1584160Y558973D03*
X1576653Y1579333D03*
X1583523Y1585567D03*
X1606535Y553297D03*
X1607369Y561330D03*
X1631889Y521480D03*
X1618884Y533388D03*
X1632798Y544564D03*
X1622391Y564169D03*
X1627242Y1436148D03*
X1627181Y1448016D03*
X1636929Y524690D03*
Y528190D03*
Y531690D03*
Y535190D03*
Y538690D03*
X1639868Y542444D03*
X1636783Y542604D03*
X1635798Y545564D03*
X1638798D03*
Y548964D03*
Y552164D03*
X1635798D03*
Y548964D03*
Y555364D03*
X1638798D03*
X1635798Y558364D03*
X1648029Y1718759D03*
Y1733909D03*
X1652525Y141762D03*
X1662129Y1582178D03*
X1673100Y126762D03*
X1676971Y1668582D03*
X1686154Y434160D03*
X1685298Y1451231D03*
X1680730Y1519682D03*
Y1533082D03*
X1688243Y1663802D03*
X1682724Y1717701D03*
X1704444Y407045D03*
X1707444D03*
X1697914Y427155D03*
X1698014Y424055D03*
X1701124Y433650D03*
X1697214Y433655D03*
X1704624Y433650D03*
X1704822Y1694243D03*
X1702985Y1700328D03*
X1711144Y425945D03*
X1722149Y1715265D03*
X1719149Y1703190D03*
X1722149Y1730415D03*
X1724263Y1681465D03*
X1752250Y303850D03*
X1749329Y1662956D03*
X1743329Y1668956D03*
X1743153Y1662956D03*
X1749329Y1674956D03*
X1743329D03*
X1754850Y303930D03*
X1755329Y1668956D03*
Y1662956D03*
Y1674956D03*
X1763463Y1691465D03*
X1758963Y1691565D03*
X1787390Y161834D03*
X1800040Y164393D03*
X1797719Y186610D03*
X1811668Y218900D03*
X1811606Y222513D03*
X1808429Y218837D03*
X1811606Y226438D03*
X1808367Y222450D03*
X1810479Y211850D03*
X1810509Y214660D03*
X1808260Y213232D03*
X1808367Y226375D03*
X1825111Y164393D03*
X1813079Y211850D03*
X1813109Y214660D03*
G54D17*
X18960Y1598181D03*
X440029Y240381D03*
X434420Y239930D03*
X934302Y578318D03*
X1769420Y19506D03*
X1777420D03*
Y24506D03*
G54D19*
X35852Y673010D03*
Y675510D03*
Y697322D03*
Y694822D03*
Y705728D03*
X50138Y425810D03*
X45182D03*
X45022Y449106D03*
X50002D03*
X48626Y552365D03*
X50880Y1412563D03*
X51358Y1647717D03*
Y1650217D03*
X52052Y1684027D03*
X67257Y69340D03*
X62930Y282866D03*
Y312866D03*
X62833Y409597D03*
X62808Y418675D03*
X65380Y427810D03*
X60393D03*
X58349Y1403331D03*
X54449Y1641722D03*
X61415Y1661695D03*
X61374Y1669931D03*
X70127Y1687362D03*
X73015Y28406D03*
X80101D03*
X73015Y40020D03*
X80101D03*
X78253Y75343D03*
X74773Y790297D03*
Y800336D03*
Y827108D03*
Y837147D03*
Y863919D03*
Y873958D03*
Y900730D03*
Y910769D03*
Y937541D03*
Y947580D03*
Y1084785D03*
Y1094824D03*
Y1121596D03*
Y1131635D03*
Y1158407D03*
Y1168446D03*
Y1195218D03*
Y1205257D03*
Y1232029D03*
Y1242068D03*
X71511Y1444379D03*
X69486Y1661828D03*
X69589Y1669878D03*
X78127Y1687362D03*
X74127D03*
X94274Y28406D03*
X87188D03*
Y40020D03*
X94274D03*
X89257Y69340D03*
X90150Y1314560D03*
X86127Y1687362D03*
X92192Y1713741D03*
X92596Y1737117D03*
X108448Y28406D03*
X101361D03*
Y40020D03*
X108448D03*
X100257Y75340D03*
X111257Y69340D03*
X104474Y790297D03*
Y800336D03*
Y827108D03*
Y837147D03*
Y863919D03*
Y873958D03*
Y900730D03*
Y910769D03*
Y937541D03*
Y947580D03*
Y1084785D03*
Y1094824D03*
Y1121596D03*
Y1131635D03*
Y1158407D03*
Y1168446D03*
Y1195218D03*
Y1205257D03*
Y1232029D03*
Y1242068D03*
X112355Y1426064D03*
Y1433564D03*
Y1441064D03*
X110144Y1597831D03*
X110996Y1592018D03*
X122621Y28406D03*
X115534D03*
Y40020D03*
X122621D03*
X122257Y75340D03*
X119855Y1426064D03*
X127355Y1433564D03*
Y1426064D03*
X119855Y1441064D03*
X127355D03*
X127374Y1572749D03*
X127392Y1575524D03*
X125768Y1568744D03*
X127246Y1585801D03*
X127264Y1588576D03*
X113496Y1592018D03*
X116353Y1646612D03*
X120353D03*
X124353D03*
X123278Y1658587D03*
X119353Y1695941D03*
X115353D03*
X125107Y1702666D03*
X124461Y1726116D03*
X114596Y1737117D03*
X129708Y28406D03*
Y40020D03*
X133257Y69343D03*
X141642Y491434D03*
X134174Y790297D03*
Y800336D03*
Y837147D03*
Y827108D03*
Y863919D03*
Y873958D03*
Y900730D03*
Y910769D03*
Y937541D03*
Y947580D03*
Y1084785D03*
Y1094824D03*
Y1121596D03*
Y1131635D03*
Y1158407D03*
Y1168446D03*
Y1195218D03*
Y1205257D03*
Y1232029D03*
Y1242068D03*
X128617Y1561022D03*
X129892Y1575524D03*
X129874Y1572749D03*
X128268Y1568744D03*
X129764Y1588576D03*
X129746Y1585801D03*
X128353Y1646612D03*
X140353D03*
X136048Y1666851D03*
X133548Y1677351D03*
X131353Y1696062D03*
X135353D03*
X139353D03*
X136596Y1737117D03*
X151400Y28406D03*
Y40020D03*
X144257Y75340D03*
X155253Y69343D03*
X148353Y1646612D03*
X144353D03*
X155328Y1670087D03*
X146928Y1685087D03*
X143353Y1696062D03*
X158487Y28406D03*
X165574D03*
X158487Y40020D03*
X165574D03*
X167461Y75340D03*
X163875Y790297D03*
Y800336D03*
Y837147D03*
Y827108D03*
Y863919D03*
Y873958D03*
Y900730D03*
Y910769D03*
Y937541D03*
Y947580D03*
Y1084785D03*
Y1094824D03*
Y1121596D03*
Y1131635D03*
Y1158407D03*
Y1168446D03*
Y1195218D03*
Y1205257D03*
Y1232029D03*
Y1242068D03*
X163421Y1425171D03*
Y1427671D03*
Y1430171D03*
Y1432671D03*
X158596Y1737117D03*
X172660Y28406D03*
X179747D03*
X172660Y40020D03*
X179747D03*
X178461Y69340D03*
X173960Y400560D03*
X172721Y1425171D03*
Y1430171D03*
Y1427671D03*
Y1432671D03*
X175351Y1462595D03*
X182051Y1452895D03*
X181760Y1731351D03*
X180596Y1737117D03*
X195534Y28406D03*
Y40020D03*
X189457Y75343D03*
X200461Y69340D03*
X193576Y790297D03*
Y800336D03*
Y827108D03*
Y837147D03*
Y863919D03*
Y873958D03*
Y900730D03*
Y910769D03*
Y937541D03*
Y947580D03*
Y1084785D03*
Y1094824D03*
Y1121596D03*
Y1131635D03*
Y1158407D03*
Y1168446D03*
Y1205257D03*
Y1195218D03*
Y1232029D03*
Y1242068D03*
X202151Y1462595D03*
X195451Y1472295D03*
X202621Y28406D03*
X216794D03*
X209708D03*
X202621Y40020D03*
X209708D03*
X216794D03*
X211595Y75340D03*
X208851Y1452895D03*
X202596Y1737117D03*
X223881Y28406D03*
X230967D03*
X223881Y40020D03*
X230967D03*
X222591Y69343D03*
X223277Y790297D03*
Y800336D03*
Y837147D03*
Y827108D03*
Y863919D03*
Y873958D03*
Y900730D03*
Y910769D03*
Y937541D03*
Y947580D03*
Y1084785D03*
Y1094824D03*
Y1121596D03*
Y1131635D03*
Y1158407D03*
Y1168446D03*
Y1205257D03*
Y1195218D03*
Y1232029D03*
Y1242068D03*
X228951Y1462595D03*
X222251Y1472295D03*
X224596Y1737117D03*
X233595Y75340D03*
X242215Y151788D03*
X234727Y584030D03*
Y571211D03*
X245815Y672746D03*
X244565Y677846D03*
Y680446D03*
Y675246D03*
X242543Y691115D03*
X239443Y691015D03*
X239843Y709715D03*
X235651Y1452895D03*
X252996Y28365D03*
X256496D03*
X249496D03*
X259996D03*
X252195Y144320D03*
X259475Y657245D03*
X259426Y644830D03*
X259475Y662845D03*
X250312Y670080D03*
Y667180D03*
X250835Y672692D03*
X253279Y672708D03*
X258379Y666644D03*
Y669601D03*
Y672708D03*
X255779D03*
X260979Y666644D03*
Y669601D03*
Y672708D03*
X247165Y677846D03*
Y680446D03*
Y675246D03*
X254448Y692050D03*
X255751Y1462595D03*
X249051Y1472295D03*
X266601Y586578D03*
X271571Y644796D03*
X264335Y657245D03*
X261905D03*
Y662845D03*
X264335D03*
X263579Y669601D03*
X266179D03*
Y672708D03*
X263579D03*
X270857Y668515D03*
X263839Y692049D03*
X275851Y1452895D03*
X262451D03*
X266596Y1737117D03*
X278979Y28406D03*
X286066D03*
X279273Y99186D03*
X289553Y121806D03*
X291109Y700885D03*
X283062Y700979D03*
X279895Y709487D03*
X283565Y706933D03*
X286009Y706949D03*
X278545Y706987D03*
X279895Y712087D03*
Y714687D03*
X291109Y703842D03*
Y706949D03*
X288509D03*
X277295Y709487D03*
Y712087D03*
Y714687D03*
X283062Y703936D03*
X277055Y722649D03*
X279171Y724988D03*
X281992Y1342705D03*
X292705Y580275D03*
X292156Y679071D03*
X304301Y679037D03*
X292205Y691486D03*
X297065D03*
X294635D03*
X293709Y700885D03*
X297065Y697086D03*
X303657Y702815D03*
X292205Y697086D03*
X294635D03*
X293709Y703842D03*
Y706949D03*
X298909Y703842D03*
Y706949D03*
X296309Y703842D03*
Y706949D03*
X303413Y1462595D03*
X315912Y721039D03*
Y723996D03*
X321279Y727099D03*
X312665Y729637D03*
Y732237D03*
X310065Y729637D03*
Y732237D03*
X316335Y727083D03*
X311315Y727137D03*
X318779Y727099D03*
X313255Y746279D03*
X312665Y734837D03*
X310065D03*
X310113Y1452895D03*
X312596Y1737117D03*
X328966Y548030D03*
X324926Y699221D03*
X329835Y711636D03*
X324975D03*
X329835Y717236D03*
X327405Y711636D03*
X324975Y717236D03*
X327405D03*
X326479Y721035D03*
X323879D03*
Y727099D03*
X326479D03*
X329079D03*
X331679D03*
X323879Y723992D03*
X326479D03*
X329079D03*
X331679D03*
X330213Y1462595D03*
X323513Y1472295D03*
X334596Y1737117D03*
X350817Y558248D03*
X343182Y586415D03*
Y591335D03*
X348449Y720827D03*
Y723784D03*
X345725Y729369D03*
X343125D03*
X345725Y731969D03*
X343125D03*
X344375Y726869D03*
X349395Y726815D03*
X336457Y722815D03*
X339825Y746269D03*
X342425D03*
X349625D03*
X345725Y734569D03*
X343125D03*
X336913Y1452895D03*
X350313Y1472295D03*
X352418Y225329D03*
Y222329D03*
X355733Y275059D03*
X357986Y698953D03*
X362895Y716968D03*
X360465Y711368D03*
X362895D03*
X358035D03*
Y716968D03*
X360465D03*
X359539Y720767D03*
X356939D03*
X351839Y726831D03*
X354339D03*
X356939D03*
X362139D03*
X359539D03*
X364739D03*
X356939Y723724D03*
X362139D03*
X359539D03*
X364739D03*
X352225Y746269D03*
X360025D03*
X362625D03*
X352943Y1214510D03*
X363713Y1452895D03*
X357013Y1462595D03*
X356596Y1737117D03*
X379023Y225149D03*
X371318Y218629D03*
X379023Y228649D03*
X379028Y232559D03*
X369428Y231759D03*
X372528Y231859D03*
X369171Y562380D03*
X376671D03*
X369100Y577400D03*
X369171Y569880D03*
X376600Y577400D03*
X376165Y729437D03*
X378765D03*
X376165Y732037D03*
X378765D03*
X377415Y726937D03*
X369557Y722615D03*
X373425Y746169D03*
X370825D03*
X376165Y734637D03*
X378765D03*
X367836Y1209506D03*
X377190Y1387697D03*
X377113Y1472295D03*
X393287Y-9234D03*
X391635Y161091D03*
X384259Y562426D03*
X384301Y577446D03*
X385443Y597279D03*
X391026Y699021D03*
X395935Y717036D03*
Y711436D03*
X393505D03*
X391075D03*
Y717036D03*
X393505D03*
X392579Y720835D03*
X389979D03*
X381802Y720789D03*
Y723746D03*
X387379Y726899D03*
X384879D03*
X389979D03*
Y723792D03*
X382435Y726883D03*
X392579Y726899D03*
X395179D03*
X392579Y723792D03*
X395179D03*
X389981Y1015474D03*
Y1022560D03*
Y1019017D03*
X383813Y1462595D03*
X390513Y1452895D03*
X406243Y100076D03*
X402184Y507101D03*
X403133Y565415D03*
X403157Y569415D03*
X410415Y709137D03*
X409165Y711637D03*
Y714237D03*
Y716837D03*
X397779Y726899D03*
Y723792D03*
X402457Y722615D03*
X397461Y1015474D03*
X404941D03*
X397461Y1022560D03*
X404941Y1019017D03*
Y1022560D03*
X397461Y1019017D03*
X403913Y1452895D03*
X417617Y79073D03*
X423376Y96664D03*
X411952Y132751D03*
Y123051D03*
X422936Y228147D03*
Y232793D03*
X420288Y244184D03*
X415984Y507024D03*
X424026Y681221D03*
X424075Y693636D03*
X425579Y703035D03*
X422979D03*
X424075Y699236D03*
X414682Y703139D03*
X411765Y711637D03*
Y714237D03*
Y716837D03*
X415435Y709083D03*
X417879Y709099D03*
X425579D03*
X422979D03*
X420379D03*
X425579Y705992D03*
X422979D03*
X414682Y706096D03*
X423811Y1009400D03*
Y1028831D03*
X417098Y1533764D03*
Y1531264D03*
X422596Y1737117D03*
X429685Y88657D03*
X436090Y116007D03*
Y124007D03*
Y132007D03*
X440591Y684518D03*
X436130Y683281D03*
X426505Y693636D03*
X428935D03*
Y699236D03*
X426505D03*
X430779Y709099D03*
Y705992D03*
X428179Y709099D03*
Y705992D03*
X435457Y704915D03*
X439411Y733527D03*
X436811D03*
X439411Y736147D03*
X436811D03*
X436411Y738717D03*
X439011D03*
X436411Y743917D03*
X439011D03*
X436411Y741317D03*
X439011D03*
X431291Y1009400D03*
X438316Y1014745D03*
X427551Y1009400D03*
X435031D03*
X438771D03*
X428473Y1014745D03*
X438771Y1028831D03*
X438316Y1023013D03*
X427551Y1028831D03*
X435031D03*
X438316Y1018879D03*
X428473D03*
Y1023013D03*
X431291Y1028831D03*
X427251Y1291747D03*
X439524Y1462595D03*
X448090Y116007D03*
X444090Y132007D03*
X452480Y273420D03*
X441320Y298170D03*
X452565Y652837D03*
X455379Y678435D03*
X450279Y684499D03*
X455379D03*
X452779D03*
X455379Y681392D03*
X444165Y687037D03*
X441565D03*
X443235Y684637D03*
X447835Y684483D03*
X447162Y678409D03*
Y681366D03*
X444325Y702449D03*
X441725D03*
X444165Y689637D03*
Y692237D03*
X441565D03*
Y689637D03*
X446591Y716837D03*
X443991D03*
X446591Y719437D03*
X443991D03*
X441959Y993766D03*
Y997766D03*
X442034Y989766D03*
X442511Y1009400D03*
X449992D03*
X446252D03*
X453732D03*
X441959Y1001766D03*
X447174Y1014745D03*
X446252Y1028831D03*
X453732D03*
X449992D03*
X447174Y1023013D03*
X442511Y1028831D03*
X447174Y1018879D03*
X446224Y1452895D03*
X444596Y1737117D03*
X463402Y229970D03*
X457731Y237588D03*
X463653Y237390D03*
X462703Y242342D03*
X467644Y353417D03*
X469046Y657062D03*
X456426Y656621D03*
X458905Y669036D03*
X456475D03*
X461335D03*
X457979Y678435D03*
X460579Y684499D03*
X457979D03*
X460579Y681392D03*
X457979D03*
X467957Y680315D03*
X463179Y684499D03*
Y681392D03*
X461335Y674636D03*
X456475D03*
X458905D03*
X457472Y1009400D03*
X457410Y1014745D03*
Y1018879D03*
Y1023013D03*
X457472Y1028831D03*
X466324Y1462595D03*
X459624Y1472295D03*
X466596Y1737117D03*
X486682Y197516D03*
X483800Y270440D03*
X475415Y658037D03*
X482879Y657999D03*
X480435Y657983D03*
X485379Y657999D03*
X479822Y651989D03*
Y654946D03*
X476765Y660537D03*
X474165D03*
X476765Y663137D03*
X474165D03*
X476765Y665737D03*
X474165D03*
X473024Y1452895D03*
X495232Y189516D03*
X486600Y200800D03*
X495232Y197516D03*
X491635Y212577D03*
X487541Y226527D03*
X488076Y350420D03*
X501171Y630087D03*
X493935Y642536D03*
X489075D03*
X491505D03*
X489026Y630121D03*
X493935Y648136D03*
X487979Y651935D03*
X490579D03*
X493179Y654892D03*
Y657999D03*
X487979Y654892D03*
X490579D03*
Y657999D03*
X487979D03*
X495779Y654892D03*
Y657999D03*
X489075Y648136D03*
X491505D03*
X499824Y1452895D03*
X493124Y1462595D03*
X486424Y1472295D03*
X488596Y1737117D03*
X510810Y49193D03*
X510065Y626437D03*
X508715Y623937D03*
X507465Y626437D03*
X513735Y623883D03*
X513012Y620706D03*
Y617749D03*
X510065Y629037D03*
X507465D03*
X510065Y631637D03*
X507465D03*
X514771Y643138D03*
X500457Y653715D03*
X513224Y1472295D03*
X517915Y42257D03*
X525001D03*
X517896Y49193D03*
X524763Y49189D03*
X522418Y137171D03*
X526418D03*
X517973Y211998D03*
X522326Y596021D03*
X524805Y608436D03*
X522375D03*
X527235D03*
X526479Y620792D03*
Y623899D03*
X523879Y620792D03*
X521279D03*
X523879Y623899D03*
X521279D03*
X518679D03*
X516179D03*
X529079Y620792D03*
Y623899D03*
X523879Y617835D03*
X521279D03*
X527235Y614036D03*
X522375D03*
X524805D03*
X521771Y643138D03*
X528771D03*
X519924Y1462595D03*
X526624Y1452895D03*
X532070Y49193D03*
X539156D03*
X530418Y137171D03*
X541013Y222441D03*
X534471Y595987D03*
X533857Y619615D03*
X534271Y643138D03*
X540024Y1452895D03*
X532596Y1737117D03*
X557091Y114382D03*
X550505D03*
X553100Y227700D03*
X551200Y377650D03*
X551171Y1167678D03*
X554596Y1737117D03*
X564431Y45132D03*
X562475Y242721D03*
X571271Y1259488D03*
X567586Y1462595D03*
X574286Y1452895D03*
X578621Y45112D03*
X585296Y222954D03*
X586000Y808862D03*
X578830Y1218588D03*
X585501Y1229536D03*
X587686Y1472295D03*
X576596Y1737117D03*
X595682Y44842D03*
X603064Y44523D03*
X599284Y32866D03*
X593920Y49193D03*
X600793Y193185D03*
X596661Y188775D03*
X590300Y190660D03*
X595563Y239128D03*
X603283Y419744D03*
X597071Y799268D03*
X592761Y1220688D03*
X594386Y1462595D03*
X601086Y1452895D03*
X598596Y1737117D03*
X618427Y43432D03*
X615180Y49193D03*
X618600Y160750D03*
X613207Y182229D03*
X615464Y347522D03*
X607871Y359262D03*
X613761Y790418D03*
X605771Y1267098D03*
X614486Y1472295D03*
X624937Y44019D03*
X620390Y36794D03*
X630900Y118920D03*
X632695Y1366157D03*
Y1372257D03*
Y1378257D03*
X627886Y1452895D03*
X621186Y1462595D03*
X620596Y1737117D03*
X648487Y44106D03*
X638695Y1366157D03*
X644795D03*
X643395Y1372857D03*
X638695Y1378257D03*
X644795D03*
X647986Y1462595D03*
X641286Y1472295D03*
X642596Y1737117D03*
X654590Y49193D03*
X661676D03*
X652804Y790297D03*
Y800336D03*
Y837147D03*
Y827108D03*
Y863919D03*
Y873958D03*
Y900730D03*
Y910769D03*
Y937541D03*
Y947580D03*
Y1084785D03*
Y1094824D03*
Y1121596D03*
Y1131635D03*
Y1158407D03*
Y1168446D03*
Y1205257D03*
Y1195218D03*
Y1232029D03*
Y1242068D03*
X661685Y1367283D03*
X654686Y1452895D03*
X662153Y1727718D03*
X675849Y49193D03*
X668763D03*
X668086Y1452895D03*
X664596Y1737117D03*
X682505Y790297D03*
Y800336D03*
Y837147D03*
Y827108D03*
Y863919D03*
Y873958D03*
Y900730D03*
Y910769D03*
Y937541D03*
Y947580D03*
Y1084785D03*
Y1094824D03*
Y1121596D03*
Y1131635D03*
Y1158407D03*
Y1168446D03*
Y1205257D03*
Y1195218D03*
Y1232029D03*
Y1242068D03*
X688540Y1455140D03*
X697400Y345761D03*
X697300Y1454140D03*
X722581Y49182D03*
X713420Y102060D03*
X712206Y790297D03*
Y800336D03*
Y827108D03*
Y837147D03*
Y863919D03*
Y873958D03*
Y900730D03*
Y910769D03*
Y937541D03*
Y947580D03*
Y1084785D03*
Y1094824D03*
Y1121596D03*
Y1131635D03*
Y1158407D03*
Y1168446D03*
Y1195218D03*
Y1205257D03*
Y1232029D03*
Y1242068D03*
X731743Y-30584D03*
X734996Y-30570D03*
X731758Y-28069D03*
X735011Y-28055D03*
X728718Y-29264D03*
X735041Y-23025D03*
X735026Y-25540D03*
X731555Y83685D03*
X737009Y83169D03*
X724134Y141288D03*
X728500Y533862D03*
X736500D03*
X732500D03*
X738260Y553625D03*
X747637Y534874D03*
X740638Y549900D03*
X741907Y790297D03*
Y800336D03*
Y827108D03*
Y837147D03*
Y863919D03*
Y873958D03*
Y900730D03*
Y910769D03*
Y937541D03*
Y947580D03*
Y1084785D03*
Y1094824D03*
Y1121596D03*
Y1131635D03*
Y1158407D03*
Y1168446D03*
Y1195218D03*
Y1205257D03*
Y1232029D03*
Y1242068D03*
X751521Y1659158D03*
X752596Y1737117D03*
X762199Y126684D03*
Y129684D03*
X758111Y172636D03*
X762300Y188910D03*
X764500Y534424D03*
X760500Y534352D03*
X781242Y489574D03*
X771608Y790297D03*
Y800336D03*
Y837147D03*
Y827108D03*
Y863919D03*
Y873958D03*
Y900730D03*
Y910769D03*
Y937541D03*
Y947580D03*
Y1084785D03*
Y1094824D03*
Y1121596D03*
Y1131635D03*
Y1158407D03*
Y1168446D03*
Y1195218D03*
Y1205257D03*
Y1232029D03*
Y1242068D03*
X778030Y1310259D03*
X780530D03*
X773974Y1731920D03*
X796333Y439344D03*
X786030Y1310259D03*
X794030D03*
X796530D03*
X788530D03*
X791823Y1527404D03*
X795926Y1731918D03*
X807451Y763765D03*
X801308Y790297D03*
Y800336D03*
Y837147D03*
Y827108D03*
Y863919D03*
Y873958D03*
Y900730D03*
Y910769D03*
Y937541D03*
Y947580D03*
Y1084785D03*
Y1094824D03*
Y1121596D03*
Y1131635D03*
Y1158407D03*
Y1168446D03*
Y1195218D03*
Y1205257D03*
Y1232029D03*
Y1242068D03*
X802030Y1310259D03*
X804530D03*
X807601Y1307191D03*
X810246Y1351988D03*
X817974Y1731920D03*
X839974D03*
X844766Y-15374D03*
Y-5374D03*
Y24626D03*
X849711Y212062D03*
X845221Y216532D03*
X854707Y229878D03*
X852207D03*
X874295Y163862D03*
X863488Y176332D03*
X861974Y1731920D03*
X883974D03*
X898000Y1112336D03*
Y1109736D03*
Y1116544D03*
Y1119144D03*
Y1130160D03*
Y1132760D03*
Y1123352D03*
Y1125952D03*
X916880Y1138969D03*
X906473Y1158574D03*
X903980Y1268420D03*
X904024Y1272692D03*
X903947Y1276968D03*
X903899Y1281203D03*
X903945Y1285420D03*
X903923Y1289630D03*
X903651Y1293853D03*
X903690Y1298027D03*
X905974Y1731920D03*
X921477Y1134647D03*
X925525Y1135172D03*
X919880Y1146569D03*
Y1139969D03*
Y1143369D03*
Y1149769D03*
X922880Y1146569D03*
Y1139969D03*
Y1143369D03*
Y1149769D03*
X919077Y1136521D03*
X923125Y1137046D03*
X919880Y1152769D03*
X928751Y1266347D03*
X928901Y1270408D03*
X928852Y1274591D03*
X928979Y1278713D03*
X928827Y1283048D03*
X928928Y1287193D03*
X928906Y1291676D03*
X928983Y1295957D03*
X927974Y1731920D03*
X935497Y195925D03*
Y210098D03*
Y203012D03*
Y224272D03*
Y217185D03*
Y231358D03*
X935783Y634051D03*
X941000Y1110557D03*
Y1107957D03*
Y1117557D03*
Y1114957D03*
Y1124557D03*
Y1121957D03*
Y1131557D03*
Y1128957D03*
X953498Y1158574D03*
X949974Y1731920D03*
X967315Y1135550D03*
X972109Y1135149D03*
X966905Y1146569D03*
X969905D03*
X966905Y1139969D03*
Y1143369D03*
X969905Y1139969D03*
Y1143369D03*
X966905Y1149769D03*
X969905D03*
X963012Y1139511D03*
X964915Y1137424D03*
X969709Y1137023D03*
X966905Y1152769D03*
X968594Y1288193D03*
X971974Y1731920D03*
X991031Y528574D03*
X998056Y518214D03*
Y523874D03*
X999031Y528574D03*
X999894Y1267126D03*
X993974Y1731920D03*
X1021220Y243638D03*
X1012220D03*
X1007669Y268884D03*
Y258222D03*
X1007587Y767480D03*
Y769980D03*
Y780880D03*
Y778380D03*
Y789484D03*
Y791984D03*
X1010894Y1271743D03*
X1010865Y1275768D03*
X1010944Y1279751D03*
X1010650Y1310500D03*
X1015974Y1731920D03*
X1025493Y758819D03*
X1044012Y268659D03*
X1051495Y265133D03*
X1040097Y529508D03*
X1050915Y790296D03*
Y800335D03*
Y827107D03*
Y837146D03*
Y863918D03*
Y873957D03*
Y910768D03*
Y900729D03*
Y937540D03*
Y947579D03*
Y1084784D03*
Y1094823D03*
Y1131634D03*
Y1121595D03*
Y1158406D03*
Y1168445D03*
Y1205256D03*
Y1195217D03*
Y1232028D03*
Y1242067D03*
X1037974Y1731920D03*
X1054355Y258698D03*
X1065552Y271441D03*
X1056517Y512787D03*
X1061837Y519703D03*
X1060721Y1313954D03*
X1061974Y1731920D03*
X1080616Y790296D03*
Y800335D03*
Y827107D03*
Y837146D03*
Y863918D03*
Y873957D03*
Y910768D03*
Y900729D03*
Y937540D03*
Y947579D03*
Y1084784D03*
Y1094823D03*
Y1131634D03*
Y1121595D03*
Y1158406D03*
Y1168445D03*
Y1205256D03*
Y1195217D03*
Y1232028D03*
Y1242067D03*
X1081857Y269856D03*
X1089030Y1691229D03*
X1092980Y1696029D03*
X1095489Y1708519D03*
X1081974Y1731920D03*
X1110316Y790296D03*
Y800335D03*
Y827107D03*
Y837146D03*
Y863918D03*
Y873957D03*
Y910768D03*
Y900729D03*
Y937540D03*
Y947579D03*
Y1084784D03*
Y1094823D03*
Y1131634D03*
Y1121595D03*
Y1158406D03*
Y1168445D03*
Y1205256D03*
Y1195217D03*
Y1232028D03*
Y1242067D03*
X1103351Y1737117D03*
X1112001Y1718991D03*
X1125351Y1737117D03*
X1140017Y790296D03*
Y800335D03*
Y827107D03*
Y837146D03*
Y863918D03*
Y873957D03*
Y910768D03*
Y900729D03*
Y937540D03*
Y947579D03*
Y1084784D03*
Y1094823D03*
Y1131634D03*
Y1121595D03*
Y1158406D03*
Y1168445D03*
Y1205256D03*
Y1195217D03*
Y1232028D03*
Y1242067D03*
X1169718Y790296D03*
Y800335D03*
Y837146D03*
Y827107D03*
Y863918D03*
Y873957D03*
Y900729D03*
Y910768D03*
Y937540D03*
Y947579D03*
Y1084784D03*
Y1094823D03*
Y1121595D03*
Y1131634D03*
Y1158406D03*
Y1168445D03*
Y1205256D03*
Y1195217D03*
Y1232028D03*
Y1242067D03*
X1183050Y-20074D03*
Y-10074D03*
Y-74D03*
Y9926D03*
X1183224Y1495595D03*
X1186312Y-20074D03*
Y-10074D03*
Y-74D03*
Y9926D03*
X1200037Y164987D03*
Y160987D03*
X1189727Y177187D03*
X1200012Y185187D03*
X1199419Y790296D03*
Y800335D03*
Y837146D03*
Y827107D03*
Y863918D03*
Y873957D03*
Y900729D03*
Y910768D03*
Y937540D03*
Y947579D03*
Y1084784D03*
Y1094823D03*
Y1121595D03*
Y1131634D03*
Y1158406D03*
Y1168445D03*
Y1195217D03*
Y1205256D03*
Y1232028D03*
Y1242067D03*
X1189924Y1485895D03*
X1199612Y1700334D03*
X1199294Y1721143D03*
X1191351Y1737117D03*
X1215581Y91346D03*
X1202711Y87651D03*
X1215581Y94846D03*
X1213355Y1412564D03*
Y1427564D03*
Y1420064D03*
X1203324Y1505295D03*
X1210024Y1495595D03*
X1214954Y1700343D03*
X1204447Y1707143D03*
X1213351Y1737117D03*
X1223455Y91346D03*
X1230312Y88635D03*
X1215931Y141530D03*
X1218431D03*
X1231118Y142125D03*
X1228355Y1412564D03*
X1220855D03*
X1228355Y1427564D03*
Y1420064D03*
X1220855Y1427564D03*
X1216724Y1485895D03*
X1230124Y1505295D03*
X1235546Y75293D03*
X1232812Y88635D03*
X1239218Y128239D03*
Y137239D03*
Y132739D03*
Y123739D03*
X1238094Y280573D03*
X1233345Y300157D03*
X1242429Y443255D03*
Y447255D03*
X1243524Y1485895D03*
X1236824Y1495595D03*
X1235351Y1737117D03*
X1248286Y-15374D03*
Y-25374D03*
Y14626D03*
X1252561Y72675D03*
X1255185Y140053D03*
Y142553D03*
X1255175Y137553D03*
X1246094Y280573D03*
X1246748Y785752D03*
X1258121Y1342686D03*
X1256924Y1505295D03*
X1257351Y1737117D03*
X1270324Y1485895D03*
X1263624Y1495595D03*
X1278677Y808988D03*
X1283724Y1485895D03*
X1279351Y1737117D03*
X1295532Y539513D03*
X1301666Y555413D03*
X1301351Y1737117D03*
X1319667Y87587D03*
Y105227D03*
X1307857Y111353D03*
X1317986Y1485895D03*
X1311286Y1495595D03*
X1333878Y637721D03*
X1331386Y1505295D03*
X1323351Y1737117D03*
X1344958Y85358D03*
X1336558Y637721D03*
X1339238D03*
X1344438D03*
X1341838D03*
X1344786Y1485895D03*
X1338086Y1495595D03*
X1345351Y1737117D03*
X1356868Y85324D03*
X1360629Y120380D03*
X1363831Y642042D03*
X1361387Y642026D03*
X1356367Y642080D03*
X1352527Y638278D03*
X1360944Y638999D03*
Y636042D03*
X1357717Y647180D03*
Y649780D03*
X1355117D03*
Y647180D03*
X1357717Y644580D03*
X1355117D03*
X1364317Y661368D03*
X1357057Y661328D03*
X1364886Y1495595D03*
X1358186Y1505295D03*
X1369808Y87587D03*
X1382123Y614130D03*
X1374887Y626579D03*
X1372457D03*
X1370027D03*
X1369978Y614164D03*
X1366331Y642042D03*
X1376731Y638935D03*
Y642042D03*
X1371531Y638935D03*
Y642042D03*
Y635978D03*
X1374887Y632179D03*
X1374131Y638935D03*
Y642042D03*
X1368931Y638935D03*
Y642042D03*
Y635978D03*
X1370027Y632179D03*
X1372457D03*
X1371847Y661328D03*
X1366123Y1015473D03*
X1373603D03*
Y1019016D03*
Y1022559D03*
X1366123D03*
Y1019016D03*
X1371586Y1485895D03*
X1367351Y1737117D03*
X1381457Y637865D03*
X1380306Y664816D03*
X1380256Y667466D03*
X1393664Y671949D03*
Y668992D03*
X1390417Y677480D03*
X1389067Y674980D03*
X1387817Y677480D03*
X1394087Y674926D03*
X1390417Y680080D03*
X1387817D03*
X1390417Y682680D03*
X1387817D03*
X1388757Y693397D03*
Y690897D03*
X1381083Y1015473D03*
Y1022559D03*
Y1019016D03*
X1384986Y1505295D03*
X1391686Y1495595D03*
X1389351Y1737117D03*
X1403207Y118938D03*
X1402678Y647064D03*
X1404231Y671835D03*
X1406831D03*
X1409431D03*
X1404231Y668878D03*
X1407587Y665079D03*
X1405157Y659479D03*
X1407587D03*
X1401631Y671835D03*
Y668878D03*
X1402727Y659479D03*
Y665079D03*
X1405157D03*
X1404231Y674942D03*
X1409431D03*
X1406831D03*
X1396531D03*
X1399031D03*
X1401631D03*
X1403693Y1009399D03*
X1407433D03*
X1399953D03*
X1404615Y1014744D03*
X1399953Y1028830D03*
X1407433D03*
X1404615Y1023012D03*
Y1018878D03*
X1403693Y1028830D03*
X1406608Y1282606D03*
X1398386Y1485895D03*
X1414823Y647030D03*
X1414157Y670665D03*
X1416241Y700281D03*
X1416291Y697631D03*
X1420417Y712660D03*
Y715260D03*
Y710060D03*
X1423017Y712660D03*
Y715260D03*
Y710060D03*
X1421667Y707560D03*
X1422757Y726097D03*
Y723597D03*
X1418101Y997765D03*
Y993765D03*
X1418176Y989765D03*
X1418653Y1009399D03*
X1418101Y1001765D03*
X1422394Y1009399D03*
X1414913D03*
X1411173D03*
X1423316Y1014744D03*
X1414458D03*
Y1023012D03*
X1418653Y1028830D03*
X1411173D03*
X1414913D03*
X1423316Y1023012D03*
Y1018878D03*
X1422394Y1028830D03*
X1414458Y1018878D03*
X1411786Y1485895D03*
X1413199Y1643920D03*
X1411351Y1737117D03*
X1438883Y-15050D03*
Y-25050D03*
Y-5050D03*
Y14950D03*
Y4950D03*
X1438312Y152166D03*
X1435278Y679644D03*
X1436257Y676265D03*
X1436831Y701458D03*
X1435327Y692059D03*
X1437757D03*
X1434231Y701458D03*
X1435327Y697659D03*
X1437757D03*
X1426264Y701572D03*
X1436831Y704415D03*
Y707522D03*
X1439431Y704415D03*
Y707522D03*
X1431631D03*
X1429131D03*
X1426687Y707506D03*
X1434231Y704415D03*
Y707522D03*
X1426264Y704529D03*
X1433614Y1009399D03*
X1426134D03*
X1429874D03*
X1433552Y1014744D03*
X1429874Y1028830D03*
X1433552Y1018878D03*
Y1023012D03*
X1426134Y1028830D03*
X1433614D03*
X1433351Y1737117D03*
X1441908Y-26370D03*
X1445161Y-26356D03*
X1441908Y-16370D03*
X1441923Y-13855D03*
X1445161Y-16356D03*
X1445176Y-13841D03*
X1441923Y-23855D03*
X1445176Y-23841D03*
X1441908Y-6370D03*
X1441923Y-3855D03*
X1445161Y-6356D03*
X1445176Y-3841D03*
X1441908Y3630D03*
X1445161Y3644D03*
X1441908Y13630D03*
X1441923Y16145D03*
X1445161Y13644D03*
X1445176Y16159D03*
X1441923Y6145D03*
X1445176Y6159D03*
X1440871Y130118D03*
X1453667Y152166D03*
X1447423Y679610D03*
X1440187Y697659D03*
X1446757Y703265D03*
X1440187Y692059D03*
X1442031Y704415D03*
Y707522D03*
X1453335Y729637D03*
Y732237D03*
Y734837D03*
X1453757Y743597D03*
Y746097D03*
X1454098Y1485895D03*
X1447398Y1495595D03*
X1459177Y163796D03*
X1456282Y568977D03*
Y572977D03*
Y576977D03*
Y580977D03*
X1468196Y699221D03*
X1468245Y711636D03*
Y717236D03*
X1467149Y721035D03*
X1458599Y721045D03*
Y724002D03*
X1455935Y729637D03*
Y732237D03*
X1454585Y727137D03*
X1459605Y727083D03*
X1462049Y727099D03*
X1464549D03*
X1467149Y723992D03*
Y727099D03*
X1455935Y734837D03*
X1467498Y1505295D03*
X1455579Y1636114D03*
X1473105Y717236D03*
X1470675Y711636D03*
X1473105D03*
X1470675Y717236D03*
X1469749Y721035D03*
X1479757Y722865D03*
X1469749Y723992D03*
X1474949D03*
X1472349D03*
Y727099D03*
X1469749D03*
X1474949D03*
X1481665Y745809D03*
X1477177Y803488D03*
X1478177Y817013D03*
X1480898Y1485895D03*
X1474198Y1495595D03*
X1498543Y587841D03*
X1492264Y721149D03*
X1486417Y729637D03*
Y732237D03*
X1489017Y729687D03*
Y732237D03*
X1492264Y724106D03*
X1487667Y727137D03*
X1492687Y727083D03*
X1495131Y727099D03*
X1497631D03*
X1486417Y734837D03*
X1489017D03*
X1484265Y745809D03*
X1489177Y803488D03*
X1498177Y817013D03*
X1494298Y1505295D03*
X1501278Y699221D03*
X1506187Y717236D03*
Y711636D03*
X1501327D03*
X1503757D03*
X1501327Y717404D03*
X1503757D03*
X1502831Y721035D03*
X1500231D03*
X1512757Y722897D03*
X1500231Y723992D03*
X1502831D03*
X1505431D03*
X1508031D03*
X1500231Y727099D03*
X1502831D03*
X1505431D03*
X1508031D03*
X1505905Y746119D03*
X1508505D03*
X1507698Y1485895D03*
X1500998Y1495595D03*
X1499351Y1737117D03*
X1519930Y543470D03*
X1516357Y555318D03*
X1516257Y559977D03*
X1525064Y721149D03*
Y724106D03*
X1521817Y729637D03*
Y732237D03*
X1525487Y727083D03*
X1527931Y727099D03*
X1519217Y729637D03*
Y732237D03*
X1520467Y727137D03*
X1521817Y734837D03*
X1519217D03*
X1515895Y746119D03*
X1518495D03*
X1521098Y1505295D03*
X1527798Y1495595D03*
X1521351Y1737117D03*
X1541580Y-19575D03*
X1541666Y69340D03*
X1532853Y560264D03*
X1534078Y699221D03*
X1536557Y711636D03*
X1534127D03*
X1538987Y717236D03*
Y711636D03*
X1534127Y717236D03*
X1536557D03*
X1535631Y721035D03*
X1533031D03*
X1538231Y723992D03*
X1540831D03*
X1538231Y727099D03*
X1540831D03*
X1530431D03*
X1533031Y723992D03*
X1535631D03*
X1533031Y727099D03*
X1535631D03*
X1543563Y757803D03*
X1543585Y762919D03*
X1543574Y760361D03*
X1534317Y1216828D03*
X1531227Y1227648D03*
X1540227D03*
X1534498Y1485895D03*
X1543351Y1737117D03*
X1554510Y28406D03*
X1547424D03*
X1554510Y40020D03*
X1547424D03*
X1552662Y75343D03*
X1546257Y701097D03*
X1558194Y702166D03*
Y699209D03*
X1552347Y712897D03*
X1554947D03*
X1552347Y710297D03*
Y707697D03*
X1554947Y710297D03*
Y707697D03*
X1553597Y705197D03*
X1558617Y705143D03*
X1551250Y723840D03*
X1553750D03*
X1545557Y722897D03*
X1556555Y740617D03*
X1556544Y738059D03*
X1554055Y740617D03*
X1554044Y738059D03*
X1546965Y746119D03*
X1546954Y743561D03*
X1548119Y751952D03*
X1545619D03*
X1548119Y754832D03*
X1545619D03*
X1546063Y757803D03*
X1546085Y762919D03*
X1546074Y760361D03*
X1549877Y1217288D03*
Y1221288D03*
X1547898Y1485895D03*
X1561597Y28406D03*
X1568683D03*
Y40020D03*
X1561597D03*
X1563666Y69340D03*
X1567208Y677281D03*
X1572117Y695296D03*
X1568761Y702052D03*
X1571361D03*
X1568761Y699095D03*
X1566161Y702052D03*
Y699095D03*
X1569687Y689696D03*
X1572117D03*
X1567257D03*
Y695296D03*
X1569687D03*
X1563561Y705159D03*
X1561061D03*
X1568761D03*
X1571361D03*
X1566161D03*
X1568660Y1283460D03*
X1572036Y1306083D03*
X1565351Y1737117D03*
X1575770Y28406D03*
X1582857D03*
Y40020D03*
X1575770D03*
X1574666Y75340D03*
X1585666Y69340D03*
X1579748Y536344D03*
X1576843Y674425D03*
X1579807Y671268D03*
X1586367Y671428D03*
X1587717Y676528D03*
Y673928D03*
X1585117Y676528D03*
Y673928D03*
Y679128D03*
X1587717D03*
X1578757Y700965D03*
X1573961Y702052D03*
X1586070Y696830D03*
Y694330D03*
X1573961Y705159D03*
X1578904Y721340D03*
Y723840D03*
X1584849Y793506D03*
X1587028Y1307137D03*
X1582160Y1485895D03*
X1575460Y1495595D03*
X1587351Y1737117D03*
X1589943Y28406D03*
X1597030D03*
Y40020D03*
X1589943D03*
X1596666Y75340D03*
X1599837Y295328D03*
X1593214Y531226D03*
X1599978Y643512D03*
X1600027Y655927D03*
X1602457D03*
X1591387Y671374D03*
X1593831Y671390D03*
X1596331D03*
X1601531D03*
Y668283D03*
Y665326D03*
X1598931Y671390D03*
Y668283D03*
Y665326D03*
X1600027Y661527D03*
X1602457D03*
X1590964Y668397D03*
Y665440D03*
X1594539Y1295288D03*
X1595560Y1505295D03*
X1602260Y1495595D03*
X1604117Y28406D03*
Y40020D03*
X1607666Y69343D03*
X1609355Y592794D03*
X1615677Y648488D03*
X1604887Y655927D03*
X1618117Y657528D03*
Y654928D03*
X1611557Y667165D03*
X1606731Y671390D03*
Y668283D03*
X1604131Y671390D03*
Y668283D03*
X1604887Y661527D03*
X1618117Y660128D03*
X1613154Y688238D03*
Y690738D03*
X1605447Y1288748D03*
X1608960Y1485895D03*
X1609351Y1737117D03*
X1632896Y28406D03*
X1625809D03*
X1632896Y40020D03*
X1625809D03*
X1618666Y75340D03*
X1631558Y588513D03*
X1628756Y588591D03*
X1624067Y588474D03*
X1621187Y588591D03*
X1632978Y624512D03*
X1633027Y636927D03*
Y642527D03*
X1620717Y657528D03*
X1631931Y652390D03*
Y649283D03*
X1626831Y652390D03*
X1629331D03*
X1631931Y646326D03*
X1624387Y652374D03*
X1619367Y652428D03*
X1620717Y654928D03*
X1623964Y649397D03*
Y646440D03*
X1621050Y671768D03*
X1623550D03*
X1620717Y660128D03*
X1628946Y790296D03*
Y800335D03*
Y827107D03*
Y837146D03*
Y863918D03*
Y873957D03*
Y900729D03*
Y910768D03*
Y937540D03*
Y947579D03*
Y1084784D03*
Y1094823D03*
Y1121595D03*
Y1131634D03*
Y1158406D03*
Y1168445D03*
Y1195217D03*
Y1205256D03*
Y1232028D03*
Y1242067D03*
X1629060Y1495595D03*
X1622360Y1505295D03*
X1631351Y1737117D03*
X1647069Y28406D03*
X1639983D03*
X1647069Y40020D03*
X1639983D03*
X1641870Y75340D03*
X1645123Y624478D03*
X1637887Y642527D03*
Y636927D03*
X1635457D03*
Y642527D03*
X1644457Y648265D03*
X1639731Y652390D03*
X1634531D03*
X1637131D03*
X1639731Y649283D03*
X1634531D03*
X1637131D03*
X1634531Y646326D03*
X1643183Y1419441D03*
X1643283Y1431541D03*
X1635760Y1485895D03*
X1654156Y28406D03*
Y40020D03*
X1652870Y69340D03*
X1650917Y657528D03*
Y654928D03*
X1653517Y657528D03*
X1652167Y652428D03*
X1653517Y654928D03*
X1648604Y671768D03*
X1650917Y660128D03*
X1659618Y659021D03*
X1662298D03*
X1651104Y671768D03*
X1653517Y660128D03*
X1656938Y659021D03*
X1651959Y689800D03*
X1658647Y790296D03*
Y800335D03*
Y827107D03*
Y837146D03*
Y863918D03*
Y873957D03*
Y900729D03*
Y910768D03*
Y937540D03*
Y947579D03*
Y1084784D03*
Y1094823D03*
Y1121595D03*
Y1131634D03*
Y1158406D03*
Y1168445D03*
Y1205256D03*
Y1195217D03*
Y1232028D03*
Y1242067D03*
X1649283Y1419441D03*
Y1431541D03*
X1655383D03*
Y1419441D03*
X1655957Y1445116D03*
X1662560Y1485895D03*
X1649160Y1505295D03*
X1655860Y1495595D03*
X1653351Y1737117D03*
X1677030Y28406D03*
X1669943D03*
X1677030Y40020D03*
X1669943D03*
X1663866Y75343D03*
X1674870Y69340D03*
X1668516Y599956D03*
X1674516D03*
X1668516Y609450D03*
X1671516Y599956D03*
X1674516Y609450D03*
X1677516Y599956D03*
X1671516Y609450D03*
X1677516D03*
X1667498Y659021D03*
X1664898D03*
X1675960Y1485895D03*
X1668000Y1711759D03*
Y1726909D03*
X1675351Y1737117D03*
X1684117Y28406D03*
X1691203D03*
Y40020D03*
X1684117D03*
X1686004Y75340D03*
X1688348Y790296D03*
Y800335D03*
Y827107D03*
Y837146D03*
Y863918D03*
Y873957D03*
Y910768D03*
Y900729D03*
Y937540D03*
Y947579D03*
Y1084784D03*
Y1094823D03*
Y1131634D03*
Y1121595D03*
Y1158406D03*
Y1168445D03*
Y1205256D03*
Y1195217D03*
Y1232028D03*
Y1242067D03*
X1684677Y1440258D03*
X1687357Y1440268D03*
X1698290Y28406D03*
X1705376D03*
X1698290Y40020D03*
X1697000Y69343D03*
X1701121Y641658D03*
X1706101D03*
X1695529Y1545193D03*
X1703000Y1711759D03*
X1697351Y1737117D03*
X1708004Y75340D03*
X1708305Y679720D03*
X1718049Y790296D03*
Y800335D03*
Y827107D03*
Y837146D03*
Y863918D03*
Y873957D03*
Y910768D03*
Y900729D03*
Y937540D03*
Y947579D03*
Y1084784D03*
Y1094823D03*
Y1131634D03*
Y1121595D03*
Y1158406D03*
Y1168445D03*
Y1195217D03*
Y1205256D03*
Y1232028D03*
Y1242067D03*
X1719351Y1737117D03*
X1735375Y-40925D03*
X1732350Y-39605D03*
X1735390Y-38410D03*
X1738628Y-40911D03*
X1738658Y-35881D03*
X1738673Y-33366D03*
X1738643Y-38396D03*
X1749571Y255317D03*
Y252317D03*
X1745502Y660088D03*
X1747750Y790296D03*
Y800335D03*
Y827107D03*
Y837146D03*
Y863918D03*
Y873957D03*
Y910768D03*
Y900729D03*
Y937540D03*
Y947579D03*
Y1084784D03*
Y1094823D03*
Y1131634D03*
Y1121595D03*
Y1158406D03*
Y1168445D03*
Y1205256D03*
Y1195217D03*
Y1232028D03*
Y1242067D03*
X1742120Y1708265D03*
Y1723415D03*
X1741351Y1737117D03*
X1753388Y28406D03*
X1760475D03*
X1754364Y100353D03*
X1764644Y122973D03*
X1755969Y251524D03*
Y248524D03*
X1763509Y251341D03*
Y248341D03*
X1763351Y1737117D03*
X1771881Y128439D03*
Y125939D03*
Y123439D03*
X1781966Y128501D03*
Y126001D03*
Y123501D03*
X1775984Y253779D03*
Y256779D03*
X1777450Y790296D03*
Y800335D03*
Y827107D03*
Y837146D03*
Y863918D03*
Y873957D03*
Y910768D03*
Y900729D03*
Y937540D03*
Y947579D03*
Y1084784D03*
Y1094823D03*
Y1131634D03*
Y1121595D03*
Y1158406D03*
Y1168445D03*
Y1205256D03*
Y1195217D03*
Y1232028D03*
Y1242067D03*
X1785072Y53161D03*
X1789811Y178083D03*
X1794629Y193323D03*
X1791645Y193397D03*
X1795219Y185910D03*
X1795949Y205580D03*
X1795909Y209128D03*
X1795365Y197567D03*
X1796019Y202030D03*
X1791445Y197497D03*
X1783592Y763765D03*
X1804111Y178083D03*
X1807711D03*
Y175083D03*
X1803165Y196127D03*
X1797621Y193373D03*
X1800389Y193424D03*
X1803045Y193397D03*
X1798943Y204744D03*
Y209044D03*
X1802276Y209013D03*
X1805235Y208950D03*
X1802276Y204713D03*
X1800125Y201857D03*
X1805235Y204650D03*
X1799629Y198870D03*
X1803145Y198697D03*
X1817674Y188699D03*
X1829732Y367359D03*
G54D24*
X67725Y1538946D03*
X74912D03*
X72585D03*
X70155D03*
X103468D03*
X105898D03*
X108328D03*
X110655D03*
X1757438Y1571982D03*
X1755008D03*
X1762195D03*
X1759868D03*
X1793181D03*
X1790751D03*
X1795611D03*
X1797938D03*
G54D28*
X130000Y1719450D03*
X543277Y88632D03*
X538620Y93289D03*
G54D63*
X1156378Y133866D03*
X1183858Y207205D03*
X1173858D03*
X1193858D03*
X1351260Y164213D03*
Y174213D03*
X1361260Y164213D03*
Y174213D03*
X1371260Y164213D03*
X1381260D03*
X1371260Y174213D03*
X1381260D03*
X1391260Y164213D03*
Y174213D03*
G54D20*
X35852Y670445D03*
Y667045D03*
Y681410D03*
Y678010D03*
Y692316D03*
Y703222D03*
Y688916D03*
Y699822D03*
X90965Y960966D03*
X112473Y1660235D03*
X109073D03*
X107569Y1685763D03*
X110969D03*
X120666Y960966D03*
X150366D03*
X154945Y1624350D03*
Y1627750D03*
X158425Y780257D03*
Y786950D03*
Y803682D03*
Y793643D03*
Y796989D03*
Y817068D03*
Y810375D03*
Y823761D03*
Y830454D03*
Y833800D03*
Y840493D03*
Y847186D03*
Y853879D03*
Y860572D03*
Y877304D03*
Y867265D03*
Y870611D03*
Y883997D03*
Y890690D03*
Y897383D03*
Y904076D03*
Y907423D03*
Y914115D03*
Y920808D03*
Y927501D03*
Y934194D03*
Y940887D03*
Y950926D03*
Y944234D03*
Y964312D03*
Y957619D03*
Y971005D03*
Y977698D03*
Y984391D03*
Y1001123D03*
Y997777D03*
Y991084D03*
Y1031241D03*
Y1037934D03*
Y1044627D03*
Y1058013D03*
Y1051320D03*
Y1074745D03*
Y1081438D03*
Y1088131D03*
Y1098171D03*
Y1104863D03*
Y1091478D03*
Y1111556D03*
Y1118249D03*
Y1134982D03*
Y1124942D03*
Y1128289D03*
Y1148367D03*
Y1141675D03*
Y1155060D03*
Y1161753D03*
Y1165100D03*
Y1171793D03*
Y1178486D03*
Y1185178D03*
Y1191871D03*
Y1208604D03*
Y1198564D03*
Y1201911D03*
Y1215297D03*
Y1221989D03*
Y1228682D03*
Y1235375D03*
Y1238722D03*
Y1245415D03*
Y1252108D03*
X163735Y1635369D03*
Y1631969D03*
X174567Y776911D03*
Y783604D03*
Y790297D03*
Y800336D03*
Y807029D03*
Y793643D03*
Y813722D03*
Y820415D03*
Y837147D03*
Y830454D03*
Y827108D03*
Y843840D03*
Y850533D03*
Y857226D03*
Y863919D03*
Y873958D03*
Y880651D03*
Y867265D03*
Y887344D03*
Y894037D03*
Y910769D03*
Y904076D03*
Y900730D03*
Y924155D03*
Y917462D03*
Y930848D03*
Y940887D03*
Y937541D03*
Y947580D03*
Y954273D03*
Y967659D03*
Y974352D03*
Y981045D03*
Y987737D03*
Y994430D03*
Y1001123D03*
Y1027895D03*
Y1034588D03*
Y1041281D03*
Y1047974D03*
Y1054667D03*
Y1061360D03*
Y1071399D03*
Y1064706D03*
Y1078092D03*
Y1088131D03*
Y1084785D03*
Y1094824D03*
Y1101517D03*
Y1108210D03*
Y1114903D03*
Y1131635D03*
Y1124942D03*
Y1121596D03*
Y1138328D03*
Y1145021D03*
Y1151714D03*
Y1161753D03*
Y1158407D03*
Y1168446D03*
Y1175139D03*
Y1181832D03*
Y1188525D03*
Y1205257D03*
Y1198564D03*
Y1195218D03*
Y1211950D03*
Y1218643D03*
Y1225336D03*
Y1235375D03*
Y1232029D03*
Y1242068D03*
Y1248761D03*
X194196Y1602380D03*
X197596D03*
X194196Y1614292D03*
X197596D03*
X209768Y960966D03*
X206256Y1602380D03*
X209656D03*
X206256Y1614292D03*
X209656D03*
X218316Y1602380D03*
X230376D03*
X221716D03*
X218316Y1614292D03*
X230376D03*
X221716D03*
X242436Y1602380D03*
X233776D03*
X245836D03*
X242436Y1614292D03*
X233776D03*
X245836D03*
X254496Y1602380D03*
X257896D03*
X254496Y1614292D03*
X257896D03*
X266556Y1602380D03*
X269956D03*
X266556Y1614292D03*
X269956D03*
X278616Y1602380D03*
X290676D03*
X282016D03*
X278616Y1614292D03*
X290676D03*
X282016D03*
X302736Y1602380D03*
X294076D03*
X306136D03*
X302736Y1614292D03*
X294076D03*
X306136D03*
X297323Y1657172D03*
Y1653772D03*
X314796Y1602380D03*
X318196D03*
X314796Y1614292D03*
X318196D03*
X307255Y1643750D03*
Y1647150D03*
X326856Y1602380D03*
X330256D03*
X326856Y1614292D03*
X330256D03*
X338916Y1602380D03*
X350976D03*
X342316D03*
X338916Y1614292D03*
X350976D03*
X342316D03*
X363036Y1602380D03*
X354376D03*
X363036Y1614292D03*
X354376D03*
X375096Y1602380D03*
X366436D03*
X378496D03*
X375096Y1614292D03*
X366436D03*
X378496D03*
X390841Y-25571D03*
Y-22171D03*
Y-15571D03*
Y-12171D03*
X455502Y88711D03*
X452102D03*
X458369Y1602380D03*
X461769D03*
X458369Y1614292D03*
X461769D03*
X476295Y130020D03*
X472895D03*
X470429Y1602380D03*
X482489D03*
X473829D03*
X470429Y1614292D03*
X482489D03*
X473829D03*
X494549Y1602380D03*
X485889D03*
X497949D03*
X494549Y1614292D03*
X485889D03*
X497949D03*
X506609Y1602380D03*
X510009D03*
X506609Y1614292D03*
X510009D03*
X518669Y1602380D03*
X522069D03*
X518669Y1614292D03*
X522069D03*
X530729Y1602380D03*
X542789D03*
X534129D03*
X530729Y1614292D03*
X542789D03*
X534129D03*
X554849Y1602380D03*
X546189D03*
X558249D03*
X554849Y1614292D03*
X546189D03*
X558249D03*
X566909Y1602380D03*
X570309D03*
X566909Y1614292D03*
X570309D03*
X578969Y1602380D03*
X582369D03*
X578969Y1614292D03*
X582369D03*
X591029Y1602380D03*
X603089D03*
X594429D03*
X591029Y1614292D03*
X603089D03*
X594429D03*
X615149Y1602380D03*
X606489D03*
X618549D03*
X615149Y1614292D03*
X606489D03*
X618549D03*
X627209Y1602380D03*
X630609D03*
X627209Y1614292D03*
X630609D03*
X639269Y1602380D03*
X642669D03*
X639269Y1614292D03*
X642669D03*
X687697Y960966D03*
X704771Y179599D03*
Y182999D03*
Y194810D03*
Y191410D03*
Y206621D03*
Y203221D03*
Y218432D03*
Y215032D03*
X706756Y780257D03*
Y786950D03*
Y803682D03*
Y793643D03*
Y796989D03*
Y817068D03*
Y810375D03*
Y823761D03*
Y830454D03*
Y833800D03*
Y840493D03*
Y847186D03*
Y853879D03*
Y860572D03*
Y877304D03*
Y867265D03*
Y870611D03*
Y883997D03*
Y890690D03*
Y897383D03*
Y904076D03*
Y907423D03*
Y914115D03*
Y920808D03*
Y927501D03*
Y934194D03*
Y940887D03*
Y950926D03*
Y944234D03*
Y964312D03*
Y957619D03*
Y971005D03*
Y977698D03*
Y984391D03*
Y1001123D03*
Y997777D03*
Y991084D03*
Y1031241D03*
Y1037934D03*
Y1044627D03*
Y1058013D03*
Y1051320D03*
Y1074745D03*
Y1081438D03*
Y1088131D03*
Y1098171D03*
Y1104863D03*
Y1091478D03*
Y1111556D03*
Y1118249D03*
Y1134982D03*
Y1124942D03*
Y1128289D03*
Y1148367D03*
Y1141675D03*
Y1155060D03*
Y1161753D03*
Y1165100D03*
Y1171793D03*
Y1178486D03*
Y1185178D03*
Y1191871D03*
Y1208604D03*
Y1198564D03*
Y1201911D03*
Y1215297D03*
Y1221989D03*
Y1228682D03*
Y1235375D03*
Y1238722D03*
Y1245415D03*
Y1252108D03*
X722898Y776911D03*
Y783604D03*
Y790297D03*
Y800336D03*
Y807029D03*
Y793643D03*
Y813722D03*
Y820415D03*
Y837147D03*
Y830454D03*
Y827108D03*
Y843840D03*
Y850533D03*
Y857226D03*
Y863919D03*
Y873958D03*
Y880651D03*
Y867265D03*
Y887344D03*
Y894037D03*
Y910769D03*
Y904076D03*
Y900730D03*
Y924155D03*
Y917462D03*
Y930848D03*
Y940887D03*
Y937541D03*
Y947580D03*
Y954273D03*
Y967659D03*
Y974352D03*
Y981045D03*
Y987737D03*
Y994430D03*
Y1001123D03*
Y1027895D03*
Y1034588D03*
Y1041281D03*
Y1047974D03*
Y1054667D03*
Y1061360D03*
Y1071399D03*
Y1064706D03*
Y1078092D03*
Y1088131D03*
Y1084785D03*
Y1094824D03*
Y1101517D03*
Y1108210D03*
Y1114903D03*
Y1131635D03*
Y1124942D03*
Y1121596D03*
Y1138328D03*
Y1145021D03*
Y1151714D03*
Y1161753D03*
Y1158407D03*
Y1168446D03*
Y1175139D03*
Y1181832D03*
Y1188525D03*
Y1205257D03*
Y1198564D03*
Y1195218D03*
Y1211950D03*
Y1218643D03*
Y1225336D03*
Y1235375D03*
Y1232029D03*
Y1242068D03*
Y1248761D03*
X725925Y-25571D03*
Y-22171D03*
Y-15571D03*
Y-12171D03*
X747099Y960966D03*
X776800D03*
X806500D03*
X842320Y-11711D03*
Y-8311D03*
Y11689D03*
Y8289D03*
X1007587Y805418D03*
Y816352D03*
Y819752D03*
Y808818D03*
Y827354D03*
Y830754D03*
Y838356D03*
Y841756D03*
X1067107Y960965D03*
X1096808D03*
X1134567Y780256D03*
Y786949D03*
Y803681D03*
Y793642D03*
Y796988D03*
Y817067D03*
Y810374D03*
Y823760D03*
Y830453D03*
Y833799D03*
Y840492D03*
Y847185D03*
Y853878D03*
Y860571D03*
Y877303D03*
Y867264D03*
Y870610D03*
Y883996D03*
Y890689D03*
Y897382D03*
Y904075D03*
Y907422D03*
Y914114D03*
Y920807D03*
Y927500D03*
Y934193D03*
Y940886D03*
Y950925D03*
Y944233D03*
Y964311D03*
Y957618D03*
Y971004D03*
X1126508Y960965D03*
X1134567Y977697D03*
Y984390D03*
Y1001122D03*
Y997776D03*
Y991083D03*
Y1031240D03*
Y1037933D03*
Y1044626D03*
Y1058012D03*
Y1051319D03*
Y1074744D03*
Y1081437D03*
Y1088130D03*
Y1098170D03*
Y1104862D03*
Y1091477D03*
Y1111555D03*
Y1118248D03*
Y1134981D03*
Y1124941D03*
Y1128288D03*
Y1148366D03*
Y1141674D03*
Y1155059D03*
Y1161752D03*
Y1165099D03*
Y1171792D03*
Y1178485D03*
Y1185177D03*
Y1191870D03*
Y1208603D03*
Y1198563D03*
Y1201910D03*
Y1215296D03*
Y1221988D03*
Y1228681D03*
Y1235374D03*
Y1238721D03*
Y1245414D03*
Y1252107D03*
X1150709Y776910D03*
Y783603D03*
Y790296D03*
Y800335D03*
Y807028D03*
Y793642D03*
Y813721D03*
Y820414D03*
Y837146D03*
Y830453D03*
Y827107D03*
Y843839D03*
Y850532D03*
Y857225D03*
Y863918D03*
Y873957D03*
Y880650D03*
Y867264D03*
Y887343D03*
Y894036D03*
Y910768D03*
Y904075D03*
Y900729D03*
Y924154D03*
Y917461D03*
Y930847D03*
Y940886D03*
Y937540D03*
Y947579D03*
Y954272D03*
Y967658D03*
Y974351D03*
Y981044D03*
Y987736D03*
Y994429D03*
Y1001122D03*
Y1027894D03*
Y1034587D03*
Y1041280D03*
Y1047973D03*
Y1054666D03*
Y1061359D03*
Y1071398D03*
Y1064705D03*
Y1078091D03*
Y1088130D03*
Y1084784D03*
Y1094823D03*
Y1101516D03*
Y1108209D03*
Y1114902D03*
Y1131634D03*
Y1124941D03*
Y1121595D03*
Y1138327D03*
Y1145020D03*
Y1151713D03*
Y1161752D03*
Y1158406D03*
Y1168445D03*
Y1175138D03*
Y1181831D03*
Y1188524D03*
Y1205256D03*
Y1198563D03*
Y1195217D03*
Y1211949D03*
Y1218642D03*
Y1225335D03*
Y1235374D03*
Y1232028D03*
Y1242067D03*
Y1248760D03*
X1177404Y-11711D03*
Y-8311D03*
Y11689D03*
Y8289D03*
X1185910Y960965D03*
X1202069Y1635380D03*
X1214129D03*
X1205469D03*
X1202069Y1647292D03*
X1214129D03*
X1205469D03*
X1226189Y1635380D03*
X1217529D03*
X1229589D03*
X1226189Y1647292D03*
X1217529D03*
X1229589D03*
X1238249Y1635380D03*
X1241649D03*
X1238249Y1647292D03*
X1241649D03*
X1245840Y-28311D03*
Y-31711D03*
Y-18311D03*
Y-21711D03*
Y11689D03*
Y8289D03*
X1250309Y1635380D03*
X1253709D03*
X1250309Y1647292D03*
X1253709D03*
X1262369Y1635380D03*
X1274429D03*
X1265769D03*
X1262369Y1647292D03*
X1274429D03*
X1265769D03*
X1286489Y1635380D03*
X1277829D03*
X1289889D03*
X1286489Y1647292D03*
X1277829D03*
X1289889D03*
X1298549Y1635380D03*
X1301949D03*
X1298549Y1647292D03*
X1301949D03*
X1310609Y1635380D03*
X1314009D03*
X1310609Y1647292D03*
X1314009D03*
X1322669Y1635380D03*
X1334729D03*
X1326069D03*
X1322669Y1647292D03*
X1334729D03*
X1326069D03*
X1346789Y1635380D03*
X1338129D03*
X1346789Y1647292D03*
X1338129D03*
X1358849Y1635380D03*
X1350189D03*
X1362249D03*
X1358849Y1647292D03*
X1350189D03*
X1362249D03*
X1370909Y1635380D03*
X1374309D03*
X1370909Y1647292D03*
X1374309D03*
X1382969Y1635380D03*
X1386369D03*
X1382969Y1647292D03*
X1386369D03*
X1436263Y-28311D03*
Y-31711D03*
Y-18311D03*
Y-21711D03*
Y11689D03*
Y8289D03*
X1466243Y1635380D03*
Y1647292D03*
X1478303Y1635380D03*
X1469643D03*
X1481703D03*
X1478303Y1647292D03*
X1469643D03*
X1481703D03*
X1490363Y1635380D03*
X1493763D03*
X1490363Y1647292D03*
X1493763D03*
X1502423Y1635380D03*
X1505823D03*
X1502423Y1647292D03*
X1505823D03*
X1514483Y1635380D03*
X1526543D03*
X1517883D03*
X1514483Y1647292D03*
X1526543D03*
X1517883D03*
X1539134Y-35912D03*
Y-32512D03*
X1538603Y1635380D03*
X1529943D03*
X1542003D03*
X1538603Y1647292D03*
X1529943D03*
X1542003D03*
X1550663Y1635380D03*
X1554063D03*
X1550663Y1647292D03*
X1554063D03*
X1562723Y1635380D03*
X1566123D03*
X1562723Y1647292D03*
X1566123D03*
X1586843Y1635380D03*
X1574783D03*
X1578183D03*
X1586843Y1647292D03*
X1574783D03*
X1578183D03*
X1598903Y1635380D03*
X1590243D03*
X1602303D03*
X1598903Y1647292D03*
X1590243D03*
X1602303D03*
X1610963Y1635380D03*
X1614363D03*
X1610963Y1647292D03*
X1614363D03*
X1623023Y1635380D03*
X1626423D03*
X1623023Y1647292D03*
X1626423D03*
X1635083Y1635380D03*
X1647143D03*
X1638483D03*
X1635083Y1647292D03*
X1647143D03*
X1638483D03*
X1650543Y1635380D03*
Y1647292D03*
X1663839Y960965D03*
X1682898Y780256D03*
Y786949D03*
Y803681D03*
Y793642D03*
Y796988D03*
Y817067D03*
Y810374D03*
Y823760D03*
Y830453D03*
Y833799D03*
Y840492D03*
Y847185D03*
Y853878D03*
Y860571D03*
Y877303D03*
Y867264D03*
Y870610D03*
Y883996D03*
Y890689D03*
Y897382D03*
Y904075D03*
Y907422D03*
Y914114D03*
Y920807D03*
Y927500D03*
Y934193D03*
Y940886D03*
Y950925D03*
Y944233D03*
Y964311D03*
Y957618D03*
Y971004D03*
Y977697D03*
Y984390D03*
Y1001122D03*
Y997776D03*
Y991083D03*
Y1031240D03*
Y1037933D03*
Y1044626D03*
Y1058012D03*
Y1051319D03*
Y1074744D03*
Y1081437D03*
Y1088130D03*
Y1098170D03*
Y1104862D03*
Y1091477D03*
Y1111555D03*
Y1118248D03*
Y1134981D03*
Y1124941D03*
Y1128288D03*
Y1148366D03*
Y1141674D03*
Y1155059D03*
Y1161752D03*
Y1165099D03*
Y1171792D03*
Y1178485D03*
Y1185177D03*
Y1191870D03*
Y1208603D03*
Y1198563D03*
Y1201910D03*
Y1215296D03*
Y1221988D03*
Y1228681D03*
Y1235374D03*
Y1238721D03*
Y1245414D03*
Y1252107D03*
X1699040Y776910D03*
Y783603D03*
Y790296D03*
Y800335D03*
Y807028D03*
Y793642D03*
Y813721D03*
Y820414D03*
Y837146D03*
Y830453D03*
Y827107D03*
Y843839D03*
Y850532D03*
Y857225D03*
Y863918D03*
Y873957D03*
Y880650D03*
Y867264D03*
Y887343D03*
Y894036D03*
Y910768D03*
Y904075D03*
Y900729D03*
Y924154D03*
Y917461D03*
Y930847D03*
Y940886D03*
Y937540D03*
Y947579D03*
Y954272D03*
Y967658D03*
Y974351D03*
Y981044D03*
Y987736D03*
Y994429D03*
Y1001122D03*
Y1027894D03*
Y1034587D03*
Y1041280D03*
Y1047973D03*
Y1054666D03*
Y1061359D03*
Y1071398D03*
Y1064705D03*
Y1078091D03*
Y1088130D03*
Y1084784D03*
Y1094823D03*
Y1101516D03*
Y1108209D03*
Y1114902D03*
Y1131634D03*
Y1124941D03*
Y1121595D03*
Y1138327D03*
Y1145020D03*
Y1151713D03*
Y1161752D03*
Y1158406D03*
Y1168445D03*
Y1175138D03*
Y1181831D03*
Y1188524D03*
Y1205256D03*
Y1198563D03*
Y1195217D03*
Y1211949D03*
Y1218642D03*
Y1225335D03*
Y1235374D03*
Y1232028D03*
Y1242067D03*
Y1248760D03*
X1729557Y-35912D03*
Y-32512D03*
X1723241Y960965D03*
X1752942D03*
X1782642D03*
G54D22*
X60303Y20354D03*
X312921Y24291D03*
X505185Y41141D03*
X757803Y45078D03*
X929331Y160413D03*
X922441Y237697D03*
X1534712Y20354D03*
X1787330Y24291D03*
G54D31*
X205478Y1536063D03*
X210202D03*
X219651D03*
X229100D03*
X233824D03*
X243273D03*
X253002Y1514243D03*
X252722Y1536063D03*
X302413Y906182D03*
Y912560D03*
Y918938D03*
Y925316D03*
Y931694D03*
Y938072D03*
Y944450D03*
Y950828D03*
Y957206D03*
Y963584D03*
Y969962D03*
Y976340D03*
Y982718D03*
Y989096D03*
Y995474D03*
Y1008230D03*
Y1001852D03*
X303594Y1030198D03*
Y1036576D03*
Y1042954D03*
Y1055710D03*
Y1049332D03*
Y1062088D03*
Y1074844D03*
Y1068466D03*
Y1081222D03*
Y1087600D03*
Y1093978D03*
Y1100356D03*
Y1106734D03*
Y1113112D03*
Y1119490D03*
Y1125868D03*
Y1132246D03*
Y1138623D03*
Y1145001D03*
Y1157757D03*
Y1151379D03*
X333540Y1536063D03*
X338264D03*
X347713D03*
X357162D03*
X361886D03*
X380784D03*
X371335D03*
X381064Y1514243D03*
X408614Y997608D03*
X410464Y1007175D03*
X404923Y1010366D03*
X423417Y997608D03*
X416015D03*
X430819D03*
X445622D03*
X453023D03*
X467826D03*
X460425D03*
X469651Y1536063D03*
X483824D03*
X474375D03*
X497997D03*
X493273D03*
X507446D03*
X526370Y1165290D03*
X515268D03*
X518969D03*
X522670D03*
X517175Y1514243D03*
X516895Y1536063D03*
X533772Y1165290D03*
X530071D03*
X602437Y1536063D03*
X597713D03*
X611886D03*
X626059D03*
X621335D03*
X645237Y1514243D03*
X644957Y1536063D03*
X635508D03*
X1213351Y1569063D03*
X1227524D03*
X1218075D03*
X1241697D03*
X1236973D03*
X1251146D03*
X1260875Y1547243D03*
X1260595Y1569063D03*
X1278555Y906181D03*
Y912559D03*
Y918937D03*
Y925315D03*
Y931693D03*
Y938071D03*
Y950827D03*
Y944449D03*
Y957205D03*
Y963583D03*
Y969961D03*
Y976339D03*
Y982717D03*
Y995473D03*
Y989095D03*
Y1008229D03*
Y1001851D03*
X1279736Y1030197D03*
Y1042953D03*
Y1036575D03*
Y1055709D03*
Y1049331D03*
Y1062087D03*
Y1068465D03*
Y1074843D03*
Y1081221D03*
Y1087599D03*
Y1093977D03*
Y1100355D03*
Y1106733D03*
Y1113111D03*
Y1119489D03*
Y1125867D03*
Y1132245D03*
Y1138622D03*
Y1145000D03*
Y1151378D03*
Y1157756D03*
X1346137Y1569063D03*
X1341413D03*
X1355586D03*
X1379208D03*
X1369759D03*
X1365035D03*
X1384756Y997607D03*
X1392157D03*
X1386606Y1007174D03*
X1381065Y1010365D03*
X1388937Y1547243D03*
X1388657Y1569063D03*
X1406961Y997607D03*
X1399559D03*
X1421764D03*
X1436567D03*
X1429165D03*
X1443968D03*
X1482249Y1569063D03*
X1477525D03*
X1491698D03*
X1502512Y1165289D03*
X1505871Y1569063D03*
X1501147D03*
X1525049Y1547243D03*
X1524769Y1569063D03*
X1515320D03*
X1610311D03*
X1605587D03*
X1629209D03*
X1619760D03*
X1643382D03*
X1633933D03*
X1653111Y1547243D03*
X1652831Y1569063D03*
G54D43*
X381770Y-30570D03*
X385023Y-30584D03*
X388048Y-29264D03*
X381755Y-28055D03*
X385008Y-28069D03*
X381740Y-25540D03*
X381725Y-23025D03*
X723479Y-19234D03*
Y-9234D03*
X833421Y-36647D03*
X839699Y-35341D03*
X833406Y-34132D03*
X836674Y-36661D03*
X836659Y-34146D03*
X833391Y-31617D03*
X833376Y-29102D03*
X836644Y-31631D03*
X836629Y-29116D03*
X1174958Y-15374D03*
Y-5374D03*
Y24626D03*
X1433817Y-25374D03*
Y-15374D03*
Y14626D03*
X1530063Y-40911D03*
X1530033Y-35881D03*
X1530018Y-33366D03*
X1530048Y-38396D03*
X1533316Y-40925D03*
X1536341Y-39605D03*
X1533301Y-38410D03*
X1727111Y-19575D03*
G54D81*
X1898799Y1198198D03*
X1908799D03*
X1921395Y-39963D03*
X1931395D03*
X1942395Y572417D03*
X1940886Y1198170D03*
X1963362Y-39821D03*
X1952395Y572417D03*
X1950886Y1198170D03*
X1973362Y-39821D03*
X1984482Y572389D03*
X1982856Y1198350D03*
X1992856D03*
X2005452Y-39811D03*
X1994482Y572389D03*
X2015452Y-39811D03*
X2026452Y572569D03*
X2036452D03*
X2047419Y-39669D03*
X2057419D03*
X2068539Y572541D03*
X2078539D03*
G54D47*
X539016Y274272D03*
X559016D03*
X569016D03*
X579016D03*
X589016D03*
X599016D03*
X609016D03*
G54D61*
X918780Y1684890D03*
Y1694890D03*
Y1714890D03*
X928780Y1684890D03*
Y1694890D03*
Y1704890D03*
Y1714890D03*
X938780Y1684890D03*
Y1694890D03*
Y1704890D03*
Y1714890D03*
G54D66*
X1225530Y67471D03*
X1454797Y80345D03*
G54D79*
X1900275Y-29973D03*
Y562227D03*
X1898799Y1208198D03*
Y1800398D03*
X1910275Y-29973D03*
Y562227D03*
X1908799Y1208198D03*
Y1800398D03*
X1921395Y-29963D03*
X1931395D03*
Y562237D03*
X1921395D03*
X1931395Y582237D03*
X1921395D03*
Y1174437D03*
X1931395D03*
X1929766Y1208160D03*
X1919766D03*
Y1800360D03*
X1929766D03*
X1942395Y-29783D03*
Y562417D03*
Y582417D03*
Y1174617D03*
X1940886Y1208170D03*
Y1800370D03*
X1952395Y-29783D03*
Y562417D03*
Y582417D03*
Y1174617D03*
X1950886Y1208170D03*
X1961856D03*
X1950886Y1800370D03*
X1961856D03*
X1963362Y-29821D03*
X1973362D03*
Y562379D03*
X1963362D03*
X1973362Y582379D03*
X1963362D03*
Y1174579D03*
X1973362D03*
X1971856Y1208170D03*
Y1800370D03*
X1984482Y-29811D03*
Y562389D03*
Y582389D03*
Y1174589D03*
X1982856Y1208350D03*
Y1800550D03*
X1994482Y-29811D03*
X2005452D03*
X1994482Y562389D03*
X2005452D03*
Y582389D03*
X1994482D03*
Y1174589D03*
X2005452D03*
X1992856Y1208350D03*
X2003823Y1208312D03*
X1992856Y1800550D03*
X2003823Y1800512D03*
X2015452Y-29811D03*
Y562389D03*
Y582389D03*
Y1174589D03*
X2013823Y1208312D03*
Y1800512D03*
X2036452Y-29631D03*
X2026452D03*
Y562569D03*
X2036452D03*
X2026452Y582569D03*
X2036452D03*
Y1174769D03*
X2026452D03*
X2047419Y-29669D03*
Y562531D03*
Y582531D03*
Y1174731D03*
X2057419Y-29669D03*
Y562531D03*
Y582531D03*
Y1174731D03*
X2068539Y582541D03*
X2078539D03*
Y1174741D03*
X2068539D03*
G54D80*
X1900275Y572227D03*
X1910275D03*
X1921395Y1184437D03*
X1931395D03*
X1919766Y1810360D03*
X1929766D03*
X1942395Y572417D03*
X1952395D03*
X1963362Y1184579D03*
X1961856Y1810370D03*
X1973362Y1184579D03*
X1971856Y1810370D03*
X1984482Y572389D03*
X1994482D03*
X2005452Y1184589D03*
X2003823Y1810512D03*
X2015452Y1184589D03*
X2013823Y1810512D03*
X2026452Y572569D03*
X2036452D03*
X2047419Y1184731D03*
X2057419D03*
G54D50*
X676509Y224606D03*
G54D42*
X369768Y886002D03*
X375319Y889191D03*
X371618D03*
X377169Y892380D03*
X371618Y895569D03*
X375319D03*
X369768Y892380D03*
X371618Y908325D03*
X377169Y911513D03*
X369768Y898758D03*
X375319Y901947D03*
X371618D03*
X377169Y905135D03*
X369768D03*
X375319Y908325D03*
X369768Y911513D03*
X377169Y898758D03*
X369768Y917891D03*
X375319Y921080D03*
X371618D03*
X377169Y924269D03*
X369768D03*
X371618Y914702D03*
X375319D03*
X377169Y917891D03*
X375319Y927458D03*
X371618D03*
X377169Y930647D03*
X369768Y937025D03*
X375319Y940214D03*
X371618D03*
Y933836D03*
X375319D03*
X369768Y930647D03*
X377169Y937025D03*
Y943403D03*
X369768D03*
X375319Y946592D03*
X371618D03*
X377169Y949781D03*
X369768Y956159D03*
X371618Y952970D03*
X375319D03*
X369768Y949781D03*
X377169Y956159D03*
X369768Y962537D03*
X375319Y965726D03*
X371618D03*
X377169Y968915D03*
X375319Y959348D03*
X371618D03*
X377169Y962537D03*
X369768Y968915D03*
X375319Y984860D03*
X369768Y975293D03*
X375319Y978482D03*
X371618D03*
X377169Y981671D03*
X371618Y972104D03*
X375319D03*
X377169Y975293D03*
Y988049D03*
X369768Y994427D03*
X371618Y997616D03*
X375319D03*
X377169Y1000805D03*
X369768D03*
X371618Y991238D03*
X377169Y994427D03*
X371618Y1010372D03*
X369768Y1007183D03*
X371618Y1003994D03*
X375319D03*
X377169Y1007183D03*
X378351Y1031245D03*
X376500Y1034434D03*
X372799D03*
X370949Y1037623D03*
X378351D03*
X376500Y1040812D03*
X372799D03*
X370949Y1044001D03*
X378351Y1050379D03*
X372799Y1059946D03*
X376500Y1047190D03*
X370949Y1050379D03*
X372799Y1053568D03*
Y1072702D03*
X378351Y1063135D03*
X370949D03*
X376500Y1066324D03*
X378351Y1069513D03*
X370949D03*
X376500Y1072702D03*
X372799Y1066324D03*
X378351Y1075891D03*
X370949D03*
X376500Y1079080D03*
X372799D03*
X378351Y1082269D03*
X370949D03*
X376500Y1085458D03*
X370949Y1088647D03*
X378351D03*
X372799Y1085458D03*
X370949Y1101403D03*
X376500Y1104592D03*
X372799Y1091836D03*
X378351Y1095025D03*
X370949D03*
X376500Y1098214D03*
X372799D03*
X378351Y1101403D03*
X372799Y1104592D03*
X376500Y1091836D03*
X372799Y1110970D03*
X378351Y1114159D03*
X370949D03*
X376500Y1117348D03*
X372799D03*
X370949Y1107781D03*
X378351D03*
X376500Y1110970D03*
X378351Y1120537D03*
X370949D03*
X376500Y1123726D03*
X372799Y1130103D03*
X378351Y1133293D03*
X370949D03*
Y1126915D03*
X378351D03*
X372799Y1123726D03*
X376500Y1130103D03*
Y1136481D03*
X372799D03*
X378351Y1139670D03*
X370949D03*
X376500Y1142859D03*
X372799Y1149237D03*
X370949Y1146048D03*
X378351D03*
X372799Y1142859D03*
X376500Y1149237D03*
X378351Y1152426D03*
X370949D03*
X376500Y1155615D03*
X388272Y892380D03*
X384571D03*
X395673D03*
X388272Y911513D03*
Y898758D03*
Y905135D03*
X384571Y911513D03*
Y898758D03*
Y905135D03*
X395673Y898758D03*
Y905135D03*
X385752Y1158804D03*
X382051D03*
X393154D03*
X389453Y1152426D03*
X385752D03*
X399374Y892380D03*
X410477D03*
X406776D03*
X399374Y898758D03*
Y905135D03*
X410477Y898758D03*
Y905135D03*
X406776Y898758D03*
Y905135D03*
X396855Y1158804D03*
X407957D03*
X404256D03*
X400555Y1152426D03*
X396855D03*
X407957D03*
X421579Y892380D03*
X417878D03*
X421579Y898758D03*
Y905135D03*
X417878Y898758D03*
Y905135D03*
X419059Y1158804D03*
X415358D03*
X411658Y1152426D03*
X422760D03*
X419059D03*
X430831Y895569D03*
X427130D03*
X430831Y901947D03*
Y908325D03*
X427130Y901947D03*
Y908325D03*
X510373Y886002D03*
X504822Y889191D03*
X508523D03*
X502971Y892380D03*
X508523Y895569D03*
X504822D03*
X510373Y892380D03*
X508523Y908325D03*
X502971Y911513D03*
X510373Y898758D03*
X504822Y901947D03*
X508523D03*
X502971Y905135D03*
X510373D03*
X504822Y908325D03*
X510373Y911513D03*
X502971Y898758D03*
X510373Y917891D03*
X504822Y921080D03*
X508523D03*
X502971Y924269D03*
X510373D03*
X508523Y914702D03*
X504822D03*
X502971Y917891D03*
X504822Y927458D03*
X508523D03*
X502971Y930647D03*
X510373Y937025D03*
X504822Y940214D03*
X508523D03*
Y933836D03*
X504822D03*
X510373Y930647D03*
X502971Y937025D03*
Y943403D03*
X510373D03*
X504822Y946592D03*
X508523D03*
X502971Y949781D03*
X510373Y956159D03*
X508523Y952970D03*
X504822D03*
X510373Y949781D03*
X502971Y956159D03*
X510373Y962537D03*
X504822Y965726D03*
X508523D03*
X502971Y968915D03*
X504822Y959348D03*
X508523D03*
X502971Y962537D03*
X510373Y968915D03*
X504822Y984860D03*
X510373Y975293D03*
X504822Y978482D03*
X508523D03*
X502971Y981671D03*
X508523Y972104D03*
X504822D03*
X502971Y975293D03*
Y988049D03*
X510373Y994427D03*
X508523Y997616D03*
X504822D03*
X502971Y1000805D03*
X510373D03*
Y988049D03*
X504822Y991238D03*
X508523Y1010372D03*
X510373Y1007183D03*
X508523Y1003994D03*
X504822D03*
X502971Y1007183D03*
X504153Y1031245D03*
X506003Y1034434D03*
X509704D03*
X511554Y1037623D03*
X504153D03*
X506003Y1040812D03*
X509704D03*
X504153Y1044001D03*
Y1050379D03*
X509704Y1059946D03*
X506003Y1047190D03*
X511554Y1050379D03*
X509704Y1053568D03*
Y1072702D03*
X504153Y1063135D03*
X511554D03*
X506003Y1066324D03*
X504153Y1069513D03*
X511554D03*
X506003Y1072702D03*
X509704Y1066324D03*
X504153Y1075891D03*
X511554D03*
X506003Y1079080D03*
X509704D03*
X504153Y1082269D03*
X511554D03*
X506003Y1085458D03*
X511554Y1088647D03*
X504153D03*
X509704Y1085458D03*
X511554Y1101403D03*
X506003Y1104592D03*
X509704Y1091836D03*
X504153Y1095025D03*
X511554D03*
X506003Y1098214D03*
X509704D03*
X504153Y1101403D03*
X509704Y1104592D03*
X506003Y1091836D03*
X509704Y1110970D03*
X504153Y1114159D03*
X511554D03*
X506003Y1117348D03*
X509704D03*
X511554Y1107781D03*
X504153D03*
X506003Y1110970D03*
X504153Y1120537D03*
X511554D03*
X506003Y1123726D03*
X509704Y1130103D03*
X504153Y1133293D03*
X511554D03*
Y1126915D03*
X504153D03*
X509704Y1123726D03*
X506003Y1130103D03*
Y1136481D03*
X509704D03*
X504153Y1139670D03*
X511554D03*
X506003Y1142859D03*
X509704Y1149237D03*
X511554Y1146048D03*
X504153D03*
X509704Y1142859D03*
X506003Y1149237D03*
X504153Y1152426D03*
X511554D03*
X506003Y1155615D03*
X1345910Y886001D03*
X1347760Y889190D03*
Y895568D03*
X1345910Y892379D03*
X1347760Y908324D03*
X1345910Y898757D03*
X1347760Y901946D03*
X1345910Y905134D03*
Y911512D03*
Y917890D03*
X1347760Y921079D03*
X1345910Y924268D03*
X1347760Y914701D03*
Y927457D03*
X1345910Y937024D03*
X1347760Y940213D03*
Y933835D03*
X1345910Y930646D03*
Y943402D03*
X1347760Y946591D03*
X1345910Y956158D03*
X1347760Y952969D03*
X1345910Y949780D03*
Y962536D03*
X1347760Y965725D03*
Y959347D03*
X1345910Y968914D03*
Y975292D03*
X1347760Y978481D03*
Y972103D03*
X1345910Y994426D03*
X1347760Y997615D03*
X1345910Y1000804D03*
X1347760Y991237D03*
Y1010371D03*
X1345910Y1007182D03*
X1347760Y1003993D03*
X1348941Y1034433D03*
X1347091Y1037622D03*
X1348941Y1040811D03*
X1347091Y1044000D03*
X1348941Y1059945D03*
X1347091Y1050378D03*
X1348941Y1053567D03*
Y1072701D03*
X1347091Y1063134D03*
Y1069512D03*
X1348941Y1066323D03*
X1347091Y1075890D03*
X1348941Y1079079D03*
X1347091Y1082268D03*
Y1088646D03*
X1348941Y1085457D03*
X1347091Y1101402D03*
X1348941Y1091835D03*
X1347091Y1095024D03*
X1348941Y1098213D03*
Y1104591D03*
Y1110969D03*
X1347091Y1114158D03*
X1348941Y1117347D03*
X1347091Y1107780D03*
Y1120536D03*
X1348941Y1130102D03*
X1347091Y1133292D03*
Y1126914D03*
X1348941Y1123725D03*
Y1136480D03*
X1347091Y1139669D03*
X1348941Y1149236D03*
X1347091Y1146047D03*
X1348941Y1142858D03*
X1347091Y1152425D03*
X1351461Y889190D03*
X1353311Y892379D03*
X1351461Y895568D03*
X1353311Y911512D03*
X1351461Y901946D03*
X1353311Y905134D03*
X1351461Y908324D03*
X1353311Y898757D03*
X1351461Y921079D03*
X1353311Y924268D03*
X1351461Y914701D03*
X1353311Y917890D03*
X1351461Y927457D03*
X1353311Y930646D03*
X1351461Y940213D03*
Y933835D03*
X1353311Y937024D03*
Y943402D03*
X1351461Y946591D03*
X1353311Y949780D03*
X1351461Y952969D03*
X1353311Y956158D03*
X1351461Y965725D03*
X1353311Y968914D03*
X1351461Y959347D03*
X1353311Y962536D03*
X1351461Y984859D03*
Y978481D03*
X1353311Y981670D03*
X1351461Y972103D03*
X1353311Y975292D03*
Y988048D03*
X1351461Y997615D03*
X1353311Y1000804D03*
Y994426D03*
X1351461Y1003993D03*
X1353311Y1007182D03*
X1354493Y1031244D03*
X1352642Y1034433D03*
X1354493Y1037622D03*
X1352642Y1040811D03*
X1354493Y1050378D03*
X1352642Y1047189D03*
X1354493Y1063134D03*
X1352642Y1066323D03*
X1354493Y1069512D03*
X1352642Y1072701D03*
X1354493Y1075890D03*
X1352642Y1079079D03*
X1354493Y1082268D03*
X1352642Y1085457D03*
X1354493Y1088646D03*
X1352642Y1104591D03*
X1354493Y1095024D03*
X1352642Y1098213D03*
X1354493Y1101402D03*
X1352642Y1091835D03*
X1354493Y1114158D03*
X1352642Y1117347D03*
X1354493Y1107780D03*
X1352642Y1110969D03*
X1354493Y1120536D03*
X1352642Y1123725D03*
X1354493Y1133292D03*
Y1126914D03*
X1352642Y1130102D03*
Y1136480D03*
X1354493Y1139669D03*
X1352642Y1142858D03*
X1354493Y1146047D03*
X1352642Y1149236D03*
X1354493Y1152425D03*
X1352642Y1155614D03*
X1361894Y1158803D03*
X1358193D03*
X1361894Y1152425D03*
X1372997Y1158803D03*
X1369296D03*
X1365595Y1152425D03*
X1376697D03*
X1372997D03*
X1384099Y1158803D03*
X1380398D03*
X1391500D03*
X1387800Y1152425D03*
X1384099D03*
X1395201Y1158803D03*
X1398902Y1152425D03*
X1395201D03*
X1434704Y892379D03*
X1425452Y895568D03*
X1438405Y892379D03*
X1429153Y895568D03*
X1434704Y898757D03*
Y905134D03*
X1425452Y901946D03*
Y908324D03*
X1438405Y898757D03*
Y905134D03*
X1429153Y901946D03*
Y908324D03*
X1445806Y892379D03*
X1449507D03*
X1445806Y898757D03*
Y905134D03*
X1449507Y898757D03*
Y905134D03*
X1468011Y892379D03*
X1456909D03*
X1460609D03*
X1468011Y911512D03*
Y898757D03*
Y905134D03*
X1456909Y898757D03*
Y905134D03*
X1460609Y898757D03*
Y905134D03*
X1471712Y892379D03*
X1480964Y889190D03*
X1479113Y892379D03*
X1480964Y895568D03*
X1471712Y911512D03*
Y898757D03*
Y905134D03*
X1479113Y911512D03*
X1480964Y901946D03*
X1479113Y905134D03*
X1480964Y908324D03*
X1479113Y898757D03*
X1480964Y921079D03*
X1479113Y924268D03*
X1480964Y914701D03*
X1479113Y917890D03*
X1480964Y927457D03*
X1479113Y930646D03*
X1480964Y940213D03*
Y933835D03*
X1479113Y937024D03*
Y943402D03*
X1480964Y946591D03*
X1479113Y949780D03*
X1480964Y952969D03*
X1479113Y956158D03*
X1480964Y965725D03*
X1479113Y968914D03*
X1480964Y959347D03*
X1479113Y962536D03*
X1480964Y984859D03*
Y978481D03*
X1479113Y981670D03*
X1480964Y972103D03*
X1479113Y975292D03*
Y988048D03*
X1480964Y997615D03*
X1479113Y1000804D03*
X1480964Y991237D03*
Y1003993D03*
X1479113Y1007182D03*
X1480295Y1031244D03*
X1482145Y1034433D03*
X1480295Y1037622D03*
X1482145Y1040811D03*
X1480295Y1044000D03*
Y1050378D03*
X1482145Y1047189D03*
X1480295Y1063134D03*
X1482145Y1066323D03*
X1480295Y1069512D03*
X1482145Y1072701D03*
X1480295Y1075890D03*
X1482145Y1079079D03*
X1480295Y1082268D03*
X1482145Y1085457D03*
X1480295Y1088646D03*
X1482145Y1104591D03*
X1480295Y1095024D03*
X1482145Y1098213D03*
X1480295Y1101402D03*
X1482145Y1091835D03*
X1480295Y1114158D03*
X1482145Y1117347D03*
X1480295Y1107780D03*
X1482145Y1110969D03*
X1480295Y1120536D03*
X1482145Y1123725D03*
X1480295Y1133292D03*
Y1126914D03*
X1482145Y1130102D03*
Y1136480D03*
X1480295Y1139669D03*
X1482145Y1142858D03*
X1480295Y1146047D03*
X1482145Y1149236D03*
X1480295Y1152425D03*
X1482145Y1155614D03*
X1486515Y886001D03*
X1484665Y889190D03*
Y895568D03*
X1486515Y892379D03*
X1484665Y908324D03*
X1486515Y898757D03*
X1484665Y901946D03*
X1486515Y905134D03*
Y911512D03*
Y917890D03*
X1484665Y921079D03*
X1486515Y924268D03*
X1484665Y914701D03*
Y927457D03*
X1486515Y937024D03*
X1484665Y940213D03*
Y933835D03*
X1486515Y930646D03*
Y943402D03*
X1484665Y946591D03*
X1486515Y956158D03*
X1484665Y952969D03*
X1486515Y949780D03*
Y962536D03*
X1484665Y965725D03*
Y959347D03*
X1486515Y968914D03*
Y975292D03*
X1484665Y978481D03*
Y972103D03*
X1486515Y994426D03*
X1484665Y997615D03*
X1486515Y1000804D03*
Y988048D03*
X1484665Y1010371D03*
X1486515Y1007182D03*
X1484665Y1003993D03*
X1485846Y1034433D03*
X1487696Y1037622D03*
X1485846Y1040811D03*
Y1059945D03*
X1487696Y1050378D03*
X1485846Y1053567D03*
Y1072701D03*
X1487696Y1063134D03*
Y1069512D03*
X1485846Y1066323D03*
X1487696Y1075890D03*
X1485846Y1079079D03*
X1487696Y1082268D03*
Y1088646D03*
X1485846Y1085457D03*
X1487696Y1101402D03*
X1485846Y1091835D03*
X1487696Y1095024D03*
X1485846Y1098213D03*
Y1104591D03*
Y1110969D03*
X1487696Y1114158D03*
X1485846Y1117347D03*
X1487696Y1107780D03*
Y1120536D03*
X1485846Y1130102D03*
X1487696Y1133292D03*
Y1126914D03*
X1485846Y1123725D03*
Y1136480D03*
X1487696Y1139669D03*
X1485846Y1149236D03*
X1487696Y1146047D03*
X1485846Y1142858D03*
X1487696Y1152425D03*
G54D49*
X676509Y145866D03*
G54D33*
X230905Y1649173D03*
Y1653897D03*
Y1663346D03*
Y1668070D03*
Y1677519D03*
Y1682244D03*
Y1691692D03*
Y1696417D03*
Y1705866D03*
Y1710590D03*
Y1720039D03*
Y1724763D03*
Y1734212D03*
X238779Y1643661D03*
X246653Y1649173D03*
Y1653897D03*
X238779Y1653110D03*
Y1657834D03*
X246653Y1663346D03*
Y1668070D03*
X238779Y1667283D03*
Y1672007D03*
X246653Y1677519D03*
Y1682244D03*
X238779Y1681456D03*
Y1686180D03*
X246653Y1691692D03*
Y1696417D03*
X238779Y1695629D03*
Y1700354D03*
X246653Y1705866D03*
Y1710590D03*
X238779Y1709803D03*
Y1714527D03*
X246653Y1720039D03*
Y1724763D03*
X238779Y1723976D03*
Y1728700D03*
X246653Y1734212D03*
X254527Y1643661D03*
Y1653110D03*
Y1657834D03*
Y1667283D03*
Y1672007D03*
Y1681456D03*
Y1686180D03*
Y1695629D03*
Y1700354D03*
Y1709803D03*
Y1714527D03*
Y1723976D03*
Y1728700D03*
X270275Y1643661D03*
X262401Y1649173D03*
X270275Y1653110D03*
X262401Y1653897D03*
X270275Y1657834D03*
X262401Y1663346D03*
X270275Y1667283D03*
X262401Y1668070D03*
X270275Y1672007D03*
X262401Y1677519D03*
X270275Y1681456D03*
X262401Y1682244D03*
X270275Y1686180D03*
X262401Y1691692D03*
X270275Y1695629D03*
X262401Y1696417D03*
X270275Y1700354D03*
X262401Y1705866D03*
X270275Y1709803D03*
X262401Y1710590D03*
X270275Y1714527D03*
X262401Y1720039D03*
X270275Y1723976D03*
X262401Y1724763D03*
X270275Y1728700D03*
X262401Y1734212D03*
X286023Y1643661D03*
X278149Y1649173D03*
X286023Y1653110D03*
X278149Y1653897D03*
X286023Y1657834D03*
X278149Y1663346D03*
X286023Y1667283D03*
X278149Y1668070D03*
X286023Y1672007D03*
X278149Y1677519D03*
X286023Y1681456D03*
X278149Y1682244D03*
X286023Y1686180D03*
X278149Y1691692D03*
X286023Y1695629D03*
X278149Y1696417D03*
X286023Y1700354D03*
X278149Y1705866D03*
X286023Y1709803D03*
X278149Y1710590D03*
X286023Y1714527D03*
X278149Y1720039D03*
X286023Y1723976D03*
X278149Y1724763D03*
X286023Y1728700D03*
X278149Y1734212D03*
X305709Y1672007D03*
X297835Y1677519D03*
X305709Y1681456D03*
X297835Y1682244D03*
X305709Y1686180D03*
X297835Y1691692D03*
X305709Y1695629D03*
X297835Y1696417D03*
X305709Y1700354D03*
X297835Y1705866D03*
X305709Y1709803D03*
X297835Y1710590D03*
X305709Y1714527D03*
X297835Y1720039D03*
X305709Y1723976D03*
X297835Y1724763D03*
X305709Y1728700D03*
X297835Y1734212D03*
X321457Y1672007D03*
X313583Y1677519D03*
X321457Y1681456D03*
X313583Y1682244D03*
X321457Y1686180D03*
X313583Y1691692D03*
X321457Y1695629D03*
X313583Y1696417D03*
X321457Y1700354D03*
X313583Y1705866D03*
X321457Y1709803D03*
X313583Y1710590D03*
X321457Y1714527D03*
X313583Y1720039D03*
X321457Y1723976D03*
X313583Y1724763D03*
X321457Y1728700D03*
X313583Y1734212D03*
X329331Y1677519D03*
Y1682244D03*
Y1691692D03*
Y1696417D03*
Y1705866D03*
Y1710590D03*
Y1720039D03*
Y1724763D03*
Y1734212D03*
X337205Y1672007D03*
X345079Y1677519D03*
Y1682244D03*
X337205Y1681456D03*
Y1686180D03*
X345079Y1691692D03*
Y1696417D03*
X337205Y1695629D03*
Y1700354D03*
X345079Y1705866D03*
Y1710590D03*
X337205Y1709803D03*
Y1714527D03*
X345079Y1720039D03*
Y1724763D03*
X337205Y1723976D03*
Y1728700D03*
X345079Y1734212D03*
X352953Y1672007D03*
Y1681456D03*
Y1686180D03*
Y1695629D03*
Y1700354D03*
Y1709803D03*
Y1714527D03*
Y1723976D03*
Y1728700D03*
X495078Y1677519D03*
Y1682244D03*
Y1691692D03*
Y1696417D03*
Y1705866D03*
Y1710590D03*
Y1720039D03*
Y1724763D03*
Y1734212D03*
X502952Y1672007D03*
X510826Y1677519D03*
Y1682244D03*
X502952Y1681456D03*
Y1686180D03*
X510826Y1691692D03*
Y1696417D03*
X502952Y1695629D03*
Y1700354D03*
X510826Y1705866D03*
Y1710590D03*
X502952Y1709803D03*
Y1714527D03*
X510826Y1720039D03*
Y1724763D03*
X502952Y1723976D03*
Y1728700D03*
X510826Y1734212D03*
X518700Y1672007D03*
Y1681456D03*
Y1686180D03*
X526574Y1677519D03*
Y1682244D03*
X518700Y1695629D03*
Y1700354D03*
X526574Y1691692D03*
Y1696417D03*
X518700Y1709803D03*
Y1714527D03*
X526574Y1705866D03*
Y1710590D03*
X518700Y1723976D03*
Y1728700D03*
X526574Y1720039D03*
Y1724763D03*
Y1734212D03*
X534448Y1672007D03*
X542322Y1677519D03*
Y1682244D03*
X534448Y1681456D03*
Y1686180D03*
X542322Y1691692D03*
Y1696417D03*
X534448Y1695629D03*
Y1700354D03*
X542322Y1705866D03*
Y1710590D03*
X534448Y1709803D03*
Y1714527D03*
X542322Y1720039D03*
Y1724763D03*
X534448Y1723976D03*
Y1728700D03*
X542322Y1734212D03*
X550196Y1672007D03*
Y1681456D03*
Y1686180D03*
Y1695629D03*
Y1700354D03*
Y1709803D03*
Y1714527D03*
Y1723976D03*
Y1728700D03*
X569882Y1672007D03*
X562008Y1677519D03*
X569882Y1681456D03*
X562008Y1682244D03*
X569882Y1686180D03*
X562008Y1691692D03*
X569882Y1695629D03*
X562008Y1696417D03*
X569882Y1700354D03*
X562008Y1705866D03*
X569882Y1709803D03*
X562008Y1710590D03*
X569882Y1714527D03*
X562008Y1720039D03*
X569882Y1723976D03*
X562008Y1724763D03*
X569882Y1728700D03*
X562008Y1734212D03*
X585630Y1672007D03*
X577756Y1677519D03*
X585630Y1681456D03*
X577756Y1682244D03*
X585630Y1686180D03*
X577756Y1691692D03*
X585630Y1695629D03*
X577756Y1696417D03*
X585630Y1700354D03*
X577756Y1705866D03*
X585630Y1709803D03*
X577756Y1710590D03*
X585630Y1714527D03*
X577756Y1720039D03*
X585630Y1723976D03*
X577756Y1724763D03*
X585630Y1728700D03*
X577756Y1734212D03*
X601378Y1672007D03*
X593504Y1677519D03*
X601378Y1681456D03*
X593504Y1682244D03*
X601378Y1686180D03*
X593504Y1691692D03*
X601378Y1695629D03*
X593504Y1696417D03*
X601378Y1700354D03*
X593504Y1705866D03*
X601378Y1709803D03*
X593504Y1710590D03*
X601378Y1714527D03*
X593504Y1720039D03*
X601378Y1723976D03*
X593504Y1724763D03*
X601378Y1728700D03*
X593504Y1734212D03*
X617126Y1672007D03*
X609252Y1677519D03*
X617126Y1681456D03*
X609252Y1682244D03*
X617126Y1686180D03*
X609252Y1691692D03*
X617126Y1695629D03*
X609252Y1696417D03*
X617126Y1700354D03*
X609252Y1705866D03*
X617126Y1709803D03*
X609252Y1710590D03*
X617126Y1714527D03*
X609252Y1720039D03*
X617126Y1723976D03*
X609252Y1724763D03*
X617126Y1728700D03*
X609252Y1734212D03*
X1238778Y1677519D03*
Y1682244D03*
Y1691692D03*
Y1696417D03*
Y1705866D03*
Y1710590D03*
Y1720039D03*
Y1724763D03*
Y1734212D03*
X1246652Y1672007D03*
X1254526Y1677519D03*
Y1682244D03*
X1246652Y1681456D03*
Y1686180D03*
X1254526Y1691692D03*
Y1696417D03*
X1246652Y1695629D03*
Y1700354D03*
X1254526Y1705866D03*
Y1710590D03*
X1246652Y1709803D03*
Y1714527D03*
X1254526Y1720039D03*
Y1724763D03*
X1246652Y1723976D03*
Y1728700D03*
X1254526Y1734212D03*
X1262400Y1672007D03*
Y1681456D03*
Y1686180D03*
X1270274Y1677519D03*
Y1682244D03*
X1262400Y1695629D03*
Y1700354D03*
X1270274Y1691692D03*
Y1696417D03*
X1262400Y1709803D03*
Y1714527D03*
X1270274Y1705866D03*
Y1710590D03*
X1262400Y1723976D03*
Y1728700D03*
X1270274Y1720039D03*
Y1724763D03*
Y1734212D03*
X1278148Y1672007D03*
X1286022Y1677519D03*
Y1682244D03*
X1278148Y1681456D03*
Y1686180D03*
X1286022Y1691692D03*
Y1696417D03*
X1278148Y1695629D03*
Y1700354D03*
X1286022Y1705866D03*
Y1710590D03*
X1278148Y1709803D03*
Y1714527D03*
X1286022Y1720039D03*
Y1724763D03*
X1278148Y1723976D03*
Y1728700D03*
X1286022Y1734212D03*
X1293896Y1672007D03*
Y1681456D03*
Y1686180D03*
Y1695629D03*
Y1700354D03*
Y1709803D03*
Y1714527D03*
Y1723976D03*
Y1728700D03*
X1313582Y1672007D03*
X1305708Y1677519D03*
X1313582Y1681456D03*
X1305708Y1682244D03*
X1313582Y1686180D03*
X1305708Y1691692D03*
X1313582Y1695629D03*
X1305708Y1696417D03*
X1313582Y1700354D03*
X1305708Y1705866D03*
X1313582Y1709803D03*
X1305708Y1710590D03*
X1313582Y1714527D03*
X1305708Y1720039D03*
X1313582Y1723976D03*
X1305708Y1724763D03*
X1313582Y1728700D03*
X1305708Y1734212D03*
X1329330Y1672007D03*
X1321456Y1677519D03*
X1329330Y1681456D03*
X1321456Y1682244D03*
X1329330Y1686180D03*
X1321456Y1691692D03*
X1329330Y1695629D03*
X1321456Y1696417D03*
X1329330Y1700354D03*
X1321456Y1705866D03*
X1329330Y1709803D03*
X1321456Y1710590D03*
X1329330Y1714527D03*
X1321456Y1720039D03*
X1329330Y1723976D03*
X1321456Y1724763D03*
X1329330Y1728700D03*
X1321456Y1734212D03*
X1345078Y1672007D03*
X1337204Y1677519D03*
X1345078Y1681456D03*
X1337204Y1682244D03*
X1345078Y1686180D03*
X1337204Y1691692D03*
X1345078Y1695629D03*
X1337204Y1696417D03*
X1345078Y1700354D03*
X1337204Y1705866D03*
X1345078Y1709803D03*
X1337204Y1710590D03*
X1345078Y1714527D03*
X1337204Y1720039D03*
X1345078Y1723976D03*
X1337204Y1724763D03*
X1345078Y1728700D03*
X1337204Y1734212D03*
X1360826Y1672007D03*
X1352952Y1677519D03*
X1360826Y1681456D03*
X1352952Y1682244D03*
X1360826Y1686180D03*
X1352952Y1691692D03*
X1360826Y1695629D03*
X1352952Y1696417D03*
X1360826Y1700354D03*
X1352952Y1705866D03*
X1360826Y1709803D03*
X1352952Y1710590D03*
X1360826Y1714527D03*
X1352952Y1720039D03*
X1360826Y1723976D03*
X1352952Y1724763D03*
X1360826Y1728700D03*
X1352952Y1734212D03*
X1510826Y1672007D03*
X1502952Y1677519D03*
X1510826Y1681456D03*
X1502952Y1682244D03*
X1510826Y1686180D03*
X1502952Y1691692D03*
X1510826Y1695629D03*
X1502952Y1696417D03*
X1510826Y1700354D03*
X1502952Y1705866D03*
X1510826Y1709803D03*
X1502952Y1710590D03*
X1510826Y1714527D03*
X1502952Y1720039D03*
X1510826Y1723976D03*
X1502952Y1724763D03*
X1510826Y1728700D03*
X1502952Y1734212D03*
X1526574Y1672007D03*
X1518700Y1677519D03*
X1526574Y1681456D03*
X1518700Y1682244D03*
X1526574Y1686180D03*
X1518700Y1691692D03*
X1526574Y1695629D03*
X1518700Y1696417D03*
X1526574Y1700354D03*
X1518700Y1705866D03*
X1526574Y1709803D03*
X1518700Y1710590D03*
X1526574Y1714527D03*
X1518700Y1720039D03*
X1526574Y1723976D03*
X1518700Y1724763D03*
X1526574Y1728700D03*
X1518700Y1734212D03*
X1542322Y1672007D03*
X1534448Y1677519D03*
X1542322Y1681456D03*
X1534448Y1682244D03*
X1542322Y1686180D03*
X1534448Y1691692D03*
X1542322Y1695629D03*
X1534448Y1696417D03*
X1542322Y1700354D03*
X1534448Y1705866D03*
X1542322Y1709803D03*
X1534448Y1710590D03*
X1542322Y1714527D03*
X1534448Y1720039D03*
X1542322Y1723976D03*
X1534448Y1724763D03*
X1542322Y1728700D03*
X1534448Y1734212D03*
X1558070Y1672007D03*
X1550196Y1677519D03*
X1558070Y1681456D03*
X1550196Y1682244D03*
X1558070Y1686180D03*
X1550196Y1691692D03*
X1558070Y1695629D03*
X1550196Y1696417D03*
X1558070Y1700354D03*
X1550196Y1705866D03*
X1558070Y1709803D03*
X1550196Y1710590D03*
X1558070Y1714527D03*
X1550196Y1720039D03*
X1558070Y1723976D03*
X1550196Y1724763D03*
X1558070Y1728700D03*
X1550196Y1734212D03*
X1569882Y1677519D03*
Y1682244D03*
Y1691692D03*
Y1696417D03*
Y1705866D03*
Y1710590D03*
Y1720039D03*
Y1724763D03*
Y1734212D03*
X1577756Y1672007D03*
X1585630Y1677519D03*
Y1682244D03*
X1577756Y1681456D03*
Y1686180D03*
X1585630Y1691692D03*
Y1696417D03*
X1577756Y1695629D03*
Y1700354D03*
X1585630Y1705866D03*
Y1710590D03*
X1577756Y1709803D03*
Y1714527D03*
X1585630Y1720039D03*
Y1724763D03*
X1577756Y1723976D03*
Y1728700D03*
X1585630Y1734212D03*
X1593504Y1672007D03*
Y1681456D03*
Y1686180D03*
X1601378Y1677519D03*
Y1682244D03*
X1593504Y1695629D03*
Y1700354D03*
X1601378Y1691692D03*
Y1696417D03*
X1593504Y1709803D03*
Y1714527D03*
X1601378Y1705866D03*
Y1710590D03*
X1593504Y1723976D03*
Y1728700D03*
X1601378Y1720039D03*
Y1724763D03*
Y1734212D03*
X1609252Y1672007D03*
X1617126Y1677519D03*
Y1682244D03*
X1609252Y1681456D03*
Y1686180D03*
X1617126Y1691692D03*
Y1696417D03*
X1609252Y1695629D03*
Y1700354D03*
X1617126Y1705866D03*
Y1710590D03*
X1609252Y1709803D03*
Y1714527D03*
X1617126Y1720039D03*
Y1724763D03*
X1609252Y1723976D03*
Y1728700D03*
X1617126Y1734212D03*
X1625000Y1672007D03*
Y1681456D03*
Y1686180D03*
Y1695629D03*
Y1700354D03*
Y1709803D03*
Y1714527D03*
Y1723976D03*
Y1728700D03*
G54D73*
X1859986Y1403418D03*
X1859706Y1709011D03*
X1871790Y476573D03*
X1861790D03*
X1870648Y783729D03*
X1860648D03*
X1862295Y850767D03*
X1872295D03*
X1871790Y1158071D03*
X1861790D03*
X1869986Y1403418D03*
X1869706Y1709011D03*
X1881862Y107291D03*
X1882340Y410829D03*
X1882711Y476864D03*
X1882240Y783474D03*
X1883273Y850816D03*
X1882579Y1158348D03*
X1881223Y1404467D03*
X1881177Y1709323D03*
X1891862Y107291D03*
X1892340Y410829D03*
X1892711Y476864D03*
X1892240Y783474D03*
X1893273Y850816D03*
X1892579Y1158348D03*
X1891223Y1404467D03*
X1891177Y1709323D03*
X2082012Y108312D03*
X2072012D03*
X2071128Y410829D03*
X2081128D03*
G54D13*
X27559Y87795D03*
X40708Y631889D03*
Y1368908D03*
X51180Y1714961D03*
X373622Y87795D03*
X395671Y1714960D03*
X661024Y631890D03*
X707677Y1714960D03*
X800787Y87795D03*
X931693Y757874D03*
X931692Y1072835D03*
X931693Y1387795D03*
X1045866Y87795D03*
X1155709Y1714961D03*
X1271260Y631890D03*
X1461806Y1714961D03*
X1499606Y87795D03*
X1806298Y1714961D03*
X1829921Y87795D03*
X1816772Y631889D03*
Y1368897D03*
G54D35*
X277098Y185236D03*
X395208D03*
G54D64*
X1183858Y217205D03*
X1173858D03*
X1193858D03*
G54D46*
X443467Y594259D03*
X1425533Y601230D03*
G54D16*
X27048Y1533228D03*
X79590Y1369350D03*
X137284Y1533228D03*
X215418Y658055D03*
X276440Y1357539D03*
X420125Y656008D03*
X443764Y1339823D03*
X523173Y578174D03*
X681440Y1385138D03*
X791678D03*
X873622Y1145275D03*
X983858D03*
X1052960Y1369350D03*
X1249812Y1357539D03*
X1370284Y582303D03*
X1417134Y1339823D03*
X1533552Y682342D03*
X1629732Y1383523D03*
X1664890Y642972D03*
X1714330Y1570984D03*
X1739968Y1383527D03*
X1761575Y159134D03*
X1824566Y1570988D03*
X1838150Y201929D03*
G54D51*
X757184Y1702772D03*
X1072863Y1409176D03*
X1080970Y1640958D03*
G54D65*
X1225530Y60384D03*
G54D72*
X1835198Y1601502D03*
G54D76*
X1864986Y1390234D03*
X1886862Y94107D03*
X1887711Y463680D03*
X1888273Y837632D03*
G54D74*
X1866790Y463389D03*
X1867295Y837583D03*
X1886223Y1391283D03*
X2077012Y95128D03*
G54D37*
X303154Y879624D03*
Y886002D03*
X305004Y882813D03*
X303154Y892380D03*
Y898758D03*
X310555Y873246D03*
X317957Y879624D03*
X310555D03*
X319807Y876435D03*
X314256Y873246D03*
X310555Y886002D03*
X314256D03*
X316107Y882813D03*
Y889191D03*
X308705D03*
X319807Y882813D03*
X314256Y892380D03*
X308705Y895569D03*
Y882813D03*
X314256Y898758D03*
X316107Y901947D03*
X308705D03*
Y908325D03*
X314256Y911513D03*
X316107Y908325D03*
X314256Y917891D03*
X308705Y914702D03*
Y921080D03*
X316107D03*
Y940214D03*
X308705Y927458D03*
X316107D03*
X308705Y933836D03*
X314256Y930647D03*
Y937025D03*
X308705Y940214D03*
X314256Y949781D03*
X316107Y946592D03*
X308705D03*
Y952970D03*
X314256Y956159D03*
X316107Y959348D03*
X308705D03*
Y965726D03*
X316107D03*
X314256Y968915D03*
X317957Y981671D03*
X308705Y978482D03*
X316107D03*
X314256Y975293D03*
X308705Y972104D03*
X316107Y984860D03*
X308705D03*
X312406D03*
X319807D03*
X308705Y991238D03*
X310555Y988049D03*
X314256D03*
X316107Y997616D03*
X308705D03*
X314256Y994427D03*
X316107Y1003994D03*
X314256Y1007183D03*
X316107Y1010372D03*
X308705D03*
Y1003994D03*
X327209Y876435D03*
X332760Y879624D03*
X325358D03*
X334598Y872066D03*
X334610Y882813D03*
X321658Y886002D03*
X325358D03*
X330910Y882813D03*
X329059Y886002D03*
X334610Y889191D03*
X327209D03*
X334610Y895569D03*
X321658Y892380D03*
X327209Y895569D03*
X329059Y892380D03*
X334610Y901947D03*
X321658Y898758D03*
X327209Y901947D03*
X329059Y898758D03*
X321658Y905135D03*
Y911513D03*
X329059Y905135D03*
Y911513D03*
X327209Y908325D03*
X334610Y908324D03*
Y914702D03*
X321658Y917891D03*
X327209Y914702D03*
X329059Y917891D03*
X334610Y921080D03*
X321658Y924269D03*
X329059D03*
X327209Y921080D03*
X334610Y927458D03*
Y933836D03*
X321658Y930647D03*
X327209Y927458D03*
Y933836D03*
X329059Y930647D03*
X334610Y940214D03*
X321658Y937025D03*
X327209Y940214D03*
X329059Y937025D03*
Y956159D03*
X334610Y946592D03*
X321658Y943403D03*
Y949781D03*
X329059Y943403D03*
Y949781D03*
X327209Y946592D03*
X334610Y952970D03*
X321658Y956159D03*
X327209Y952970D03*
X334610Y959348D03*
Y965726D03*
X329059Y962537D03*
X327209Y965726D03*
X321658Y962537D03*
X327209Y959348D03*
X321658Y968915D03*
X329059D03*
X334610Y972104D03*
Y978482D03*
X321658Y975293D03*
Y981671D03*
X329059Y975293D03*
X327209Y972104D03*
X332760Y981671D03*
X329059D03*
X327209Y978482D03*
X334610Y984860D03*
X327209D03*
X330910D03*
X334610Y991238D03*
Y997616D03*
X321658Y988049D03*
Y994427D03*
X327209Y991238D03*
X329059Y988049D03*
Y994427D03*
X327209Y997616D03*
X321658Y1000805D03*
X329059D03*
X334610Y1003994D03*
Y1010372D03*
X321658Y1007183D03*
X327209Y1010372D03*
X329059Y1007183D03*
X327209Y1003994D03*
X343862Y879624D03*
X340162Y879568D03*
X345713Y882813D03*
X336461Y886002D03*
X340162D03*
X347563D03*
X342012Y882813D03*
X347563Y892380D03*
X342012Y889191D03*
X340162Y892380D03*
X347563Y898758D03*
Y905135D03*
Y911513D03*
X342012Y901947D03*
X340162Y898758D03*
Y911513D03*
X342012Y908325D03*
X347563Y917891D03*
Y924269D03*
X340162Y917891D03*
X342012Y921080D03*
X347563Y930647D03*
Y937025D03*
X342012Y927458D03*
X340162Y930647D03*
X342012Y940214D03*
X340162Y937025D03*
X347563Y943403D03*
Y949781D03*
Y956159D03*
X340162Y949781D03*
X342012Y946592D03*
X340162Y956159D03*
X347563Y962537D03*
Y968915D03*
X342012Y959348D03*
Y965726D03*
X340162Y968915D03*
X347563Y975293D03*
Y981671D03*
X345713Y984860D03*
X340162Y975293D03*
X343862Y981671D03*
X342012Y978482D03*
Y984860D03*
X347563Y988049D03*
Y994427D03*
Y1000805D03*
X340162Y988049D03*
X342012Y997616D03*
X340162Y994427D03*
X347563Y1007183D03*
X342012Y1010372D03*
X340162Y1007183D03*
X342012Y1003994D03*
X351265Y879568D03*
X360516Y876435D03*
X354965Y879624D03*
X356803Y872066D03*
X351264Y886002D03*
X362366D03*
X356815Y882813D03*
X360516D03*
X353114D03*
X354965Y886002D03*
Y892380D03*
X360516Y889191D03*
Y895569D03*
X353114Y889191D03*
Y895569D03*
X354965Y898758D03*
X360516Y901947D03*
X353114D03*
X354965Y911513D03*
Y905135D03*
X360516Y908325D03*
X353114Y908324D03*
X354965Y917891D03*
X360516Y914702D03*
X353114D03*
X354965Y924269D03*
X360516Y921080D03*
X353114D03*
X354965Y930647D03*
X360516Y927458D03*
Y933836D03*
X353114D03*
Y927458D03*
X354965Y937025D03*
X360516Y940214D03*
X353114D03*
X360516Y946592D03*
X353114D03*
X360516Y952970D03*
X353114D03*
X354965Y956159D03*
Y943403D03*
Y949781D03*
X360516Y959348D03*
Y965726D03*
X353114Y959348D03*
Y965726D03*
X354965Y962537D03*
Y968915D03*
Y975293D03*
Y981671D03*
X360516Y972104D03*
Y978482D03*
X358665Y981671D03*
X353114Y972104D03*
Y978482D03*
X360516Y984860D03*
X356815D03*
X353114D03*
X360516Y997616D03*
Y991238D03*
X353114D03*
Y997616D03*
X354965Y988049D03*
Y994427D03*
Y1000805D03*
Y1007183D03*
X360516Y1003994D03*
X353114D03*
X360516Y1010372D03*
X353114D03*
X369768Y879624D03*
X373469D03*
X375319Y876435D03*
X377169Y879624D03*
X366067Y886002D03*
Y892380D03*
X367917Y889191D03*
X373469Y892380D03*
X367917Y882813D03*
X373469Y886002D03*
X379020Y882813D03*
X377169Y886002D03*
X379020Y895569D03*
X366067Y898758D03*
Y911513D03*
X367917Y901947D03*
X373469Y898758D03*
X379020Y908325D03*
X373469Y911513D03*
Y905135D03*
X367917Y908324D03*
X366067Y917891D03*
X373469D03*
X367917Y921080D03*
X373469Y924269D03*
X379020Y921080D03*
X366067Y930647D03*
Y937025D03*
X367917Y927458D03*
X379020Y933836D03*
X373469Y930647D03*
X367917Y940214D03*
X373469Y937025D03*
X379020Y940214D03*
X366067Y949781D03*
Y956159D03*
X367917Y946592D03*
X373469Y943403D03*
Y949781D03*
Y956159D03*
X379020Y952970D03*
X366067Y968915D03*
X367917Y959348D03*
Y965726D03*
X373469Y962537D03*
Y968915D03*
X379020Y965726D03*
X366067Y975293D03*
X369768Y981671D03*
X367917Y978482D03*
X373469Y975293D03*
Y981671D03*
X367917Y984860D03*
X379020D03*
X371618D03*
X379020Y978482D03*
X366067Y994427D03*
Y988049D03*
X367917Y997616D03*
X379020Y991238D03*
X373469Y988049D03*
X379020Y997616D03*
X373469Y994427D03*
Y1000805D03*
X366067Y1007183D03*
X373469D03*
X367917Y1003994D03*
X379020D03*
X367917Y1010372D03*
X386421Y876435D03*
X388272Y879624D03*
X384571Y873246D03*
X382721Y882813D03*
Y889191D03*
X380870Y892380D03*
X384571Y886002D03*
X386421Y882813D03*
X393823D03*
X388272Y886002D03*
X390122Y882813D03*
X391973Y892380D03*
X390122Y895569D03*
X386421Y889191D03*
X393823D03*
X382721Y901947D03*
X380870Y898758D03*
Y911513D03*
Y905135D03*
X393823Y901947D03*
X391973Y898758D03*
X390122Y901947D03*
X386421D03*
X391973Y905135D03*
Y911513D03*
X390122Y908325D03*
X382721Y914702D03*
X380870Y917891D03*
Y924269D03*
X386421Y914702D03*
X391973Y917891D03*
X393823Y914702D03*
X390122D03*
Y921080D03*
X391973Y924269D03*
X382721Y927458D03*
Y933836D03*
X380870Y930647D03*
X386421Y927458D03*
Y933836D03*
X393823Y927458D03*
X390122D03*
X393823Y933836D03*
X391973Y930647D03*
X390122Y933836D03*
Y940214D03*
X382721Y946592D03*
X380870Y943403D03*
Y949781D03*
Y956159D03*
X386421Y946592D03*
X391973Y943403D03*
Y949781D03*
X393823Y946592D03*
X390122D03*
X391973Y956159D03*
X390122Y952970D03*
X382721Y959348D03*
X380870Y962537D03*
Y968915D03*
X393823Y959348D03*
X390122D03*
Y965726D03*
X386421Y959348D03*
X391973Y962537D03*
Y968915D03*
X386421Y984860D03*
X382721Y972104D03*
X380870Y975293D03*
X393823Y972104D03*
X390122D03*
Y978482D03*
X384571Y981671D03*
X391973D03*
Y975293D03*
X386421Y972104D03*
X393823Y984860D03*
X391973Y988049D03*
X384571Y994427D03*
Y988049D03*
X391973Y994427D03*
X393823Y991238D03*
X386421D03*
Y997616D03*
X391973Y1000805D03*
X384571D03*
X393823Y997616D03*
X386421Y1003994D03*
X382721Y1010372D03*
X390122D03*
X391973Y1007183D03*
X393823Y1003994D03*
X395673Y1007183D03*
X384571D03*
X410477Y873246D03*
X397524Y876435D03*
X399374Y873246D03*
Y879624D03*
X397524Y882813D03*
Y889191D03*
X401225Y882813D03*
X408626D03*
X404925D03*
X401225Y895569D03*
X408626Y889191D03*
X404925D03*
X403075Y892380D03*
X397524Y901947D03*
X401225D03*
X408626D03*
X404925D03*
X403075Y898758D03*
Y905135D03*
Y911513D03*
X401225Y908324D03*
X397524Y914702D03*
X401225D03*
X408626D03*
X403075Y917891D03*
X404925Y914702D03*
X401225Y921080D03*
X403075Y924269D03*
X401225Y933836D03*
X408626Y927458D03*
X404925D03*
X403075Y930647D03*
X401225Y940214D03*
X397524Y927458D03*
Y933836D03*
X401225Y927458D03*
X397524Y946592D03*
X401225D03*
X403075Y943403D03*
X408626Y946592D03*
X403075Y949781D03*
X404925Y946592D03*
X401225Y952970D03*
X403075Y956159D03*
X397524Y959348D03*
X401225Y965726D03*
Y959348D03*
X408626D03*
X404925D03*
X403075Y962537D03*
Y968915D03*
X397524Y972104D03*
X401225D03*
X408626D03*
X404925D03*
X399374Y981671D03*
X406776D03*
X401225Y978482D03*
X403075Y975293D03*
X401225Y984860D03*
X408626D03*
Y991238D03*
X399374Y988049D03*
Y994427D03*
X406776Y988049D03*
X401225Y991238D03*
Y997616D03*
X399374Y1000805D03*
X397524Y1010372D03*
X399374Y1007183D03*
X401225Y1003994D03*
X421579Y873246D03*
X412327Y882813D03*
Y895569D03*
X414177Y892380D03*
X419729Y882813D03*
X416028D03*
X423429Y895569D03*
X425280Y892380D03*
X416028Y889191D03*
X419729D03*
X412327Y901947D03*
X414177Y898758D03*
Y905135D03*
Y911513D03*
X412327Y908325D03*
X423429Y901947D03*
X425280Y898758D03*
X419729Y901947D03*
X416028D03*
X425280Y905135D03*
Y911513D03*
X423429Y908324D03*
X414177Y917891D03*
X412327Y914702D03*
X414177Y924269D03*
X412327Y921080D03*
X423429Y914702D03*
X419729D03*
X416028D03*
X425280Y917891D03*
Y924269D03*
X423429Y921080D03*
X412327Y927458D03*
Y933836D03*
X414177Y930647D03*
X412327Y940214D03*
X414177Y937025D03*
X423429Y927458D03*
X419729D03*
X423429Y933836D03*
X425280Y930647D03*
X419729Y933836D03*
X416028Y927458D03*
Y933836D03*
X425280Y937025D03*
X423429Y940214D03*
X414177Y949781D03*
X412327Y946592D03*
X414177Y943403D03*
X412327Y952970D03*
X414177Y956159D03*
X416028Y946592D03*
X425280Y943403D03*
Y949781D03*
X423429Y946592D03*
X419729D03*
X423429Y952970D03*
X425280Y956159D03*
X412327Y965726D03*
Y959348D03*
X414177Y962537D03*
Y968915D03*
X423429Y965726D03*
X416028Y959348D03*
X423429D03*
X419729D03*
X425280Y962537D03*
Y968915D03*
X416028Y972104D03*
X423429D03*
X419729D03*
X416028Y984860D03*
X423429D03*
X412327Y978482D03*
X414177Y981671D03*
Y975293D03*
X412327Y972104D03*
X423429Y978482D03*
X421579Y981671D03*
X425280Y975293D03*
X414177Y988049D03*
X421579D03*
X423429Y991238D03*
X416028D03*
X434532Y876435D03*
X432681Y879624D03*
X430831Y882813D03*
X427130D03*
X430831Y889191D03*
X427130D03*
X434532Y895569D03*
Y889191D03*
X428981Y905135D03*
X434532Y901947D03*
X432681Y905135D03*
X434532Y908325D03*
X428981Y917891D03*
X432681D03*
X434532Y914702D03*
Y921080D03*
X428981Y930647D03*
Y937025D03*
X432681Y930647D03*
X434532Y927458D03*
Y933836D03*
X432681Y937025D03*
X434532Y940214D03*
X428981Y949781D03*
X432681D03*
X434532Y946592D03*
Y952970D03*
X428981Y962537D03*
X432681D03*
X434532Y959348D03*
Y965726D03*
X428981Y981671D03*
Y975293D03*
X430831Y984860D03*
X434532Y972104D03*
X432681Y975293D03*
X434532Y978482D03*
X430831Y991238D03*
X428981Y988049D03*
X445609Y876435D03*
X447460Y879624D03*
X445609Y882813D03*
Y889191D03*
Y895569D03*
X453011Y882813D03*
X449310Y889191D03*
X453011D03*
X454861Y892380D03*
X445609Y901947D03*
Y908325D03*
X454861Y898758D03*
X451160Y905135D03*
X454861D03*
Y911513D03*
X447460Y905135D03*
X445609Y914702D03*
Y921080D03*
X447460Y917891D03*
X451160D03*
X454861D03*
Y924269D03*
Y930647D03*
X447460Y937025D03*
X451160D03*
X454861D03*
X445609Y927458D03*
Y933836D03*
Y940214D03*
X447460Y930647D03*
X451160D03*
X445609Y946592D03*
Y952970D03*
X447460Y949781D03*
X454861Y943403D03*
X451160Y949781D03*
X454861D03*
Y956159D03*
X445609Y959348D03*
Y965726D03*
X454861Y962537D03*
X451160D03*
X447460D03*
X454861Y968915D03*
X445609Y972104D03*
Y978482D03*
Y984860D03*
X447460Y981671D03*
X454861D03*
X451160Y975293D03*
X447460D03*
X454861D03*
X453011Y984860D03*
X445609Y991238D03*
X453011D03*
X454861Y988049D03*
X447460D03*
X460412Y876435D03*
X469664Y879624D03*
X460412Y889191D03*
X456712Y895569D03*
X467814Y882813D03*
X465964Y892380D03*
X467814Y895569D03*
X464113Y889191D03*
X456712Y908324D03*
X465964Y911513D03*
X456712Y901947D03*
X460412D03*
X465964Y898758D03*
X467814Y901947D03*
X464113D03*
X467814Y908325D03*
X465964Y905135D03*
X460412Y914702D03*
X456712D03*
Y921080D03*
X467814Y914702D03*
X464113D03*
X465964Y917891D03*
X467814Y921080D03*
X465964Y924269D03*
X460412Y927458D03*
X456712D03*
Y933836D03*
X460412D03*
X456712Y940214D03*
X467814Y927458D03*
Y933836D03*
X464113Y927458D03*
Y933836D03*
X467814Y940214D03*
X465964Y937025D03*
X460412Y946592D03*
X456712D03*
Y952970D03*
X467814Y946592D03*
X464113D03*
X465964Y943403D03*
Y949781D03*
X467814Y952970D03*
X465964Y956159D03*
X456712Y965726D03*
X460412Y959348D03*
X456712D03*
X467814Y965726D03*
Y959348D03*
X465964Y962537D03*
X464113Y959348D03*
X465964Y968915D03*
X456712Y972104D03*
Y978482D03*
X462263Y981671D03*
X460412Y972104D03*
Y984860D03*
X469664Y981671D03*
X467814Y978482D03*
Y972104D03*
X465964Y975293D03*
X464113Y972104D03*
X467814Y984860D03*
X460412Y991238D03*
X462263Y988049D03*
X469664D03*
X467814Y991238D03*
X471515Y876435D03*
X480767Y873246D03*
Y879624D03*
X482617Y876435D03*
X478916Y882813D03*
X475215D03*
X471515D03*
X478916Y895569D03*
X477066Y892380D03*
X475215Y889191D03*
X471515D03*
X482617Y882813D03*
Y889191D03*
X478916Y901947D03*
X471515D03*
X475215D03*
X477066Y898758D03*
X478916Y908325D03*
X477066Y905135D03*
Y911513D03*
X482617Y901947D03*
X478916Y914702D03*
X477066Y917891D03*
X475215Y914702D03*
X471515D03*
X478916Y921080D03*
X477066Y924269D03*
X482617Y914702D03*
X478916Y927458D03*
Y933836D03*
X475215Y927458D03*
X471515D03*
X477066Y930647D03*
X478916Y940214D03*
X482617Y927458D03*
Y933836D03*
X478916Y946592D03*
X477066Y943403D03*
X475215Y946592D03*
X471515D03*
X477066Y949781D03*
X478916Y952970D03*
X477066Y956159D03*
X482617Y946592D03*
X478916Y965726D03*
Y959348D03*
X475215D03*
X471515D03*
X477066Y962537D03*
Y968915D03*
X482617Y959348D03*
X478916Y978482D03*
Y972104D03*
X477066Y981671D03*
Y975293D03*
X475215Y972104D03*
X471515D03*
X475215Y984860D03*
X484467Y981671D03*
X482617Y972104D03*
Y984860D03*
X477066Y994427D03*
X475215Y991238D03*
X477066Y988049D03*
Y1000805D03*
X484467Y994427D03*
Y988049D03*
X482617Y991238D03*
Y997616D03*
X484467Y1000805D03*
X477066Y1007183D03*
X484467D03*
X482617Y1010372D03*
Y1003994D03*
X493719Y876435D03*
X491869Y879624D03*
X493719Y882813D03*
X490019D03*
X486318D03*
X493719Y889191D03*
X486318D03*
X490019Y895569D03*
X488168Y892380D03*
X497420Y889191D03*
X499271Y892380D03*
X493719Y901947D03*
X486318D03*
X490019D03*
X488168Y898758D03*
Y905135D03*
Y911513D03*
X497420Y901947D03*
X499271Y898758D03*
Y905135D03*
Y911513D03*
X490019Y908324D03*
X493719Y914702D03*
X488168Y917891D03*
X490019Y914702D03*
X486318D03*
X490019Y921080D03*
X488168Y924269D03*
X499271Y917891D03*
X497420Y914702D03*
X499271Y924269D03*
X493719Y927458D03*
X486318D03*
X490019D03*
X493719Y933836D03*
X490019D03*
X486318D03*
X488168Y930647D03*
X490019Y940214D03*
X497420Y927458D03*
Y933836D03*
X499271Y930647D03*
X488168Y943403D03*
X493719Y946592D03*
X490019D03*
X486318D03*
X488168Y949781D03*
X490019Y952970D03*
X488168Y956159D03*
X497420Y946592D03*
X499271Y943403D03*
Y949781D03*
Y956159D03*
X490019Y965726D03*
X493719Y959348D03*
X490019D03*
X486318D03*
X488168Y962537D03*
Y968915D03*
X499271Y962537D03*
X497420Y959348D03*
X499271Y968915D03*
X491869Y981671D03*
X490019Y978482D03*
X493719Y972104D03*
X488168Y975293D03*
X490019Y972104D03*
X486318D03*
X490019Y984860D03*
X497420Y972104D03*
X499271Y975293D03*
Y981671D03*
X497420Y984860D03*
X491869Y994427D03*
Y988049D03*
X490019Y997616D03*
Y991238D03*
X491869Y1000805D03*
X497420Y991238D03*
Y997616D03*
X499271Y988049D03*
Y994427D03*
Y1000805D03*
X491869Y1007183D03*
X490019Y1010372D03*
Y1003994D03*
X497420Y1010372D03*
Y1003994D03*
X499271Y1007183D03*
X502971Y879624D03*
X501133Y872118D03*
X508523Y882813D03*
X506672Y886002D03*
X502971D03*
X504822Y882813D03*
X506672Y892380D03*
X501121Y895569D03*
X512223Y882813D03*
X514074Y886002D03*
X512223Y889191D03*
X514074Y892380D03*
X506672Y898758D03*
Y905135D03*
Y911513D03*
X501121Y908325D03*
X512223Y901947D03*
X514074Y898758D03*
Y911513D03*
X512223Y908325D03*
X506672Y917891D03*
X501121Y921080D03*
X506672Y924269D03*
X514074Y917891D03*
X512223Y921080D03*
X506672Y930647D03*
X501121Y933836D03*
X506672Y937025D03*
X501121Y940214D03*
X512223Y927458D03*
X514074Y930647D03*
X512223Y940214D03*
X514074Y937025D03*
X506672Y943403D03*
Y949781D03*
X501121Y952970D03*
X506672Y956159D03*
X514074Y949781D03*
X512223Y946592D03*
X514074Y956159D03*
X506672Y962537D03*
X501121Y965726D03*
X506672Y968915D03*
X512223Y959348D03*
Y965726D03*
X514074Y968915D03*
X510373Y981671D03*
X506672Y975293D03*
Y981671D03*
X501121Y978482D03*
X508523Y984860D03*
X514074Y975293D03*
X512223Y978482D03*
Y984860D03*
X506672Y988049D03*
Y994427D03*
Y1000805D03*
X514074Y988049D03*
Y994427D03*
X512223Y997616D03*
X506672Y1007183D03*
X514074D03*
X512223Y1003994D03*
X525176Y879624D03*
X515924Y876435D03*
X525176Y873246D03*
Y886002D03*
X523326Y882813D03*
X517775Y886002D03*
X519625Y882813D03*
X527027Y895569D03*
Y889191D03*
X525176Y892380D03*
X519625Y889191D03*
Y895569D03*
X528877Y886002D03*
X527027Y901947D03*
X525176Y898758D03*
X519625Y901947D03*
X525176Y905135D03*
Y911513D03*
X519625Y908325D03*
X527027Y908324D03*
X525176Y917891D03*
X519625Y914702D03*
X527027D03*
Y921080D03*
X525176Y924269D03*
X519625Y921080D03*
X525176Y937025D03*
X527027Y927458D03*
Y933836D03*
X525176Y930647D03*
X519625Y927458D03*
Y933836D03*
X527027Y940214D03*
X519625D03*
X527027Y946592D03*
X519625D03*
X525176Y943403D03*
Y949781D03*
X527027Y952970D03*
X525176Y956159D03*
X519625Y952970D03*
X527027Y959348D03*
Y965726D03*
X525176Y962537D03*
X519625Y959348D03*
Y965726D03*
X525176Y968915D03*
X521475Y981671D03*
X519625Y978482D03*
X527027Y984860D03*
X523326D03*
X519625D03*
X527027Y972104D03*
Y978482D03*
X525176Y975293D03*
Y981671D03*
X519625Y972104D03*
X527027Y991238D03*
Y997616D03*
X525176Y988049D03*
Y994427D03*
X519625Y991238D03*
Y997616D03*
X525176Y1000805D03*
X527027Y1010372D03*
Y1003994D03*
X525176Y1007183D03*
X519625Y1010372D03*
Y1003994D03*
X534428Y876435D03*
X539979Y879624D03*
X532578D03*
X541830Y876435D03*
X543680Y879624D03*
X538129Y889191D03*
X539979Y892380D03*
X532578D03*
X543680Y886002D03*
X538129Y882813D03*
X532578Y886002D03*
X534428Y882813D03*
X538129Y901947D03*
X539979Y898758D03*
X532578D03*
X539979Y911513D03*
X538129Y908325D03*
X532578Y905135D03*
Y911513D03*
X539979Y917891D03*
X532578D03*
X538129Y921080D03*
X532578Y924269D03*
X538129Y927458D03*
X539979Y930647D03*
X532578D03*
X539979Y937025D03*
X538129Y940214D03*
X532578Y937025D03*
X539979Y949781D03*
X538129Y946592D03*
X532578Y943403D03*
Y949781D03*
X539979Y956159D03*
X532578D03*
X538129Y959348D03*
Y965726D03*
X532578Y962537D03*
X539979Y968915D03*
X532578D03*
X539979Y975293D03*
X532578D03*
X538129Y978482D03*
X536279Y981671D03*
X532578D03*
X538129Y984860D03*
X534428D03*
X532578Y994427D03*
X539979Y988049D03*
X532578D03*
X539979Y994427D03*
X538129Y997616D03*
X532578Y1000805D03*
X539978Y1007184D03*
X538129Y1003994D03*
X532578Y1007183D03*
X545531Y876435D03*
X552932D03*
X556633D03*
X551082Y879624D03*
X545543Y872085D03*
X554783Y886002D03*
X549231Y882813D03*
X558483Y892380D03*
X545531Y889191D03*
Y895569D03*
X552932Y889191D03*
X551082Y892380D03*
X552932Y895569D03*
X558483Y886002D03*
X545531Y882813D03*
X551082Y886002D03*
X558483Y898758D03*
X545531Y901947D03*
X552932D03*
X551082Y898758D03*
X558483Y905135D03*
Y911513D03*
X551082Y905135D03*
Y911513D03*
X552932Y908325D03*
X545531Y908324D03*
X558483Y917891D03*
X551082D03*
X552932Y914702D03*
X545531D03*
X558483Y924269D03*
X551082D03*
X552932Y921080D03*
X545531D03*
X558483Y930647D03*
X545531Y927458D03*
Y933836D03*
X552932Y927458D03*
Y933836D03*
X551082Y930647D03*
X558483Y937025D03*
X545531Y940214D03*
X551082Y937025D03*
X552932Y940214D03*
X558483Y943403D03*
Y949781D03*
X545531Y946592D03*
X551082Y943403D03*
Y949781D03*
X552932Y946592D03*
X558483Y956159D03*
X545531Y952970D03*
X552932D03*
X551082Y956159D03*
X558483Y962537D03*
X545531Y959348D03*
Y965726D03*
X552932Y959348D03*
X551082Y962537D03*
X552932Y965726D03*
X558483Y968915D03*
X551082D03*
X558483Y975293D03*
Y981671D03*
X545531Y972104D03*
Y978482D03*
X547381Y981671D03*
X551082Y975293D03*
X552932Y972104D03*
X551082Y981671D03*
X552932Y978482D03*
Y984860D03*
X549231D03*
X545531D03*
X558483Y988049D03*
Y994427D03*
X552932Y991238D03*
X551082Y994427D03*
X552932Y997616D03*
X545531Y991238D03*
Y997616D03*
X551082Y988049D03*
X558483Y1000805D03*
X551082D03*
X558483Y1007183D03*
X545531Y1010372D03*
Y1003994D03*
X552932Y1010372D03*
X551082Y1007183D03*
X552932Y1003994D03*
X562184Y879624D03*
X569586Y873246D03*
X560334Y882813D03*
X564034D03*
X569586Y886002D03*
X571436Y882813D03*
Y889191D03*
X564034D03*
X565885Y892380D03*
X571436Y895569D03*
X564034Y901947D03*
X571436D03*
X565885Y898758D03*
X564034Y908325D03*
X571436D03*
X565885Y911513D03*
Y917891D03*
X571436Y914702D03*
X564034Y921080D03*
X571436D03*
X564034Y927458D03*
X571436D03*
X565885Y930647D03*
X571436Y933836D03*
X565885Y937025D03*
X564034Y940214D03*
X571436D03*
X565885Y949781D03*
X564034Y946592D03*
X571436D03*
Y952970D03*
X565885Y956159D03*
X564034Y959348D03*
X571436D03*
X564034Y965726D03*
X571436D03*
X565885Y968915D03*
X562184Y981671D03*
X565885Y975293D03*
X571436Y972104D03*
X564034Y978482D03*
X571436D03*
X567735Y984860D03*
X560334D03*
X564034D03*
X571436D03*
X569586Y988049D03*
X571436Y991238D03*
X565885Y994427D03*
X564034Y997616D03*
X571436D03*
X565885Y988049D03*
X571436Y1010372D03*
X565885Y1007183D03*
X564034Y1003994D03*
X571436D03*
X576987Y879624D03*
X575137Y882813D03*
X576987Y886002D03*
Y892380D03*
Y898758D03*
X1286697Y873245D03*
Y879623D03*
X1279296D03*
X1284847Y895568D03*
Y882812D03*
X1286697Y886001D03*
X1281146Y882812D03*
X1279296Y886001D03*
X1284847Y889190D03*
X1279296Y892379D03*
X1284847Y901946D03*
X1279296Y898757D03*
X1284847Y908324D03*
Y914701D03*
Y921079D03*
Y927457D03*
Y933835D03*
Y940213D03*
Y946591D03*
Y952969D03*
Y959347D03*
Y965725D03*
Y972103D03*
Y978481D03*
Y984859D03*
X1288548D03*
X1284847Y991237D03*
X1286697Y988048D03*
X1284847Y997615D03*
Y1010371D03*
Y1003993D03*
X1290398Y873245D03*
X1301500Y879623D03*
X1303351Y876434D03*
X1294099Y879623D03*
X1295949Y876434D03*
X1303351Y895568D03*
X1290398Y886001D03*
Y892379D03*
X1292249Y882812D03*
X1297800Y886001D03*
X1301500D03*
X1295949Y882812D03*
X1292249Y889190D03*
X1303351D03*
X1297800Y892379D03*
X1290398Y898757D03*
Y911512D03*
X1292249Y901946D03*
X1297800Y898757D03*
X1303351Y901946D03*
X1292249Y908324D03*
X1297800Y905134D03*
Y911512D03*
X1303351Y908324D03*
X1290398Y917890D03*
X1297800D03*
X1303351Y914701D03*
Y921079D03*
X1297800Y924268D03*
X1292249Y921079D03*
X1297800Y930646D03*
X1303351Y927457D03*
Y933835D03*
X1292249Y927457D03*
X1303351Y940213D03*
X1297800Y937024D03*
X1292249Y940213D03*
X1290398Y930646D03*
Y937024D03*
Y949780D03*
Y956158D03*
X1297800Y949780D03*
X1303351Y946591D03*
X1292249D03*
X1297800Y943402D03*
X1303351Y952969D03*
X1297800Y956158D03*
X1290398Y968914D03*
X1297800Y962536D03*
X1303351Y959347D03*
Y965725D03*
X1292249Y959347D03*
Y965725D03*
X1297800Y968914D03*
X1290398Y975292D03*
X1297800Y981670D03*
Y975292D03*
X1303351Y972103D03*
Y978481D03*
X1294099Y981670D03*
X1292249Y978481D03*
X1303351Y984859D03*
X1295949D03*
X1292249D03*
X1290398Y988048D03*
Y994426D03*
X1297800D03*
Y988048D03*
X1303351Y991237D03*
Y997615D03*
X1292249D03*
X1297800Y1000804D03*
X1290398Y1007182D03*
X1292249Y1010371D03*
X1297800Y1007182D03*
X1303351Y1010371D03*
Y1003993D03*
X1292249D03*
X1314453Y876434D03*
X1308902Y873245D03*
Y879623D03*
X1310752Y895568D03*
X1307052Y882812D03*
X1305201Y886001D03*
Y892379D03*
X1310752Y882812D03*
X1312603Y886001D03*
X1316304D03*
X1318154Y882812D03*
X1310752Y889190D03*
X1318154D03*
X1316304Y892379D03*
X1305201Y898757D03*
Y905134D03*
Y911512D03*
X1310752Y901946D03*
X1318154D03*
X1316304Y898757D03*
Y911512D03*
X1318154Y908324D03*
X1310752Y908323D03*
X1305201Y917890D03*
Y924268D03*
X1310752Y914701D03*
X1316304Y917890D03*
X1318154Y921079D03*
X1310752D03*
X1305201Y930646D03*
Y937024D03*
X1310752Y927457D03*
Y933835D03*
X1318154Y927457D03*
X1316304Y930646D03*
Y937024D03*
X1310752Y940213D03*
X1318154D03*
X1305201Y943402D03*
Y949780D03*
Y956158D03*
X1310752Y946591D03*
X1316304Y949780D03*
X1318154Y946591D03*
X1310752Y952969D03*
X1316304Y956158D03*
X1318154Y959347D03*
Y965725D03*
X1316304Y968914D03*
X1305201Y962536D03*
Y968914D03*
X1310752Y959347D03*
Y965725D03*
X1305201Y975292D03*
Y981670D03*
X1307052Y984859D03*
X1310752Y972103D03*
Y978481D03*
X1316304Y975292D03*
X1318154Y978481D03*
X1308902Y981670D03*
X1310752Y984859D03*
X1318154D03*
X1305201Y988048D03*
Y994426D03*
Y1000804D03*
X1310752Y991237D03*
Y997615D03*
X1316304Y988048D03*
X1318154Y997615D03*
X1316304Y994426D03*
X1305201Y1007182D03*
X1310752Y1003993D03*
Y1010371D03*
X1318154D03*
X1316304Y1007182D03*
X1318154Y1003993D03*
X1320004Y879623D03*
X1331107Y873245D03*
X1325556Y876434D03*
X1331107Y879623D03*
X1321855Y882812D03*
X1323705Y886001D03*
X1329256Y882812D03*
X1332957D03*
X1331107Y886001D03*
X1327406D03*
X1323705Y892379D03*
X1329256Y889190D03*
X1331107Y892379D03*
X1329256Y895568D03*
X1323705Y898757D03*
X1331107D03*
X1329256Y901946D03*
X1331107Y911512D03*
X1323705D03*
Y905134D03*
X1331107D03*
X1329256Y908323D03*
Y914701D03*
X1323705Y917890D03*
X1331107D03*
X1323705Y924268D03*
X1329256Y921079D03*
X1331107Y924268D03*
Y930646D03*
X1329256Y933835D03*
X1323705Y930646D03*
X1329256Y927457D03*
X1331107Y937024D03*
X1329256Y940213D03*
X1323705Y937024D03*
X1331107Y943402D03*
X1329256Y946591D03*
X1331107Y949780D03*
X1323705Y943402D03*
Y949780D03*
X1329256Y952969D03*
X1331107Y956158D03*
X1323705D03*
X1329256Y959347D03*
X1331107Y962536D03*
X1329256Y965725D03*
X1323705Y962536D03*
X1331107Y968914D03*
X1323705D03*
X1320004Y981670D03*
X1321855Y984859D03*
X1323705Y975292D03*
Y981670D03*
X1329256Y972103D03*
X1331107Y975292D03*
X1329256Y978481D03*
X1331107Y981670D03*
X1334807D03*
X1329256Y984859D03*
X1332957D03*
X1323705Y1000804D03*
Y988048D03*
Y994426D03*
X1329256Y997615D03*
X1331107Y988048D03*
X1329256Y991237D03*
X1331107Y994426D03*
Y1000804D03*
X1323705Y1007182D03*
X1329256Y1003993D03*
X1331107Y1007182D03*
X1329256Y1010371D03*
X1336658Y876434D03*
X1345910Y879623D03*
X1349611D03*
X1338508Y886001D03*
X1336658Y882812D03*
Y889190D03*
Y895568D03*
X1342209Y886001D03*
X1349611D03*
X1344059Y882812D03*
Y889190D03*
X1342209Y892379D03*
X1349611D03*
X1336658Y901946D03*
Y908324D03*
X1342209Y898757D03*
X1349611D03*
X1344059Y901946D03*
X1349611Y905134D03*
X1342209Y911512D03*
X1349611D03*
X1344059Y908323D03*
X1336658Y914701D03*
Y921079D03*
X1342209Y917890D03*
X1349611D03*
X1344059Y921079D03*
X1349611Y924268D03*
X1336658Y933835D03*
Y927457D03*
Y940213D03*
X1344059Y927457D03*
X1342209Y930646D03*
X1349611D03*
X1344059Y940213D03*
X1342209Y937024D03*
X1349611D03*
Y943402D03*
X1344059Y946591D03*
X1349611Y949780D03*
X1342209D03*
X1349611Y956158D03*
X1342209D03*
X1336658Y946591D03*
Y952969D03*
Y965725D03*
Y959347D03*
X1344059D03*
X1349611Y962536D03*
X1344059Y965725D03*
X1349611Y968914D03*
X1342209D03*
X1336658Y972103D03*
Y978481D03*
Y984859D03*
X1349611Y975292D03*
X1342209D03*
X1344059Y978481D03*
X1349611Y981670D03*
X1345910D03*
X1344059Y984859D03*
X1347760D03*
X1336658Y997615D03*
Y991237D03*
X1349611Y988048D03*
Y994426D03*
X1342209D03*
X1344059Y997615D03*
X1342209Y988048D03*
X1349611Y1000804D03*
X1336658Y1010371D03*
X1344059D03*
X1336658Y1003993D03*
X1344059D03*
X1342209Y1007182D03*
X1349611D03*
X1351461Y876434D03*
X1353311Y879623D03*
X1364414D03*
X1360713Y873245D03*
X1362563Y876434D03*
X1353311Y886001D03*
X1362563Y882812D03*
X1358863D03*
X1364414Y886001D03*
X1360713D03*
X1355162Y882812D03*
X1357012Y892379D03*
X1355162Y895568D03*
X1362563Y889190D03*
X1358863D03*
X1357012Y898757D03*
X1362563Y901946D03*
X1358863D03*
X1357012Y905134D03*
Y911512D03*
X1355162Y908324D03*
X1358863Y914701D03*
X1362563D03*
X1357012Y917890D03*
X1355162Y921079D03*
X1357012Y924268D03*
X1362563Y933835D03*
X1358863D03*
X1355162D03*
X1362563Y927457D03*
X1358863D03*
X1357012Y930646D03*
X1355162Y940213D03*
X1357012Y943402D03*
X1358863Y946591D03*
X1362563D03*
X1357012Y949780D03*
Y956158D03*
X1355162Y952969D03*
X1358863Y959347D03*
X1362563D03*
X1357012Y962536D03*
X1355162Y965725D03*
X1357012Y968914D03*
X1358863Y972103D03*
X1362563D03*
X1357012Y975292D03*
X1360713Y981670D03*
X1355162Y978481D03*
X1362563Y984859D03*
X1355162D03*
Y991237D03*
Y997615D03*
X1362563Y991237D03*
Y997615D03*
X1360713Y994426D03*
Y988048D03*
Y1000804D03*
X1358863Y1010371D03*
X1360713Y1007182D03*
X1362563Y1003993D03*
X1355162D03*
X1373666Y876434D03*
X1375516Y873245D03*
Y879623D03*
X1369965Y882812D03*
X1366264D03*
X1369965Y889190D03*
X1368115Y892379D03*
X1366264Y895568D03*
X1373666Y882812D03*
X1377367D03*
X1379217Y892379D03*
X1377367Y895568D03*
X1373666Y889190D03*
X1368115Y898757D03*
X1369965Y901946D03*
X1366264D03*
X1368115Y905134D03*
Y911512D03*
X1366264Y908324D03*
X1379217Y898757D03*
X1377367Y901946D03*
X1373666D03*
X1379217Y905134D03*
X1377367Y908324D03*
X1379217Y911512D03*
X1369965Y914701D03*
X1368115Y917890D03*
X1366264Y914701D03*
X1368115Y924268D03*
X1366264Y921079D03*
X1377367Y914701D03*
X1373666D03*
X1379217Y917890D03*
X1377367Y921079D03*
X1379217Y924268D03*
X1366264Y933835D03*
X1369965Y927457D03*
X1368115Y930646D03*
X1369965Y933835D03*
X1366264Y927457D03*
Y940213D03*
X1377367Y927457D03*
X1373666D03*
X1379217Y930646D03*
X1377367Y933835D03*
X1373666D03*
X1377367Y940213D03*
X1368115Y943402D03*
X1369965Y946591D03*
X1368115Y949780D03*
X1366264Y946591D03*
X1368115Y956158D03*
X1366264Y952969D03*
X1379217Y943402D03*
X1373666Y946591D03*
X1377367D03*
X1379217Y949780D03*
X1377367Y952969D03*
X1379217Y956158D03*
X1366264Y959347D03*
X1369965D03*
X1368115Y962536D03*
X1366264Y965725D03*
X1368115Y968914D03*
X1373666Y959347D03*
X1377367Y965725D03*
Y959347D03*
X1379217Y962536D03*
Y968914D03*
X1369965Y972103D03*
X1368115Y975292D03*
Y981670D03*
X1366264Y972103D03*
Y978481D03*
X1369965Y984859D03*
X1373666Y972103D03*
X1377367D03*
X1379217Y975292D03*
X1375516Y981670D03*
X1377367Y978481D03*
Y984859D03*
X1369965Y991237D03*
Y997615D03*
X1368115Y994426D03*
Y988048D03*
Y1000804D03*
X1375516Y994426D03*
X1377367Y991237D03*
Y997615D03*
X1375516Y988048D03*
Y1000804D03*
X1369965Y1003993D03*
X1368115Y1007182D03*
X1366264Y1010371D03*
X1373666D03*
X1375516Y1007182D03*
X1371815D03*
X1377367Y1003993D03*
X1386619Y879623D03*
X1382918Y873245D03*
X1384768Y876434D03*
X1394020Y873245D03*
X1384768Y882812D03*
X1381067D03*
Y889190D03*
X1384768D03*
X1392170Y882812D03*
X1388469D03*
Y895568D03*
X1392170Y889190D03*
X1390319Y892379D03*
X1381067Y901946D03*
X1384768D03*
X1388469D03*
X1390319Y898757D03*
X1392170Y901946D03*
X1388469Y908324D03*
X1390319Y911512D03*
Y905134D03*
X1381067Y914701D03*
X1384768D03*
X1390319Y917890D03*
X1388469Y914701D03*
X1392170D03*
X1388469Y921079D03*
X1390319Y924268D03*
X1381067Y927457D03*
X1384768D03*
X1388469D03*
Y933835D03*
X1392170Y927457D03*
X1390319Y930646D03*
X1392170Y933835D03*
X1388469Y940213D03*
X1390319Y937024D03*
X1381067Y946591D03*
X1384768D03*
X1388469D03*
X1390319Y943402D03*
X1392170Y946591D03*
X1390319Y949780D03*
X1388469Y952969D03*
X1390319Y956158D03*
X1381067Y959347D03*
X1384768D03*
X1388469Y965725D03*
Y959347D03*
X1392170D03*
X1390319Y962536D03*
Y968914D03*
X1388469Y978481D03*
X1381067Y972103D03*
X1384768D03*
X1382918Y981670D03*
X1384768Y984859D03*
X1388469Y972103D03*
X1392170D03*
X1390319Y981670D03*
Y975292D03*
X1392170Y984859D03*
X1384768Y991237D03*
X1382918Y988048D03*
X1392170Y991237D03*
X1390319Y988048D03*
X1397721Y873245D03*
Y879623D03*
X1395871Y876434D03*
X1408823Y879623D03*
X1399571Y882812D03*
X1395871D03*
X1401422Y892379D03*
X1399571Y895568D03*
X1395871Y889190D03*
X1403272Y882812D03*
X1406973D03*
X1403272Y889190D03*
X1406973D03*
X1399571Y901946D03*
X1395871D03*
X1401422Y905134D03*
Y911512D03*
X1405123Y905134D03*
X1408823D03*
X1401422Y898757D03*
X1399571Y908323D03*
Y914701D03*
X1401422Y917890D03*
X1395871Y914701D03*
X1399571Y921079D03*
X1401422Y924268D03*
X1405123Y917890D03*
X1408823D03*
X1395871Y927457D03*
Y933835D03*
X1399571Y927457D03*
X1401422Y930646D03*
X1399571Y933835D03*
Y940213D03*
X1401422Y937024D03*
X1405123Y930646D03*
X1408823D03*
X1405123Y937024D03*
X1408823D03*
X1401422Y943402D03*
X1399571Y946591D03*
X1401422Y949780D03*
X1399571Y952969D03*
X1401422Y956158D03*
X1408823Y949780D03*
X1405123D03*
X1395871Y946591D03*
X1399571Y965725D03*
X1395871Y959347D03*
X1399571D03*
X1401422Y962536D03*
Y968914D03*
X1408823Y962536D03*
X1405123D03*
X1397721Y981670D03*
X1399571Y978481D03*
X1395871Y972103D03*
X1399571D03*
X1401422Y975292D03*
X1399571Y984859D03*
X1405123Y981670D03*
X1408823Y975292D03*
X1405123D03*
X1406973Y984859D03*
X1399571Y991237D03*
X1397721Y988048D03*
X1406973Y991237D03*
X1405123Y988048D03*
X1410674Y876434D03*
X1423602Y879623D03*
X1421751Y876434D03*
X1410674Y882812D03*
Y889190D03*
Y895568D03*
X1421751Y882812D03*
Y895568D03*
Y889190D03*
X1410674Y901946D03*
Y908324D03*
X1421751Y901946D03*
X1423602Y905134D03*
X1421751Y908324D03*
X1410674Y914701D03*
Y921079D03*
X1423602Y917890D03*
X1421751Y914701D03*
Y921079D03*
Y940213D03*
X1410674Y927457D03*
Y933835D03*
Y940213D03*
X1423602Y930646D03*
X1421751Y927457D03*
Y933835D03*
X1423602Y937024D03*
X1410674Y946591D03*
Y952969D03*
X1423602Y949780D03*
X1421751Y946591D03*
Y952969D03*
X1410674Y959347D03*
Y965725D03*
X1423602Y962536D03*
X1421751Y959347D03*
Y965725D03*
X1410674Y972103D03*
Y978481D03*
X1423602Y981670D03*
Y975292D03*
X1421751Y972103D03*
Y978481D03*
Y984859D03*
X1423602Y988048D03*
X1421751Y991237D03*
X1436554Y876434D03*
X1429153Y882812D03*
X1425452Y889190D03*
X1429153D03*
X1431003Y892379D03*
X1432854Y895568D03*
X1436554Y889190D03*
X1432854Y901946D03*
X1431003Y898757D03*
Y911512D03*
Y905134D03*
X1427302D03*
X1436554Y901946D03*
X1432854Y908323D03*
Y914701D03*
X1431003Y917890D03*
X1427302D03*
X1432854Y921079D03*
X1431003Y924268D03*
X1436554Y914701D03*
X1432854Y927457D03*
X1431003Y930646D03*
X1427302D03*
X1432854Y933835D03*
Y940213D03*
X1431003Y937024D03*
X1427302D03*
X1436554Y927457D03*
Y933835D03*
X1431003Y943402D03*
Y949780D03*
X1427302D03*
X1432854Y946591D03*
Y952969D03*
X1431003Y956158D03*
X1436554Y946591D03*
X1432854Y959347D03*
X1427302Y962536D03*
X1431003D03*
X1432854Y965725D03*
X1431003Y968914D03*
X1436554Y959347D03*
X1432854Y978481D03*
X1431003Y981670D03*
X1432854Y972103D03*
X1431003Y975292D03*
X1427302D03*
X1429153Y984859D03*
X1438405Y981670D03*
X1436554Y972103D03*
Y984859D03*
X1431003Y988048D03*
X1429153Y991237D03*
X1436554D03*
X1438405Y988048D03*
X1447657Y876434D03*
X1445806Y879623D03*
X1443956Y882812D03*
X1447657D03*
X1440255Y889190D03*
X1447657D03*
X1442106Y892379D03*
X1443956Y895568D03*
X1451357Y882812D03*
X1451358Y889190D03*
X1453208Y892379D03*
X1442106Y898757D03*
X1440255Y901946D03*
X1447657D03*
X1443956D03*
X1442106Y905134D03*
X1443956Y908324D03*
X1442106Y911512D03*
X1451358Y901946D03*
X1453208Y898757D03*
Y905134D03*
Y911512D03*
X1440255Y914701D03*
X1443956D03*
X1447657D03*
X1442106Y917890D03*
X1443956Y921079D03*
X1442106Y924268D03*
X1451357Y914701D03*
X1453208Y917890D03*
Y924268D03*
X1440255Y927457D03*
X1443956D03*
X1447657D03*
X1440255Y933835D03*
X1443956D03*
X1442106Y937024D03*
X1443956Y940213D03*
X1453208Y930646D03*
X1451357Y927457D03*
X1447657Y946591D03*
X1442106Y943402D03*
X1440255Y946591D03*
X1442106Y949780D03*
X1443956Y946591D03*
Y952969D03*
X1442106Y956158D03*
X1451357Y946591D03*
X1453208Y943402D03*
Y949780D03*
Y956158D03*
X1440255Y959347D03*
X1443956D03*
X1447657D03*
X1443956Y965725D03*
X1442106Y962536D03*
Y968914D03*
X1451357Y959347D03*
X1453208Y962536D03*
Y968914D03*
X1445806Y981670D03*
X1443956Y978481D03*
Y972103D03*
X1447657D03*
X1442106Y975292D03*
X1440255Y972103D03*
X1443956Y984859D03*
X1453208Y981670D03*
X1451357Y972103D03*
X1453208Y975292D03*
X1451357Y984859D03*
X1445806Y988048D03*
X1443956Y991237D03*
X1453208Y988048D03*
Y994426D03*
X1451357Y991237D03*
X1453208Y1000804D03*
Y1007182D03*
X1456909Y873245D03*
Y879623D03*
X1458759Y876434D03*
X1468011Y879623D03*
X1455058Y882812D03*
X1462460D03*
X1466161D03*
X1458759D03*
Y889190D03*
X1455058Y895568D03*
X1464310Y892379D03*
X1466161Y895568D03*
X1462460Y889190D03*
X1464310Y898757D03*
X1455058Y901946D03*
X1458759D03*
X1466161D03*
X1462460D03*
X1464310Y905134D03*
X1455058Y908324D03*
X1464310Y911512D03*
X1466161Y908323D03*
X1458759Y914701D03*
X1464310Y917890D03*
Y924268D03*
X1455058Y921079D03*
X1466161D03*
X1455058Y914701D03*
X1462460D03*
X1466161D03*
X1455058Y927457D03*
X1458759D03*
X1466161D03*
X1462460D03*
X1455058Y933835D03*
X1464310Y930646D03*
X1462460Y933835D03*
X1466161D03*
X1458759D03*
X1455058Y940213D03*
X1466161D03*
X1462460Y946591D03*
X1466161D03*
X1458759D03*
X1466161Y952969D03*
X1464310Y956158D03*
X1455058Y952969D03*
X1464310Y943402D03*
X1455058Y946591D03*
X1464310Y949780D03*
X1455058Y965725D03*
X1466161D03*
X1455058Y959347D03*
X1462460D03*
X1466161D03*
X1458759D03*
X1464310Y962536D03*
Y968914D03*
X1460609Y981670D03*
X1455058Y978481D03*
X1466161D03*
X1455058Y972103D03*
X1462460D03*
X1466161D03*
X1458759D03*
X1464310Y975292D03*
X1458759Y984859D03*
X1466161D03*
X1468011Y981670D03*
X1458759Y997615D03*
X1466161D03*
X1460609Y988048D03*
Y994426D03*
X1458759Y991237D03*
X1466161D03*
X1460609Y1000804D03*
X1468011Y988048D03*
Y994426D03*
Y1000804D03*
X1458759Y1003993D03*
X1466161D03*
Y1010371D03*
X1458759D03*
X1460609Y1007182D03*
X1468011D03*
X1479113Y873245D03*
X1469861Y876434D03*
X1479113Y879623D03*
X1482814Y886001D03*
X1480964Y882812D03*
X1469861D03*
X1479113Y886001D03*
X1482814Y892379D03*
X1469861Y889190D03*
X1473562D03*
X1475413Y892379D03*
X1477263Y895568D03*
X1482814Y898757D03*
X1469861Y901946D03*
X1475413Y898757D03*
X1473562Y901946D03*
X1482814Y905134D03*
Y911512D03*
X1477263Y908324D03*
X1475413Y911512D03*
Y905134D03*
X1482814Y917890D03*
X1469861Y914701D03*
X1473562D03*
X1475413Y917890D03*
Y924268D03*
X1482814D03*
X1477263Y921079D03*
X1469861Y933835D03*
X1473562D03*
X1482814Y930646D03*
X1475413D03*
X1477263Y933835D03*
X1473562Y927457D03*
X1469861D03*
X1482814Y937024D03*
X1477263Y940213D03*
X1482814Y943402D03*
Y949780D03*
X1475413Y943402D03*
X1469861Y946591D03*
X1473562D03*
X1475413Y949780D03*
X1482814Y956158D03*
X1477263Y952969D03*
X1475413Y956158D03*
X1482814Y962536D03*
X1469861Y959347D03*
X1473562D03*
X1475413Y962536D03*
X1477263Y965725D03*
X1482814Y968914D03*
X1475413D03*
X1482814Y975292D03*
Y981670D03*
X1469861Y972103D03*
X1473562D03*
X1475413Y975292D03*
X1477263Y978481D03*
X1475413Y981670D03*
X1473562Y984859D03*
X1475413Y1000804D03*
X1482814Y988048D03*
Y994426D03*
X1473562Y991237D03*
Y997615D03*
X1475413Y988048D03*
Y994426D03*
X1482814Y1000804D03*
Y1007182D03*
X1473562Y1003993D03*
Y1010371D03*
X1475413Y1007182D03*
X1492066Y876434D03*
X1490216Y886001D03*
X1484665Y882812D03*
X1488365D03*
X1495767D03*
X1493917Y886001D03*
X1488365Y889190D03*
X1495767D03*
X1490216Y892379D03*
X1495767Y895568D03*
X1490216Y898757D03*
X1488365Y901946D03*
X1495767D03*
X1488365Y908324D03*
X1490216Y911512D03*
X1495767Y908324D03*
Y914701D03*
X1490216Y917890D03*
X1488365Y921079D03*
X1495767D03*
X1490216Y930646D03*
X1495767Y933835D03*
X1488365Y927457D03*
X1495767D03*
X1488365Y940213D03*
X1495767D03*
X1490216Y937024D03*
X1488365Y946591D03*
X1490216Y949780D03*
X1495767Y946591D03*
Y952969D03*
X1490216Y956158D03*
X1488365Y965725D03*
X1495767Y959347D03*
Y965725D03*
X1488365Y959347D03*
X1490216Y968914D03*
X1495767Y972103D03*
X1490216Y975292D03*
X1486515Y981670D03*
X1488365Y978481D03*
X1495767D03*
X1497617Y981670D03*
X1484665Y984859D03*
X1488365D03*
X1495767D03*
X1490216Y988048D03*
X1488365Y997615D03*
X1490216Y994426D03*
X1495767Y991237D03*
Y997615D03*
X1488365Y1003993D03*
X1490216Y1007182D03*
X1495767Y1003993D03*
Y1010371D03*
X1501318Y873245D03*
Y879623D03*
X1510570Y876434D03*
X1508720Y879623D03*
X1501318Y886001D03*
X1510570Y882812D03*
X1508720Y886001D03*
X1503169Y889190D03*
Y895568D03*
X1501318Y892379D03*
X1508720D03*
X1499468Y882812D03*
X1505019Y886001D03*
X1501318Y898757D03*
X1508720D03*
X1503169Y901946D03*
X1501318Y905134D03*
X1508720D03*
X1501318Y911512D03*
X1508720D03*
X1503169Y908323D03*
Y914701D03*
X1501318Y917890D03*
X1508720D03*
X1503169Y921079D03*
X1501318Y924268D03*
X1508720D03*
X1503169Y927457D03*
X1501318Y930646D03*
X1503169Y933835D03*
X1508720Y930646D03*
Y937024D03*
X1503169Y940213D03*
X1501318Y937024D03*
Y943402D03*
X1508720D03*
X1503169Y946591D03*
X1501318Y949780D03*
X1508720D03*
X1503169Y952969D03*
X1501318Y956158D03*
X1508720D03*
X1503169Y959347D03*
Y965725D03*
X1501318Y962536D03*
X1508720D03*
X1501318Y968914D03*
X1508720D03*
X1510570Y984859D03*
X1512421Y981670D03*
X1503169Y972103D03*
X1501318Y975292D03*
X1503169Y978481D03*
X1501318Y981670D03*
X1508720Y975292D03*
Y981670D03*
X1499468Y984859D03*
X1503169D03*
Y991237D03*
X1501318Y988048D03*
X1503169Y997615D03*
X1501318Y994426D03*
X1508720Y988048D03*
Y994426D03*
X1501318Y1000804D03*
X1508720D03*
X1501318Y1007182D03*
X1503169Y1010371D03*
X1508720Y1007182D03*
X1503169Y1003993D03*
X1521673Y876434D03*
X1517972D03*
X1519822Y879623D03*
X1527224D03*
X1516121D03*
X1523523Y873245D03*
X1514271Y882812D03*
Y889190D03*
X1521673Y882812D03*
X1519822Y886001D03*
X1525373Y882812D03*
X1527224Y886001D03*
X1521673Y889190D03*
Y895568D03*
X1527224Y892379D03*
X1516121D03*
X1514271Y901946D03*
Y908324D03*
X1521673Y901946D03*
X1527224Y898757D03*
X1516121D03*
X1527224Y911512D03*
Y905134D03*
X1516121Y911512D03*
X1521673Y908323D03*
X1514271Y921079D03*
X1521673Y914701D03*
X1527224Y917890D03*
X1516121D03*
X1521673Y921079D03*
X1527224Y924268D03*
X1514271Y927457D03*
Y940213D03*
X1516121Y930646D03*
X1521673Y927457D03*
Y933835D03*
X1527224Y930646D03*
X1516121Y937024D03*
X1527224D03*
X1521673Y940213D03*
X1514271Y946591D03*
X1516121Y949780D03*
X1521673Y946591D03*
X1527224Y943402D03*
Y949780D03*
X1521673Y952969D03*
X1527224Y956158D03*
X1516121D03*
X1514271Y959347D03*
Y965725D03*
X1521673Y959347D03*
Y965725D03*
X1527224Y962536D03*
Y968914D03*
X1516121D03*
X1514271Y978481D03*
Y984859D03*
X1521673Y972103D03*
X1523523Y981670D03*
X1521673Y978481D03*
X1527224Y975292D03*
Y981670D03*
X1516121Y975292D03*
X1521673Y984859D03*
X1525373D03*
X1514271Y997615D03*
X1521673Y991237D03*
Y997615D03*
X1527224Y988048D03*
Y994426D03*
X1516121Y988048D03*
Y994426D03*
X1527224Y1000804D03*
X1514271Y1003993D03*
X1516121Y1007182D03*
X1521673Y1003993D03*
Y1010371D03*
X1527224Y1007182D03*
X1529074Y876434D03*
X1538326Y879623D03*
X1530925Y886001D03*
X1529074Y889190D03*
Y895568D03*
X1540176Y882812D03*
X1536476D03*
X1534625Y886001D03*
X1540176Y889190D03*
X1542027Y892379D03*
X1534625D03*
X1529074Y901946D03*
Y908324D03*
X1542027Y898757D03*
X1540176Y901946D03*
X1534625Y898757D03*
X1540176Y908324D03*
X1542027Y911512D03*
X1534625Y905134D03*
Y911512D03*
X1529074Y914701D03*
Y921079D03*
X1542027Y917890D03*
X1534625D03*
X1540176Y921079D03*
X1534625Y924268D03*
X1529074Y927457D03*
Y933835D03*
Y940213D03*
X1540176Y927457D03*
X1542027Y930646D03*
X1534625D03*
X1542027Y937024D03*
X1540176Y940213D03*
X1534625Y937024D03*
X1529074Y946591D03*
Y952969D03*
X1540176Y946591D03*
X1542027Y949780D03*
X1534625Y943402D03*
Y949780D03*
Y956158D03*
X1542027D03*
X1529074Y959347D03*
Y965725D03*
X1540176Y959347D03*
Y965725D03*
X1534625Y962536D03*
X1542027Y968914D03*
X1534625D03*
X1538326Y981670D03*
X1542027Y975292D03*
X1540176Y978481D03*
X1534625Y975292D03*
Y981670D03*
X1536476Y984859D03*
X1540176D03*
X1529074Y972103D03*
Y978481D03*
Y984859D03*
Y991237D03*
Y997615D03*
X1542027Y988048D03*
X1540176Y997615D03*
X1542027Y994426D03*
X1534625Y988048D03*
Y994426D03*
Y1000804D03*
X1542027Y1007182D03*
X1534625D03*
X1529074Y1003993D03*
Y1010371D03*
X1540176Y1003993D03*
X1545728Y873245D03*
X1553129Y879623D03*
X1545728Y886001D03*
X1547578Y882812D03*
X1553129Y886001D03*
X1551279Y882812D03*
X1547578Y889190D03*
Y895568D03*
X1553129Y892379D03*
X1547578Y901946D03*
X1553129Y898757D03*
X1547578Y908324D03*
Y914701D03*
Y921079D03*
Y927457D03*
Y933835D03*
Y940213D03*
Y946591D03*
Y952969D03*
Y959347D03*
Y965725D03*
X1543877Y984859D03*
X1547578Y972103D03*
Y978481D03*
Y984859D03*
X1545728Y988048D03*
X1547578Y991237D03*
Y997615D03*
Y1003993D03*
Y1010371D03*
G54D59*
X928740Y321654D03*
G54D34*
X250326Y185236D03*
X368437D03*
G54D60*
X916546Y309460D03*
X911495Y321654D03*
X916546Y333848D03*
X928740Y304409D03*
Y338899D03*
X940934Y309460D03*
X945985Y321654D03*
X940934Y333848D03*
G54D71*
X1766929Y1714960D03*
G54D11*
X19685Y-29134D03*
Y1803261D03*
X2081889Y-29134D03*
Y1803261D03*
G54D27*
X117933Y605376D03*
X763602Y605413D03*
X1094076Y605378D03*
X1739745Y605411D03*
G54D18*
X44000Y154200D03*
X31818Y1424257D03*
X441043Y1672205D03*
Y1718465D03*
X1416437Y1672205D03*
Y1718465D03*
X1800449Y126194D03*
X1804650Y1667292D03*
G54D52*
X791280Y1704890D03*
X1066280D03*
G54D32*
X230905Y1644448D03*
Y1658621D03*
Y1672795D03*
Y1686968D03*
Y1701141D03*
Y1715314D03*
Y1729488D03*
X246653Y1644448D03*
X238779Y1648385D03*
X246653Y1658621D03*
X238779Y1662558D03*
X246653Y1672795D03*
X238779Y1676732D03*
X246653Y1686968D03*
X238779Y1690905D03*
X246653Y1701141D03*
X238779Y1705078D03*
X246653Y1715314D03*
X238779Y1719251D03*
X246653Y1729488D03*
X238779Y1733425D03*
X254527Y1648385D03*
Y1662558D03*
Y1676732D03*
Y1690905D03*
Y1705078D03*
Y1719251D03*
Y1733425D03*
X262401Y1644448D03*
X270275Y1648385D03*
X262401Y1658621D03*
X270275Y1662558D03*
X262401Y1672795D03*
X270275Y1676732D03*
X262401Y1686968D03*
X270275Y1690905D03*
X262401Y1701141D03*
X270275Y1705078D03*
X262401Y1715314D03*
X270275Y1719251D03*
X262401Y1729488D03*
X270275Y1733425D03*
X278149Y1644448D03*
X286023Y1648385D03*
X278149Y1658621D03*
X286023Y1662558D03*
X278149Y1672795D03*
X286023Y1676732D03*
X278149Y1686968D03*
X286023Y1690905D03*
X278149Y1701141D03*
X286023Y1705078D03*
X278149Y1715314D03*
X286023Y1719251D03*
X278149Y1729488D03*
X286023Y1733425D03*
X297835Y1672795D03*
X305709Y1676732D03*
X297835Y1686968D03*
X305709Y1690905D03*
X297835Y1701141D03*
X305709Y1705078D03*
X297835Y1715314D03*
X305709Y1719251D03*
X297835Y1729488D03*
X305709Y1733425D03*
X313583Y1672795D03*
X321457Y1676732D03*
X313583Y1686968D03*
X321457Y1690905D03*
X313583Y1701141D03*
X321457Y1705078D03*
X313583Y1715314D03*
X321457Y1719251D03*
X313583Y1729488D03*
X321457Y1733425D03*
X329331Y1672795D03*
Y1686968D03*
Y1701141D03*
Y1715314D03*
Y1729488D03*
X345079Y1672795D03*
X337205Y1676732D03*
X345079Y1686968D03*
X337205Y1690905D03*
X345079Y1701141D03*
X337205Y1705078D03*
X345079Y1715314D03*
X337205Y1719251D03*
X345079Y1729488D03*
X337205Y1733425D03*
X352953Y1676732D03*
Y1690905D03*
Y1705078D03*
Y1719251D03*
Y1733425D03*
X495078Y1672795D03*
Y1686968D03*
Y1701141D03*
Y1715314D03*
Y1729488D03*
X510826Y1672795D03*
X502952Y1676732D03*
X510826Y1686968D03*
X502952Y1690905D03*
X510826Y1701141D03*
X502952Y1705078D03*
X510826Y1715314D03*
X502952Y1719251D03*
X510826Y1729488D03*
X502952Y1733425D03*
X526574Y1672795D03*
X518700Y1676732D03*
X526574Y1686968D03*
X518700Y1690905D03*
X526574Y1701141D03*
X518700Y1705078D03*
X526574Y1715314D03*
X518700Y1719251D03*
X526574Y1729488D03*
X518700Y1733425D03*
X542322Y1672795D03*
X534448Y1676732D03*
X542322Y1686968D03*
X534448Y1690905D03*
X542322Y1701141D03*
X534448Y1705078D03*
X542322Y1715314D03*
X534448Y1719251D03*
X542322Y1729488D03*
X534448Y1733425D03*
X550196Y1676732D03*
Y1690905D03*
Y1705078D03*
Y1719251D03*
Y1733425D03*
X562008Y1672795D03*
X569882Y1676732D03*
X562008Y1686968D03*
X569882Y1690905D03*
X562008Y1701141D03*
X569882Y1705078D03*
X562008Y1715314D03*
X569882Y1719251D03*
X562008Y1729488D03*
X569882Y1733425D03*
X577756Y1672795D03*
X585630Y1676732D03*
X577756Y1686968D03*
X585630Y1690905D03*
X577756Y1701141D03*
X585630Y1705078D03*
X577756Y1715314D03*
X585630Y1719251D03*
X577756Y1729488D03*
X585630Y1733425D03*
X593504Y1672795D03*
X601378Y1676732D03*
X593504Y1686968D03*
X601378Y1690905D03*
X593504Y1701141D03*
X601378Y1705078D03*
X593504Y1715314D03*
X601378Y1719251D03*
X593504Y1729488D03*
X601378Y1733425D03*
X609252Y1672795D03*
X617126Y1676732D03*
X609252Y1686968D03*
X617126Y1690905D03*
X609252Y1701141D03*
X617126Y1705078D03*
X609252Y1715314D03*
X617126Y1719251D03*
X609252Y1729488D03*
X617126Y1733425D03*
X1238778Y1672795D03*
Y1686968D03*
Y1701141D03*
Y1715314D03*
Y1729488D03*
X1254526Y1672795D03*
X1246652Y1676732D03*
X1254526Y1686968D03*
X1246652Y1690905D03*
X1254526Y1701141D03*
X1246652Y1705078D03*
X1254526Y1715314D03*
X1246652Y1719251D03*
X1254526Y1729488D03*
X1246652Y1733425D03*
X1270274Y1672795D03*
X1262400Y1676732D03*
X1270274Y1686968D03*
X1262400Y1690905D03*
X1270274Y1701141D03*
X1262400Y1705078D03*
X1270274Y1715314D03*
X1262400Y1719251D03*
X1270274Y1729488D03*
X1262400Y1733425D03*
X1286022Y1672795D03*
X1278148Y1676732D03*
X1286022Y1686968D03*
X1278148Y1690905D03*
X1286022Y1701141D03*
X1278148Y1705078D03*
X1286022Y1715314D03*
X1278148Y1719251D03*
X1286022Y1729488D03*
X1278148Y1733425D03*
X1305708Y1672795D03*
Y1686968D03*
X1293896Y1676732D03*
X1305708Y1701141D03*
X1293896Y1690905D03*
X1305708Y1715314D03*
X1293896Y1705078D03*
X1305708Y1729488D03*
X1293896Y1719251D03*
Y1733425D03*
X1313582Y1676732D03*
Y1690905D03*
Y1705078D03*
Y1719251D03*
Y1733425D03*
X1321456Y1672795D03*
X1329330Y1676732D03*
X1321456Y1686968D03*
X1329330Y1690905D03*
X1321456Y1701141D03*
X1329330Y1705078D03*
X1321456Y1715314D03*
X1329330Y1719251D03*
X1321456Y1729488D03*
X1329330Y1733425D03*
X1337204Y1672795D03*
X1345078Y1676732D03*
X1337204Y1686968D03*
X1345078Y1690905D03*
X1337204Y1701141D03*
X1345078Y1705078D03*
X1337204Y1715314D03*
X1345078Y1719251D03*
X1337204Y1729488D03*
X1345078Y1733425D03*
X1352952Y1672795D03*
X1360826Y1676732D03*
X1352952Y1686968D03*
X1360826Y1690905D03*
X1352952Y1701141D03*
X1360826Y1705078D03*
X1352952Y1715314D03*
X1360826Y1719251D03*
X1352952Y1729488D03*
X1360826Y1733425D03*
X1502952Y1672795D03*
X1510826Y1676732D03*
X1502952Y1686968D03*
X1510826Y1690905D03*
X1502952Y1701141D03*
X1510826Y1705078D03*
X1502952Y1715314D03*
X1510826Y1719251D03*
X1502952Y1729488D03*
X1510826Y1733425D03*
X1518700Y1672795D03*
X1526574Y1676732D03*
X1518700Y1686968D03*
X1526574Y1690905D03*
X1518700Y1701141D03*
X1526574Y1705078D03*
X1518700Y1715314D03*
X1526574Y1719251D03*
X1518700Y1729488D03*
X1526574Y1733425D03*
X1534448Y1672795D03*
X1542322Y1676732D03*
X1534448Y1686968D03*
X1542322Y1690905D03*
X1534448Y1701141D03*
X1542322Y1705078D03*
X1534448Y1715314D03*
X1542322Y1719251D03*
X1534448Y1729488D03*
X1542322Y1733425D03*
X1550196Y1672795D03*
X1558070Y1676732D03*
X1550196Y1686968D03*
X1558070Y1690905D03*
X1550196Y1701141D03*
X1558070Y1705078D03*
X1550196Y1715314D03*
X1558070Y1719251D03*
X1550196Y1729488D03*
X1558070Y1733425D03*
X1569882Y1672795D03*
Y1686968D03*
Y1701141D03*
Y1715314D03*
Y1729488D03*
X1585630Y1672795D03*
X1577756Y1676732D03*
X1585630Y1686968D03*
X1577756Y1690905D03*
X1585630Y1701141D03*
X1577756Y1705078D03*
X1585630Y1715314D03*
X1577756Y1719251D03*
X1585630Y1729488D03*
X1577756Y1733425D03*
X1601378Y1672795D03*
X1593504Y1676732D03*
X1601378Y1686968D03*
X1593504Y1690905D03*
X1601378Y1701141D03*
X1593504Y1705078D03*
X1601378Y1715314D03*
X1593504Y1719251D03*
X1601378Y1729488D03*
X1593504Y1733425D03*
X1617126Y1672795D03*
X1609252Y1676732D03*
X1617126Y1686968D03*
X1609252Y1690905D03*
X1617126Y1701141D03*
X1609252Y1705078D03*
X1617126Y1715314D03*
X1609252Y1719251D03*
X1617126Y1729488D03*
X1609252Y1733425D03*
X1625000Y1676732D03*
Y1690905D03*
Y1705078D03*
Y1719251D03*
Y1733425D03*
G54D45*
X441043Y1698268D03*
X1416437D03*
G54D54*
X805690Y204724D03*
X1057659D03*
G54D15*
X17292Y290137D03*
X35689Y301357D03*
X33822Y1462075D03*
Y1459075D03*
Y1456075D03*
X36822D03*
Y1459075D03*
Y1462075D03*
X33822Y1465075D03*
X36822D03*
X37671Y1515214D03*
X34704Y1515235D03*
X47892Y290137D03*
X49400Y384392D03*
X49250Y396332D03*
X47618Y412613D03*
X47619Y421655D03*
X42822Y1462075D03*
Y1459075D03*
Y1456075D03*
Y1465075D03*
X47138Y1513072D03*
X47089Y1510268D03*
X50642Y1557451D03*
X45633Y1592481D03*
X50133D03*
X38426Y1654079D03*
X41427Y1668587D03*
X38426Y1659059D03*
X44583Y1672433D03*
Y1677613D03*
X66289Y301357D03*
X61340Y384362D03*
X61250Y396142D03*
X56542Y589521D03*
X66822Y1462075D03*
Y1459075D03*
Y1456075D03*
X57822Y1462075D03*
Y1459075D03*
Y1456075D03*
X66822Y1465075D03*
X57822D03*
X63990Y1562177D03*
Y1567627D03*
Y1564727D03*
X63915Y1558805D03*
Y1556254D03*
X63990Y1570427D03*
X61225Y1570283D03*
X58564Y1570209D03*
X65767Y1609405D03*
X59767D03*
X53767D03*
X65767Y1615405D03*
X65943Y1621405D03*
X59767D03*
X53767Y1615405D03*
Y1621405D03*
X59427Y1644410D03*
X53648Y1653088D03*
X77790Y520108D03*
X77733Y526764D03*
X77790Y537808D03*
X77733Y544464D03*
X81822Y1462075D03*
Y1456075D03*
Y1465075D03*
X68427Y1644410D03*
X73427D03*
X80000Y1702450D03*
X79500Y1720450D03*
X88722Y1462075D03*
X85722D03*
X88722Y1456075D03*
X85722D03*
X88722Y1465075D03*
X85722D03*
X85621Y1551969D03*
X82974Y1552051D03*
X83340Y1654353D03*
X89466Y1663138D03*
Y1667127D03*
X83340Y1659333D03*
X85395Y1670331D03*
Y1675311D03*
X102096Y1555442D03*
X100439Y1667361D03*
X106573Y1660235D03*
X100915Y1679564D03*
X105069Y1685763D03*
X102243Y1682263D03*
Y1689263D03*
X120016Y300654D03*
Y320631D03*
X114973Y1660235D03*
X113469Y1685763D03*
X133120Y1454751D03*
X137120D03*
X141028Y1454705D03*
X140775Y1638035D03*
X146982Y526997D03*
X145028Y1454705D03*
X152449Y1623572D03*
Y1628528D03*
X151611Y1663933D03*
X159427Y1687843D03*
X151510Y1676811D03*
X163113Y1477590D03*
Y1499490D03*
X164730Y1521561D03*
X161239Y1636147D03*
Y1631191D03*
X162995Y1661377D03*
X160011Y1663933D03*
X163003Y1666462D03*
X159910Y1676811D03*
X162848Y1679357D03*
X162840Y1674272D03*
X187250Y129674D03*
X189410Y388180D03*
X200754Y595174D03*
Y603274D03*
X192951Y1560498D03*
X196081Y1639349D03*
X195504Y1645359D03*
X203754Y595174D03*
Y603274D03*
X207968Y1653130D03*
X203800Y1646832D03*
X272242Y523076D03*
X276085Y1509654D03*
X270720Y1531073D03*
X273220D03*
X275720D03*
X281147Y521803D03*
X280621Y1478082D03*
X291175Y1477590D03*
X283221Y1484772D03*
Y1479992D03*
X278021Y1484772D03*
Y1479992D03*
X283221Y1493392D03*
X280621Y1491482D03*
X278021Y1493392D03*
X291175Y1499490D03*
X283221Y1498172D03*
X278021D03*
X291619Y1536606D03*
X291593Y1529402D03*
Y1531902D03*
X284800Y1526750D03*
X277572Y1536763D03*
X280072D03*
X291619Y1539106D03*
X292792Y1521561D03*
X297323Y1651172D03*
X318660Y24989D03*
X307255Y1641150D03*
X339914Y165170D03*
X384668Y471926D03*
X410701Y99148D03*
X396977Y216685D03*
X399625Y479119D03*
X408683Y1478082D03*
Y1491482D03*
X406083Y1479992D03*
Y1484772D03*
Y1493392D03*
Y1498172D03*
X404147Y1509654D03*
X398782Y1531073D03*
X401282D03*
X403782D03*
X411800Y220200D03*
X413425Y479042D03*
X411283Y1479992D03*
Y1484772D03*
Y1493392D03*
Y1498172D03*
X412862Y1526750D03*
X436090Y120007D03*
X429997Y166400D03*
X441997D03*
X439299Y220046D03*
X427225Y478965D03*
X440159Y966741D03*
Y981741D03*
Y974241D03*
X427286Y1477590D03*
Y1499490D03*
X428746Y1521727D03*
X427730Y1536606D03*
X427704Y1531902D03*
Y1529402D03*
X427730Y1539106D03*
X428500Y1650000D03*
X465997Y166400D03*
X457997D03*
X466041Y1664913D03*
X483467Y209755D03*
X514418Y145171D03*
Y149171D03*
Y153171D03*
X513360Y169190D03*
X511771Y199576D03*
X506261Y865338D03*
X522418Y153171D03*
X516572Y865327D03*
X530418Y145171D03*
Y149171D03*
Y153171D03*
X531280Y210922D03*
X544794Y1478082D03*
Y1491482D03*
X542194Y1479992D03*
Y1484772D03*
Y1493392D03*
X537694Y1504872D03*
X542194Y1498172D03*
X543759Y1536882D03*
X540193Y1531073D03*
X537693D03*
X535193D03*
X541259Y1536882D03*
X555348Y1477590D03*
X547394Y1479992D03*
Y1484772D03*
Y1493392D03*
X555348Y1499490D03*
X547394Y1498172D03*
X556965Y1521561D03*
X556642Y1529389D03*
X554715Y1531564D03*
X550540Y1526910D03*
X556197Y1536687D03*
Y1539187D03*
X561248Y106985D03*
Y100399D03*
X562208Y387227D03*
Y376427D03*
Y401158D03*
X568433Y415846D03*
X581985Y379577D03*
Y390377D03*
Y404308D03*
X588723Y423949D03*
X593975Y164440D03*
X598208Y387227D03*
Y376427D03*
X599164Y432209D03*
X604718Y257562D03*
X617985Y379577D03*
Y398578D03*
Y390377D03*
X610935Y409996D03*
X615075Y443000D03*
X633882Y587488D03*
X646285Y297171D03*
X640317Y391085D03*
X634566Y407848D03*
X639482Y587488D03*
X645446Y587300D03*
X653821Y90326D03*
X653013Y443200D03*
X664170Y445711D03*
X651046Y587300D03*
X672856Y1478082D03*
Y1491482D03*
X675112Y1479602D03*
X675456Y1484772D03*
Y1493392D03*
X670256Y1479992D03*
Y1484772D03*
Y1493392D03*
X665756Y1504872D03*
X675456Y1498172D03*
X670256D03*
X680710Y1520284D03*
X683674Y1522287D03*
X695796Y418358D03*
X708395Y430957D03*
X702095Y421508D03*
X698946Y437256D03*
X702095Y449854D03*
X708395Y474971D03*
X698946Y468672D03*
X695796Y487570D03*
X706172Y1552082D03*
X698003Y1684692D03*
X711544Y421508D03*
X720993Y443555D03*
Y446705D03*
X717843D03*
Y440405D03*
X720993Y449854D03*
Y462373D03*
Y459223D03*
Y456074D03*
X717843Y459223D03*
Y465523D03*
X711544Y484420D03*
X722141Y1405912D03*
X721916Y1414339D03*
Y1416939D03*
X722141Y1408412D03*
X721916Y1428989D03*
Y1431589D03*
X733512Y427807D03*
X727292Y421508D03*
X736661Y443555D03*
X733512Y446705D03*
Y443555D03*
X727292Y446705D03*
Y443555D03*
X724143D03*
Y462373D03*
X727292D03*
X733512Y459223D03*
X727292D03*
X733512Y462373D03*
X736661D03*
X727292Y474971D03*
X736661Y484420D03*
X724143D03*
X752409Y421508D03*
X739811Y443555D03*
Y446705D03*
X742961Y440405D03*
X739811Y449854D03*
Y456074D03*
Y459223D03*
Y462373D03*
X742961Y465523D03*
X752409Y484420D03*
X746082Y1506931D03*
X751030Y1668583D03*
X765008Y418358D03*
X758709Y437256D03*
X755559Y456074D03*
X758709Y468672D03*
X765008Y487570D03*
X758179Y1482049D03*
X758163Y1526223D03*
X758179Y1534963D03*
X779014Y1343262D03*
Y1340062D03*
X782014D03*
Y1337062D03*
Y1343262D03*
X780000Y1353500D03*
X779014Y1346462D03*
Y1349862D03*
X782014Y1346462D03*
Y1349862D03*
X780000Y1357500D03*
Y1363500D03*
Y1360500D03*
X780111Y1405366D03*
X782758Y1405249D03*
X795421Y1331257D03*
X785014Y1350862D03*
X804099Y1333835D03*
X801171Y1343278D03*
X810986Y1361684D03*
X819115Y115223D03*
X824499Y145198D03*
X820405Y311830D03*
X831115Y115223D03*
X829115Y150273D03*
X838670Y1518558D03*
X841310Y1518608D03*
X838630Y1521538D03*
X841270Y1521588D03*
X854578Y99651D03*
X856397Y339751D03*
X847007Y1521458D03*
X844367Y1521408D03*
Y1518784D03*
X847007Y1518834D03*
X855853Y1521308D03*
X853213Y1521258D03*
X850146Y1521261D03*
Y1518637D03*
X853213Y1518634D03*
X855853Y1518684D03*
X860152Y328399D03*
X865132D03*
X861377Y339751D03*
X872986Y753451D03*
X858581Y1518568D03*
X858567Y1521416D03*
X876133Y73580D03*
Y95580D03*
Y117580D03*
X919272Y989932D03*
X921289Y1663187D03*
X942779Y277731D03*
X936693Y1462328D03*
X939507Y1462497D03*
X945195Y1459453D03*
X942056Y1459650D03*
X939416Y1459600D03*
Y1456976D03*
X942056Y1457026D03*
X945195Y1456829D03*
X951099Y632206D03*
X956693Y1459805D03*
X953630Y1456760D03*
X958383Y1462447D03*
X950902Y1459500D03*
X948262Y1459450D03*
X953616Y1459608D03*
X948262Y1456826D03*
X950902Y1456876D03*
X953520Y1567570D03*
X950520D03*
X959520D03*
X956520D03*
X953520Y1582570D03*
X950520D03*
Y1579570D03*
X953520D03*
Y1576570D03*
X950520D03*
X953520Y1573570D03*
X950520D03*
Y1570570D03*
X953520D03*
X959520Y1582570D03*
X956520D03*
Y1579570D03*
X959520D03*
Y1576570D03*
X956520D03*
X959520Y1573570D03*
X956520D03*
Y1570570D03*
X959520D03*
X953520Y1588570D03*
X950520D03*
Y1585570D03*
X953520D03*
X959520Y1588570D03*
X956520D03*
Y1585570D03*
X959520D03*
X977150Y1052684D03*
X966000Y1300000D03*
X968500D03*
X971000D03*
X988160Y1567710D03*
X991160D03*
X985160D03*
X988160Y1582710D03*
X991160D03*
X985160D03*
Y1579710D03*
X991160D03*
X988160D03*
X991160Y1570710D03*
X988160D03*
Y1573710D03*
X991160D03*
X988160Y1576710D03*
X991160D03*
X985160Y1570710D03*
Y1573710D03*
Y1576710D03*
X988160Y1588710D03*
X991160D03*
X985160D03*
Y1585710D03*
X991160D03*
X988160D03*
X1014206Y510304D03*
X1013306Y526146D03*
X1016750Y1567710D03*
X1019750D03*
X1016750Y1576710D03*
Y1573710D03*
Y1570710D03*
X1019750Y1576710D03*
Y1573710D03*
Y1570710D03*
Y1579710D03*
X1016750D03*
Y1582710D03*
X1019750D03*
Y1585710D03*
X1016750D03*
Y1588710D03*
X1019750D03*
X1022750Y1567710D03*
Y1576710D03*
Y1573710D03*
Y1570710D03*
Y1579710D03*
Y1582710D03*
Y1585710D03*
Y1588710D03*
X1045254Y521074D03*
X1037212Y510940D03*
X1048219Y1567883D03*
X1051219D03*
X1048219Y1576883D03*
Y1573883D03*
Y1570883D03*
X1051219Y1576883D03*
Y1573883D03*
Y1570883D03*
Y1579883D03*
X1048219D03*
Y1582883D03*
X1051219D03*
Y1585883D03*
X1048219D03*
Y1588883D03*
X1051219D03*
X1055934Y385488D03*
X1054219Y1567883D03*
Y1576883D03*
Y1573883D03*
Y1570883D03*
Y1579883D03*
Y1582883D03*
Y1585883D03*
Y1588883D03*
X1068143Y383688D03*
X1073204Y383417D03*
X1083819Y353094D03*
X1119067Y1551457D03*
X1133765Y1572102D03*
X1170986Y1510590D03*
Y1532490D03*
X1183354Y77685D03*
X1176972Y86788D03*
X1200824Y1593498D03*
X1192612Y1680410D03*
X1207954Y1680419D03*
X1209879Y1700359D03*
X1230094Y314216D03*
X1226094Y305216D03*
X1216875Y1705826D03*
X1216738Y1720861D03*
X1277732Y236594D03*
Y246594D03*
Y241594D03*
Y251594D03*
X1288494Y1511082D03*
X1285894Y1512992D03*
Y1517772D03*
X1288494Y1524482D03*
X1285894Y1531172D03*
Y1526392D03*
X1283958Y1542654D03*
X1278593Y1564073D03*
X1281093D03*
X1283593D03*
X1287945Y1569763D03*
X1285445D03*
X1302365Y1418702D03*
X1292522Y1421596D03*
X1303943Y1430729D03*
X1299048Y1510590D03*
X1291094Y1512992D03*
Y1517772D03*
X1299048Y1532490D03*
X1291094Y1531172D03*
Y1526392D03*
X1299466Y1562402D03*
Y1564902D03*
X1292673Y1559750D03*
X1299492Y1572106D03*
Y1569606D03*
X1307766Y563013D03*
X1308700Y590300D03*
X1317266Y592522D03*
X1308700Y587800D03*
X1313109Y1195398D03*
Y1200898D03*
X1325366Y592522D03*
X1339488Y1202295D03*
X1340483Y1209006D03*
X1336861Y1222119D03*
X1350809Y1202323D03*
X1368137Y1222298D03*
Y1227798D03*
X1383800Y1685398D03*
X1406655Y1564073D03*
X1409155D03*
X1399940Y1637127D03*
X1414619Y244450D03*
X1416301Y966740D03*
Y981740D03*
Y974240D03*
X1416556Y1511082D03*
X1419156Y1512992D03*
Y1517772D03*
X1413956Y1512992D03*
Y1517772D03*
X1416556Y1524482D03*
X1419156Y1531172D03*
Y1526392D03*
X1413956Y1531172D03*
Y1526392D03*
X1412020Y1542654D03*
X1420735Y1559750D03*
X1411655Y1564073D03*
X1435160Y1510590D03*
Y1532490D03*
X1435578Y1564902D03*
Y1562402D03*
X1436940Y1554277D03*
X1435604Y1572106D03*
Y1569606D03*
X1445985Y116953D03*
X1441390Y163944D03*
X1442993Y176204D03*
X1462405Y61563D03*
X1461242Y128242D03*
X1463017Y136368D03*
X1465832Y535330D03*
X1542767Y1564073D03*
X1552668Y1511082D03*
X1555268Y1512992D03*
Y1517772D03*
X1550068Y1512992D03*
Y1517772D03*
X1552668Y1524482D03*
X1555268Y1531172D03*
Y1526392D03*
X1550068Y1531172D03*
Y1526392D03*
X1548132Y1542654D03*
X1556847Y1559750D03*
X1545267Y1564073D03*
X1547767D03*
X1552118Y1569763D03*
X1549618D03*
X1563222Y1510590D03*
Y1532490D03*
X1564581Y1562316D03*
X1562613Y1564816D03*
X1564128Y1572225D03*
X1562621Y1569761D03*
X1602270Y229530D03*
X1629597Y221842D03*
X1619909Y306746D03*
X1643283Y1425541D03*
X1648337Y1451313D03*
X1654419Y233062D03*
X1655383Y1425541D03*
X1656997Y1708609D03*
Y1723759D03*
X1665100Y156762D03*
Y166762D03*
X1673223Y220857D03*
X1673630Y1533092D03*
Y1537872D03*
X1684925Y118762D03*
Y149762D03*
Y161762D03*
Y153762D03*
X1684942Y234000D03*
X1683587Y1433425D03*
X1680430Y1511198D03*
X1682760Y1512169D03*
X1683330Y1517772D03*
X1678130Y1512992D03*
Y1517772D03*
X1680730Y1524482D03*
X1683330Y1531172D03*
Y1526392D03*
X1678130Y1531172D03*
Y1526392D03*
X1688584Y1553284D03*
X1691548Y1555287D03*
X1686857Y1683918D03*
X1684733Y1698952D03*
X1695102Y1698947D03*
X1691357Y1688418D03*
X1691997Y1708609D03*
X1733083Y654034D03*
X1737606Y1539807D03*
X1736579Y1587480D03*
X1723929Y1654456D03*
X1723963Y1658965D03*
Y1663465D03*
Y1667965D03*
X1731117Y1705115D03*
Y1720265D03*
X1741329Y1482405D03*
Y1485405D03*
Y1491405D03*
Y1488405D03*
X1740058Y1537419D03*
X1744866Y1539589D03*
X1742165Y1539620D03*
X1740979Y1577905D03*
X1743681Y1626750D03*
X1750681D03*
X1747181D03*
X1743481Y1616550D03*
X1750481D03*
X1746981D03*
X1747963Y1641965D03*
X1764029Y1485405D03*
Y1482405D03*
Y1491405D03*
Y1488405D03*
X1756329Y1485405D03*
Y1482405D03*
Y1491405D03*
Y1488405D03*
X1769054Y1585705D03*
X1753079Y1596650D03*
Y1606550D03*
Y1603050D03*
Y1600150D03*
X1761839Y1634223D03*
X1757763Y1643365D03*
X1761494Y1661947D03*
X1779029Y1482405D03*
Y1485405D03*
Y1491405D03*
Y1488405D03*
X1772904Y1585005D03*
X1773863Y1661465D03*
X1774940Y1669037D03*
X1773738Y1672965D03*
X1773963Y1680965D03*
X1793070Y25001D03*
X1788029Y1485405D03*
Y1482405D03*
Y1491405D03*
Y1488405D03*
X1789379Y1588478D03*
X1805525Y146716D03*
X1812029Y1485405D03*
Y1482405D03*
X1803029D03*
Y1485405D03*
X1812029Y1491405D03*
Y1488405D03*
X1803029Y1491405D03*
Y1488405D03*
X1801789Y1536742D03*
X1807408Y1539223D03*
X1810408D03*
X1812078Y1596725D03*
X1812003Y1607375D03*
Y1603875D03*
X1812078Y1600225D03*
X1809179Y1616550D03*
X1809254Y1613775D03*
X1812570Y159275D03*
X1827029Y1488405D03*
Y1491405D03*
Y1485405D03*
Y1482405D03*
X1815344Y1539373D03*
X1818344D03*
X1823112Y1538659D03*
X1812679Y1616550D03*
X1816179D03*
X1812754Y1613775D03*
X1816254D03*
X1837641Y159275D03*
X1840700Y326201D03*
Y348201D03*
Y370201D03*
Y392201D03*
Y414201D03*
Y436201D03*
Y458201D03*
Y480201D03*
Y502201D03*
Y524201D03*
Y546201D03*
Y568201D03*
Y590201D03*
Y656201D03*
Y678201D03*
Y700201D03*
Y722201D03*
Y744201D03*
Y766201D03*
Y788201D03*
Y810201D03*
Y832201D03*
Y854201D03*
Y876201D03*
Y898201D03*
Y920201D03*
Y942201D03*
Y964201D03*
Y986201D03*
Y1008201D03*
Y1030201D03*
Y1052201D03*
Y1074201D03*
Y1096201D03*
Y1118201D03*
Y1140201D03*
Y1162201D03*
Y1184201D03*
Y1206201D03*
Y1228201D03*
Y1250201D03*
Y1272201D03*
Y1294201D03*
Y1316201D03*
Y1338201D03*
Y1404201D03*
Y1448201D03*
Y1470201D03*
Y1492201D03*
Y1514201D03*
Y1536201D03*
Y1558201D03*
Y1580201D03*
X1828889Y1622578D03*
Y1644578D03*
Y1666578D03*
Y1688578D03*
X1854479Y66461D03*
Y110461D03*
Y132461D03*
Y154461D03*
X1847866Y159124D03*
X1854479Y176461D03*
Y198461D03*
Y220461D03*
Y242461D03*
Y264461D03*
Y286461D03*
G54D58*
X922441Y154311D03*
Y243799D03*
G54D12*
X21569Y49379D03*
X21345Y387760D03*
X21309Y395712D03*
X36500Y323500D03*
X33686Y383944D03*
X27309Y383926D03*
X29962Y401000D03*
X36524Y398013D03*
X26771Y398811D03*
X30680Y438142D03*
X35852Y664480D03*
Y686410D03*
Y683910D03*
X43569Y49379D03*
X45423Y197224D03*
Y212224D03*
Y202224D03*
Y207224D03*
X40000Y323500D03*
X55190Y360862D03*
X42809D03*
X46834D03*
X39410Y384582D03*
X39226Y395346D03*
X53825Y421746D03*
X49848Y524210D03*
X49889Y531149D03*
X50880Y1421963D03*
X52405Y1514835D03*
X49405D03*
X52405Y1511986D03*
X49405D03*
X52330Y1509137D03*
X49330D03*
X52796Y1526469D03*
X52905Y1523335D03*
X47760Y1529506D03*
X65347Y66847D03*
X60367D03*
X65347Y71839D03*
X60367D03*
X58457Y69340D03*
X67575Y287500D03*
X56620Y303500D03*
X64150Y434972D03*
X53800Y435451D03*
X54762Y444993D03*
X56800Y524220D03*
X56719Y531120D03*
X64923Y795316D03*
Y832127D03*
Y868938D03*
Y905750D03*
Y942561D03*
Y1089805D03*
Y1126616D03*
Y1163427D03*
Y1200238D03*
Y1237049D03*
X58349Y1412731D03*
X55755Y1511885D03*
X55905Y1514835D03*
X57281Y1523287D03*
X66081D03*
X59881D03*
X63481D03*
X55789Y1509224D03*
X57281Y1526394D03*
X66081D03*
X65281Y1529501D03*
X59881Y1526394D03*
X63481D03*
X62681Y1529501D03*
X64235Y1533150D03*
X61755D03*
X59275D03*
X67196Y1552869D03*
X64235Y1538750D03*
X61755D03*
X59275D03*
X63802Y1579997D03*
X58602D03*
X61302D03*
X75928Y3001D03*
X81159Y17045D03*
X72087Y25977D03*
X74087Y23981D03*
X79043D03*
X81043Y25977D03*
X79192Y19541D03*
X81159Y22037D03*
X73025Y37106D03*
X80111D03*
X73025Y48720D03*
X80111D03*
X69453Y75343D03*
X82367Y71839D03*
X80457Y69340D03*
X82367Y66847D03*
X76347Y72850D03*
X71367D03*
X76347Y77842D03*
X71367D03*
X71779Y157194D03*
Y161194D03*
X71772Y421746D03*
X68365Y443677D03*
X80915Y756766D03*
X73873D03*
Y760266D03*
X69323Y776911D03*
X80915Y763766D03*
X80015Y786950D03*
X69323Y783604D03*
X81065Y791970D03*
X80015Y796989D03*
X69323Y807029D03*
Y813722D03*
Y820415D03*
X80015Y823761D03*
Y833800D03*
X81065Y828781D03*
X69323Y843840D03*
Y850533D03*
X80015Y860572D03*
X81065Y865592D03*
X69323Y857226D03*
X80015Y870611D03*
X69323Y880651D03*
Y887344D03*
Y894037D03*
X80015Y907423D03*
Y897383D03*
X81065Y902403D03*
X69323Y924155D03*
Y917462D03*
X81065Y939214D03*
X80015Y934194D03*
X69323Y930848D03*
X80015Y944234D03*
X69323Y954273D03*
Y960966D03*
Y967659D03*
Y974352D03*
Y981045D03*
Y987737D03*
Y994430D03*
Y1004470D03*
Y1034588D03*
Y1041281D03*
Y1047974D03*
Y1054667D03*
Y1071399D03*
Y1061360D03*
X80015Y1081438D03*
X81065Y1086458D03*
X69323Y1078092D03*
X80015Y1091478D03*
X69323Y1101517D03*
X80015Y1118249D03*
X69323Y1114903D03*
Y1108210D03*
X80015Y1128289D03*
X81065Y1123269D03*
X69323Y1145021D03*
Y1138328D03*
X80015Y1165100D03*
X81065Y1160080D03*
X80015Y1155060D03*
X69323Y1151714D03*
Y1175139D03*
Y1181832D03*
X80015Y1191871D03*
X69323Y1188525D03*
X81065Y1196891D03*
X80015Y1201911D03*
X69323Y1211950D03*
Y1218643D03*
X80015Y1238722D03*
Y1228682D03*
X81065Y1233702D03*
X69323Y1225336D03*
Y1248761D03*
Y1255454D03*
X76378Y1406622D03*
X74325Y1523303D03*
X68870Y1523147D03*
X71359Y1523186D03*
X81868Y1511285D03*
X81405Y1516835D03*
X81905Y1513835D03*
X81405Y1519835D03*
Y1522835D03*
X78808Y1522839D03*
X81905Y1508698D03*
X74440Y1526385D03*
X74462Y1529665D03*
X82696Y1529095D03*
X76806Y1593265D03*
X80400Y1602225D03*
X86139Y17045D03*
X95333D03*
X88148Y19541D03*
X95216Y25977D03*
X86260D03*
X93216Y23981D03*
X88260D03*
X86139Y22037D03*
X95333D03*
X93365Y19541D03*
X94284Y37106D03*
X87198D03*
Y48720D03*
X94284D03*
X87347Y71839D03*
Y66847D03*
X91457Y75340D03*
X93367Y72847D03*
Y77839D03*
X89150Y154494D03*
X93717Y159053D03*
X87654Y376026D03*
X87520Y386502D03*
X85465Y773564D03*
Y780257D03*
Y803682D03*
X94624Y795316D03*
X85465Y810375D03*
Y817068D03*
X94624Y832127D03*
X85465Y840493D03*
Y847186D03*
Y853879D03*
Y877304D03*
X94624Y868938D03*
X85465Y890690D03*
Y883997D03*
X94624Y905750D03*
X85465Y920808D03*
Y914115D03*
Y927501D03*
Y950926D03*
X94624Y942561D03*
X85465Y957619D03*
Y971005D03*
Y964312D03*
Y984391D03*
Y977698D03*
Y991084D03*
Y997777D03*
Y1004470D03*
Y1044627D03*
Y1031241D03*
Y1037934D03*
Y1051320D03*
Y1058013D03*
Y1068052D03*
Y1074745D03*
X94624Y1089805D03*
X85465Y1098171D03*
Y1104863D03*
Y1111556D03*
X94624Y1126616D03*
X85465Y1134982D03*
Y1148367D03*
Y1141675D03*
X94624Y1163427D03*
X85465Y1178486D03*
Y1171793D03*
Y1185178D03*
Y1208604D03*
X94624Y1200238D03*
X85465Y1215297D03*
Y1221989D03*
X94624Y1237049D03*
X85465Y1252108D03*
Y1245415D03*
X90501Y1338952D03*
X92791Y1341302D03*
X96191Y1337721D03*
X92941Y1346172D03*
X91000Y1350300D03*
X88500D03*
X84000Y1408000D03*
Y1412500D03*
Y1417000D03*
X97530Y1410247D03*
X93000Y1430500D03*
X84000Y1421500D03*
Y1426000D03*
X93000Y1435500D03*
Y1440000D03*
X84500D03*
X95624Y1523287D03*
X85368Y1511285D03*
X85405Y1513835D03*
X88868Y1511285D03*
X88905Y1513835D03*
X93024Y1523287D03*
X85405Y1508698D03*
X88905D03*
X97498Y1533150D03*
X95624Y1526394D03*
X95018Y1533150D03*
X88696Y1526769D03*
X93024Y1526394D03*
X88696Y1523769D03*
X97498Y1538750D03*
X95018D03*
X93029Y1705225D03*
X97683Y1722477D03*
X97928Y3001D03*
X100313Y17045D03*
X109506D03*
X109389Y25977D03*
X100433D03*
X107389Y23981D03*
X102433D03*
X100313Y22037D03*
X102321Y19541D03*
X109506Y22037D03*
X107538Y19541D03*
X108458Y37106D03*
X101371D03*
Y48720D03*
X108458D03*
X98347Y72847D03*
X104367Y71839D03*
X109347D03*
X102457Y69340D03*
X104367Y66847D03*
X109347D03*
X98347Y77839D03*
X104829Y151191D03*
X107931Y158767D03*
X99754Y155807D03*
X110616Y756766D03*
X103574D03*
Y760266D03*
X99024Y776911D03*
X110616Y763766D03*
X103574Y767266D03*
X99024Y783604D03*
X109716Y786950D03*
X110766Y791970D03*
X99024Y807029D03*
X109716Y796989D03*
X99024Y813722D03*
Y820415D03*
X109716Y823761D03*
Y833800D03*
X110766Y828781D03*
X99024Y843840D03*
Y850533D03*
Y857226D03*
X109716Y860572D03*
X110766Y865592D03*
X99024Y880651D03*
X109716Y870611D03*
X99024Y887344D03*
Y894037D03*
X109716Y897383D03*
X110766Y902403D03*
X109716Y907423D03*
X99024Y924155D03*
Y917462D03*
Y930848D03*
X110766Y939214D03*
X109716Y934194D03*
X99024Y954273D03*
X109716Y944234D03*
X99024Y960966D03*
Y967659D03*
Y974352D03*
Y981045D03*
Y987737D03*
Y994430D03*
Y1004470D03*
Y1034588D03*
Y1041281D03*
Y1047974D03*
Y1054667D03*
Y1071399D03*
Y1061360D03*
Y1078092D03*
X109716Y1081438D03*
X110766Y1086458D03*
X99024Y1101517D03*
X109716Y1091478D03*
X99024Y1114903D03*
Y1108210D03*
X109716Y1118249D03*
Y1128289D03*
X110766Y1123269D03*
X99024Y1145021D03*
Y1138328D03*
Y1151714D03*
X109716Y1165100D03*
X110766Y1160080D03*
X109716Y1155060D03*
X99024Y1175139D03*
Y1181832D03*
Y1188525D03*
X109716Y1191871D03*
X110766Y1196891D03*
X109716Y1201911D03*
X99024Y1211950D03*
Y1218643D03*
Y1225336D03*
X109716Y1228682D03*
Y1238722D03*
X110766Y1233702D03*
X99024Y1248761D03*
Y1255454D03*
X99211Y1337771D03*
X112677Y1357409D03*
X110077D03*
X107477D03*
X104877D03*
X111581Y1372872D03*
X106721Y1367272D03*
Y1372872D03*
X109151D03*
X112677Y1363473D03*
X110077D03*
X112677Y1360516D03*
X110077D03*
X107477D03*
X104877D03*
X100347Y1361417D03*
X109151Y1367272D03*
X111581D03*
X111630Y1385287D03*
X101995Y1388247D03*
X98492Y1523287D03*
X100922D03*
X109635Y1523158D03*
X106713Y1523098D03*
X103513D03*
X99978Y1533150D03*
X98492Y1526394D03*
X98424Y1529501D03*
X100922Y1526394D03*
X101024Y1529501D03*
X108861Y1528840D03*
Y1526410D03*
X101396Y1552769D03*
X99978Y1538750D03*
X106448Y1696436D03*
X119928Y3001D03*
X114486Y17045D03*
X123683D03*
X123563Y25977D03*
X114607D03*
X116607Y23981D03*
X121563D03*
X114486Y22037D03*
X116494Y19541D03*
X121712D03*
X123683Y22037D03*
X122631Y37106D03*
X115544D03*
Y48720D03*
X122631D03*
X113457Y75340D03*
X115367Y72847D03*
X120347D03*
X126367Y71842D03*
X124457Y69343D03*
X126367Y66850D03*
X115367Y77839D03*
X120347D03*
X115166Y773564D03*
Y780257D03*
X124324Y795316D03*
X115166Y803682D03*
Y810375D03*
Y817068D03*
X124324Y832127D03*
X115166Y840493D03*
Y847186D03*
Y853879D03*
Y877304D03*
X124324Y868938D03*
X115166Y890690D03*
Y883997D03*
X124324Y905750D03*
X115166Y920808D03*
Y914115D03*
Y927501D03*
Y950926D03*
X124324Y942561D03*
X115166Y957619D03*
Y971005D03*
Y964312D03*
Y984391D03*
Y977698D03*
Y991084D03*
Y997777D03*
Y1004470D03*
Y1031241D03*
Y1037934D03*
Y1044627D03*
Y1051320D03*
Y1058013D03*
Y1068052D03*
Y1074745D03*
X124324Y1089805D03*
X115166Y1098171D03*
Y1104863D03*
Y1111556D03*
X124324Y1126616D03*
X115166Y1134982D03*
Y1148367D03*
Y1141675D03*
X124324Y1163427D03*
X115166Y1178486D03*
Y1171793D03*
Y1185178D03*
Y1208604D03*
X124324Y1200238D03*
X115166Y1215297D03*
Y1221989D03*
X124324Y1237049D03*
X115166Y1252108D03*
Y1245415D03*
X124071Y1337843D03*
X126671D03*
X115277Y1357409D03*
X126491Y1354871D03*
X125241Y1357371D03*
X126491Y1352271D03*
X123891Y1354871D03*
Y1352271D03*
X120221Y1357425D03*
X126491Y1349671D03*
X123891D03*
X117777Y1357409D03*
X121207Y1360686D03*
X114405Y1509335D03*
Y1516335D03*
Y1512835D03*
Y1519835D03*
Y1522835D03*
X116905D03*
Y1519835D03*
Y1512835D03*
Y1516335D03*
Y1509335D03*
Y1526335D03*
X120052Y1712450D03*
X141928Y3001D03*
X128663Y17045D03*
X130668Y19541D03*
X128663Y22037D03*
X129718Y37106D03*
Y48720D03*
X135457Y75340D03*
X137367Y72847D03*
X142347D03*
X131347Y71842D03*
Y66850D03*
X137367Y77839D03*
X142347D03*
X128367Y202241D03*
Y207241D03*
Y197241D03*
Y212241D03*
X139440Y439000D03*
X138090Y441900D03*
X140800Y441920D03*
X134812Y530955D03*
X131861Y664958D03*
X139869Y686582D03*
X140316Y756766D03*
X133124D03*
Y760266D03*
X128724Y776911D03*
X140316Y763766D03*
X133124Y767266D03*
X139416Y786950D03*
X128724Y783604D03*
X140466Y791970D03*
X128724Y807029D03*
X139416Y796989D03*
X128724Y813722D03*
Y820415D03*
X139416Y823761D03*
Y833800D03*
X140466Y828781D03*
X128724Y843840D03*
Y850533D03*
Y857226D03*
X139416Y860572D03*
X140466Y865592D03*
X128724Y880651D03*
X139416Y870611D03*
X128724Y887344D03*
Y894037D03*
X139416Y897383D03*
X140466Y902403D03*
X139416Y907423D03*
X128724Y924155D03*
Y917462D03*
X140466Y939214D03*
X139416Y934194D03*
X128724Y930848D03*
Y954273D03*
X139416Y944234D03*
X128724Y960966D03*
Y967659D03*
Y974352D03*
Y981045D03*
Y987737D03*
Y994430D03*
Y1004470D03*
Y1034588D03*
Y1041281D03*
Y1047974D03*
Y1054667D03*
Y1071399D03*
Y1061360D03*
X139416Y1081438D03*
X140466Y1086458D03*
X128724Y1078092D03*
Y1101517D03*
X139416Y1091478D03*
X128724Y1114903D03*
X139416Y1118249D03*
X128724Y1108210D03*
X139416Y1128289D03*
X140466Y1123269D03*
X128724Y1145021D03*
Y1138328D03*
X139416Y1165100D03*
X140466Y1160080D03*
X139416Y1155060D03*
X128724Y1151714D03*
Y1175139D03*
Y1181832D03*
X139416Y1191871D03*
X128724Y1188525D03*
X140466Y1196891D03*
X139416Y1201911D03*
X128724Y1211950D03*
Y1218643D03*
Y1225336D03*
X139416Y1228682D03*
X140466Y1233702D03*
X139416Y1238722D03*
X128724Y1248761D03*
Y1255454D03*
X137551Y1337771D03*
X131791Y1337811D03*
X140077Y1357409D03*
X137477D03*
X139321Y1367272D03*
Y1372872D03*
X141751D03*
X140077Y1360516D03*
X137477D03*
X132947Y1361417D03*
X141751Y1367272D03*
X130492Y1384789D03*
X132150Y1386740D03*
X132643Y1711846D03*
X150473Y25977D03*
X157429Y23981D03*
X152473D03*
X151410Y37106D03*
Y48720D03*
X153347Y71842D03*
X148367D03*
X153347Y66850D03*
X148367D03*
X146453Y69343D03*
X150318Y233536D03*
X142660Y438930D03*
X143720Y441960D03*
X145960Y438800D03*
X146930Y441870D03*
X149210Y438640D03*
X149830Y441920D03*
X149672Y665500D03*
X152705Y683218D03*
X144866Y773564D03*
Y780257D03*
X154025Y795316D03*
X144866Y803682D03*
Y810375D03*
Y817068D03*
X154025Y832127D03*
X144866Y840493D03*
Y847186D03*
Y853879D03*
Y877304D03*
X154025Y868938D03*
X144866Y890690D03*
Y883997D03*
X154025Y905750D03*
X144866Y920808D03*
Y914115D03*
Y927501D03*
X154025Y942561D03*
X144866Y950926D03*
Y957619D03*
Y971005D03*
Y964312D03*
Y984391D03*
Y977698D03*
Y991084D03*
Y997777D03*
Y1004470D03*
Y1031241D03*
Y1037934D03*
Y1044627D03*
Y1051320D03*
Y1058013D03*
Y1068052D03*
Y1074745D03*
X154025Y1089805D03*
X144866Y1098171D03*
Y1104863D03*
Y1111556D03*
X154025Y1126616D03*
X144866Y1134982D03*
Y1148367D03*
Y1141675D03*
X154025Y1163427D03*
X144866Y1178486D03*
Y1171793D03*
Y1185178D03*
Y1208604D03*
X154025Y1200238D03*
X144866Y1215297D03*
Y1221989D03*
X154025Y1237049D03*
X144866Y1252108D03*
Y1245415D03*
X156491Y1354871D03*
Y1352271D03*
X152821Y1357425D03*
X156491Y1349671D03*
X145277Y1357409D03*
X147877D03*
X142677D03*
X150377D03*
X144181Y1367272D03*
X153767Y1360456D03*
Y1363413D03*
X144181Y1372872D03*
X142677Y1360516D03*
X145277Y1363473D03*
X142677D03*
X145277Y1360516D03*
X144230Y1385287D03*
X150900Y1433500D03*
Y1429500D03*
X143478Y1440000D03*
X151082Y1436653D03*
X146978Y1440000D03*
X147277Y1712791D03*
X152815Y1705500D03*
X155740Y1729726D03*
X163928Y3001D03*
X164525Y17045D03*
X159545D03*
X159429Y25977D03*
X164646D03*
X171602Y23981D03*
X166646D03*
X157578Y19541D03*
X166534D03*
X171751D03*
X164525Y22037D03*
X159545D03*
X158497Y37106D03*
X165584D03*
X158497Y48720D03*
X165584D03*
X158661Y75340D03*
X160571Y72847D03*
X165551D03*
X171571Y71839D03*
X169661Y69340D03*
X171571Y66847D03*
X160571Y77839D03*
X165551D03*
X172120Y416600D03*
X168950Y412950D03*
X168910Y415930D03*
X170500Y441420D03*
X167580Y441380D03*
X164870Y441360D03*
X169440Y438390D03*
X166220Y438460D03*
X162975Y760266D03*
Y756766D03*
X170017D03*
X158425Y776911D03*
X170017Y763766D03*
X162975Y767266D03*
X158425Y783604D03*
X169117Y786950D03*
X170167Y791970D03*
X158425Y807029D03*
X169117Y796989D03*
X158425Y813722D03*
Y820415D03*
X169117Y823761D03*
Y833800D03*
X170167Y828781D03*
X158425Y843840D03*
Y850533D03*
Y857226D03*
X169117Y860572D03*
X170167Y865592D03*
X158425Y880651D03*
X169117Y870611D03*
X158425Y887344D03*
Y894037D03*
X169117Y897383D03*
X170167Y902403D03*
X169117Y907423D03*
X158425Y924155D03*
Y917462D03*
Y930848D03*
X170167Y939214D03*
X169117Y934194D03*
X158425Y954273D03*
X169117Y944234D03*
X158425Y960966D03*
Y967659D03*
Y974352D03*
Y981045D03*
Y987737D03*
Y994430D03*
Y1004470D03*
Y1034588D03*
Y1041281D03*
Y1047974D03*
Y1054667D03*
Y1071399D03*
Y1061360D03*
Y1078092D03*
X169117Y1081438D03*
X170167Y1086458D03*
X158425Y1101517D03*
X169117Y1091478D03*
X158425Y1114903D03*
Y1108210D03*
X169117Y1118249D03*
Y1128289D03*
X170167Y1123269D03*
X158425Y1145021D03*
Y1138328D03*
X169117Y1165100D03*
X170167Y1160080D03*
X169117Y1155060D03*
X158425Y1151714D03*
Y1175139D03*
Y1181832D03*
Y1188525D03*
X169117Y1191871D03*
X170167Y1196891D03*
X169117Y1201911D03*
X158425Y1211950D03*
Y1218643D03*
Y1225336D03*
X169117Y1238722D03*
Y1228682D03*
X170167Y1233702D03*
X158425Y1248761D03*
Y1255454D03*
X171481Y1337853D03*
X164481Y1337813D03*
X161881D03*
X170177Y1357409D03*
X159091Y1354871D03*
X157841Y1357371D03*
X159091Y1352271D03*
Y1349671D03*
X172021Y1367272D03*
Y1372872D03*
X170177Y1360516D03*
X165647Y1361417D03*
X163192Y1384789D03*
X164850Y1386740D03*
X168661Y1459995D03*
X166751Y1462595D03*
X168661Y1465195D03*
X164650Y1529350D03*
Y1540250D03*
X171925Y1708428D03*
X167500Y1712864D03*
X171925Y1727581D03*
X157860Y1718500D03*
X185928Y3001D03*
X173719Y17045D03*
X178699D03*
X173602Y25977D03*
X173719Y22037D03*
X178699D03*
X180707Y19541D03*
X172670Y37106D03*
X179757D03*
X172670Y48720D03*
X179757D03*
X176551Y71839D03*
Y66847D03*
X180657Y75343D03*
X182571Y72850D03*
Y77842D03*
X182548Y147260D03*
X176610Y441380D03*
X175990Y438100D03*
X173710Y441330D03*
X172740Y438260D03*
X173299Y664958D03*
X172802Y682036D03*
X174567Y773564D03*
Y780257D03*
Y803682D03*
X183726Y795316D03*
X174567Y810375D03*
Y817068D03*
X183726Y832127D03*
X174567Y840493D03*
Y847186D03*
Y853879D03*
Y877304D03*
X183726Y868938D03*
X174567Y890690D03*
Y883997D03*
X183726Y905750D03*
X174567Y920808D03*
Y914115D03*
Y927501D03*
Y950926D03*
X183726Y942561D03*
X174567Y957619D03*
Y971005D03*
Y964312D03*
Y984391D03*
Y977698D03*
Y991084D03*
Y997777D03*
Y1004470D03*
Y1031241D03*
Y1037934D03*
Y1044627D03*
Y1051320D03*
Y1058013D03*
Y1068052D03*
Y1074745D03*
X183726Y1089805D03*
X174567Y1098171D03*
Y1104863D03*
Y1111556D03*
Y1134982D03*
X183726Y1126616D03*
X174567Y1148367D03*
Y1141675D03*
X183726Y1163427D03*
X174567Y1178486D03*
Y1171793D03*
Y1185178D03*
Y1208604D03*
X183726Y1200238D03*
X174567Y1215297D03*
Y1221989D03*
X183726Y1237049D03*
X174567Y1252108D03*
Y1245415D03*
X185701Y1337853D03*
X183101D03*
X174081D03*
X172777Y1357409D03*
X183077D03*
X185521Y1357425D03*
X175377Y1357409D03*
X177977D03*
X180577D03*
X176881Y1367272D03*
X174451D03*
X186467Y1360456D03*
Y1363413D03*
X172777Y1360516D03*
X176881Y1372872D03*
X174451D03*
X177977Y1363473D03*
X175377D03*
Y1360516D03*
X177977D03*
X176930Y1385287D03*
X173441Y1459995D03*
X173451Y1452895D03*
X180141Y1450295D03*
X175361D03*
X180141Y1455495D03*
X175361D03*
X173441Y1465195D03*
X186851Y1472295D03*
X177322Y1498320D03*
X173980Y1528731D03*
X185254Y1686870D03*
X179444Y1708810D03*
X184340Y1718000D03*
X194607Y25977D03*
X196607Y23981D03*
X201563D03*
X201712Y19541D03*
X195544Y37106D03*
Y48720D03*
X193571Y71839D03*
X198551D03*
X191661Y69340D03*
X193571Y66847D03*
X198551D03*
X187656Y72850D03*
Y77842D03*
X195979Y109462D03*
X203061Y131158D03*
X195690Y415390D03*
X195730Y412410D03*
X200405Y622385D03*
Y632385D03*
X192676Y760266D03*
Y756766D03*
X199718D03*
X192676Y767266D03*
X199718Y763766D03*
X188126Y776911D03*
X199868Y791970D03*
X198818Y786950D03*
X188126Y783604D03*
X198818Y796989D03*
X188126Y807029D03*
Y813722D03*
Y820415D03*
X199868Y828781D03*
X198818Y823761D03*
Y833800D03*
X188126Y843840D03*
Y850533D03*
X199868Y865592D03*
X198818Y860572D03*
X188126Y857226D03*
X198818Y870611D03*
X188126Y880651D03*
Y887344D03*
Y894037D03*
X199868Y902403D03*
X198818Y897383D03*
Y907423D03*
X188126Y917462D03*
Y924155D03*
X199868Y939214D03*
X198818Y934194D03*
X188126Y930848D03*
X198818Y944234D03*
X188126Y954273D03*
Y960966D03*
Y967659D03*
Y974352D03*
Y981045D03*
Y987737D03*
Y994430D03*
Y1004470D03*
Y1034588D03*
Y1041281D03*
Y1047974D03*
Y1054667D03*
Y1061360D03*
Y1071399D03*
X199868Y1086458D03*
X198818Y1081438D03*
X188126Y1078092D03*
X198818Y1091478D03*
X188126Y1101517D03*
X198818Y1118249D03*
X188126Y1108210D03*
Y1114903D03*
X199868Y1123269D03*
X198818Y1128289D03*
X188126Y1138328D03*
Y1145021D03*
X199868Y1160080D03*
X198818Y1155060D03*
Y1165100D03*
X188126Y1151714D03*
Y1175139D03*
X198818Y1191871D03*
X188126Y1181832D03*
Y1188525D03*
X199868Y1196891D03*
X198818Y1201911D03*
X188126Y1211950D03*
Y1218643D03*
X199868Y1233702D03*
X198818Y1228682D03*
Y1238722D03*
X188126Y1225336D03*
Y1248761D03*
Y1255454D03*
X195771Y1337903D03*
X193171D03*
X190541Y1357371D03*
X189191Y1354871D03*
Y1352271D03*
X191791Y1354871D03*
Y1352271D03*
X189191Y1349671D03*
X191791D03*
X198547Y1361417D03*
X196092Y1384789D03*
X197750Y1386740D03*
X193551Y1462595D03*
X200241Y1459995D03*
X195461D03*
X202161Y1450295D03*
X200251Y1452895D03*
X202161Y1455495D03*
X193541Y1469695D03*
X188761D03*
X193541Y1474895D03*
X188761D03*
X200241Y1465195D03*
X195461D03*
X197703Y1550897D03*
X192978Y1550797D03*
X188254D03*
X187388Y1594876D03*
X192344D03*
X199448D03*
X187388Y1589884D03*
X199448D03*
X192344D03*
X193418Y1604876D03*
Y1599884D03*
X198374D03*
Y1604876D03*
Y1611796D03*
X193418D03*
X198374Y1616788D03*
X193418D03*
X192344Y1626788D03*
X199448D03*
X192344Y1621796D03*
X199448D03*
X187388D03*
Y1626788D03*
X200848Y1655656D03*
X190242Y1656635D03*
X201120Y1668603D03*
X199040Y1666925D03*
X196366Y1664821D03*
X190271Y1671753D03*
X195153Y1679774D03*
X190391Y1701988D03*
X195300Y1694898D03*
X194000Y1712362D03*
X201531Y1715000D03*
X192745Y1707106D03*
X199547Y1704605D03*
X195150Y1723000D03*
X207928Y3001D03*
X208659Y17045D03*
X203679D03*
X208780Y25977D03*
X203563D03*
X210780Y23981D03*
X215736D03*
X210668Y19541D03*
X215885D03*
X208659Y22037D03*
X203679D03*
X202631Y37106D03*
X216804D03*
X209718D03*
X202631Y48720D03*
X209718D03*
X216804D03*
X202795Y75340D03*
X204705Y72847D03*
X209685D03*
X213791Y69343D03*
X215705Y66850D03*
Y71842D03*
X204705Y77839D03*
X209685D03*
X214107Y113022D03*
X205489Y142790D03*
X206760Y148760D03*
X206805Y622385D03*
X203605D03*
X206805Y632385D03*
X203605D03*
X204268Y773564D03*
Y780257D03*
X213427Y795316D03*
X204268Y803682D03*
Y810375D03*
Y817068D03*
X213427Y832127D03*
X204268Y840493D03*
Y847186D03*
Y853879D03*
X213427Y868938D03*
X204268Y877304D03*
Y883997D03*
Y890690D03*
X213427Y905750D03*
X204268Y914115D03*
Y920808D03*
Y927501D03*
X213427Y942561D03*
X204268Y950926D03*
Y957619D03*
Y964312D03*
Y971005D03*
Y977698D03*
Y984391D03*
Y991084D03*
Y997777D03*
Y1004470D03*
Y1031241D03*
Y1037934D03*
Y1044627D03*
Y1051320D03*
Y1058013D03*
Y1068052D03*
Y1074745D03*
X213427Y1089805D03*
X204268Y1098171D03*
Y1104863D03*
Y1111556D03*
X213427Y1126616D03*
X204268Y1134982D03*
Y1141675D03*
Y1148367D03*
X213427Y1163427D03*
X204268Y1171793D03*
Y1178486D03*
Y1185178D03*
X213427Y1200238D03*
X204268Y1208604D03*
Y1215297D03*
Y1221989D03*
X213427Y1237049D03*
X204268Y1245415D03*
Y1252108D03*
X215977Y1357409D03*
X210877D03*
X208277D03*
X213477D03*
X205677D03*
X203077D03*
X207351Y1367272D03*
X209781Y1372872D03*
X204921Y1367272D03*
Y1372872D03*
X207351D03*
X210877Y1363473D03*
X208277D03*
Y1360516D03*
X210877D03*
X205677D03*
X203077D03*
X209781Y1367272D03*
X209830Y1385287D03*
X213648Y1416262D03*
X206941Y1450295D03*
Y1455495D03*
X213651Y1472295D03*
X215561Y1469695D03*
Y1474895D03*
X216601Y1550697D03*
X202427D03*
X211876Y1550897D03*
X207152D03*
X211508Y1594876D03*
X204404D03*
X216464D03*
X211508Y1589884D03*
X204404D03*
X216464D03*
X210434Y1604876D03*
X205478D03*
X210434Y1599884D03*
X205478D03*
Y1611796D03*
X210434D03*
Y1616788D03*
X205478D03*
X211508Y1626788D03*
X216464D03*
X211508Y1621796D03*
X216464D03*
X204404Y1626788D03*
Y1621796D03*
X203807Y1681173D03*
Y1696366D03*
X211103Y1708988D03*
X229928Y3001D03*
X217853Y17045D03*
X222833D03*
X217736Y25977D03*
X217853Y22037D03*
X222833D03*
X224841Y19541D03*
X223891Y37106D03*
X230977D03*
X223891Y48720D03*
X230977D03*
X224795Y75340D03*
X226705Y72847D03*
X231685D03*
X220685Y66850D03*
Y71842D03*
X231685Y77839D03*
X226705D03*
X233653Y162074D03*
X222000Y160000D03*
X220687Y522453D03*
X226687D03*
X233493Y676906D03*
X227493D03*
X224493D03*
X230493D03*
X221493D03*
X222377Y760266D03*
Y756766D03*
X229419D03*
X222377Y767266D03*
X229419Y763119D03*
X217827Y776911D03*
X229569Y791970D03*
X228519Y786950D03*
X217827Y783604D03*
X228519Y796989D03*
X217827Y807029D03*
Y813722D03*
Y820415D03*
X229569Y828781D03*
X228519Y823761D03*
Y833800D03*
X217827Y843840D03*
Y850533D03*
X229569Y865592D03*
X228519Y860572D03*
X217827Y857226D03*
X228519Y870611D03*
X217827Y880651D03*
Y887344D03*
Y894037D03*
X229569Y902403D03*
X228519Y897383D03*
Y907423D03*
X217827Y917462D03*
Y924155D03*
X229569Y939214D03*
X228519Y934194D03*
X217827Y930848D03*
X228519Y944234D03*
X217827Y954273D03*
Y960966D03*
Y967659D03*
Y974352D03*
Y981045D03*
Y987737D03*
Y994430D03*
Y1004470D03*
Y1034588D03*
Y1041281D03*
Y1047974D03*
Y1054667D03*
Y1061360D03*
Y1071399D03*
X229569Y1086458D03*
X228519Y1081438D03*
X217827Y1078092D03*
Y1101517D03*
X228519Y1091478D03*
Y1118249D03*
X217827Y1108210D03*
Y1114903D03*
X229569Y1123269D03*
X228519Y1128289D03*
X217827Y1138328D03*
Y1145021D03*
X229569Y1160080D03*
X228519Y1155060D03*
Y1165100D03*
X217827Y1151714D03*
Y1175139D03*
X228519Y1191871D03*
X217827Y1181832D03*
Y1188525D03*
X229569Y1196891D03*
X228519Y1201911D03*
X217827Y1211950D03*
Y1218643D03*
X229569Y1233702D03*
X228519Y1228682D03*
Y1238722D03*
X217827Y1225336D03*
Y1248761D03*
Y1255454D03*
X224481Y1326418D03*
X221881D03*
X224481Y1323918D03*
X221881Y1321418D03*
X224481D03*
X221881Y1323918D03*
X230171Y1323904D03*
Y1321404D03*
X227871Y1338124D03*
X223941Y1338068D03*
X221341D03*
X230661Y1338124D03*
X224691Y1354871D03*
Y1352271D03*
X223441Y1357371D03*
X222091Y1354871D03*
Y1352271D03*
X218421Y1357425D03*
X224691Y1349671D03*
X222091D03*
X219367Y1360456D03*
Y1363413D03*
X231347Y1361417D03*
X228892Y1384789D03*
X230550Y1386740D03*
X228693Y1408885D03*
X224881Y1410685D03*
X220803Y1412115D03*
X217097Y1413863D03*
X227051Y1452895D03*
X220351Y1462595D03*
X228961Y1450295D03*
Y1455495D03*
X227041Y1459995D03*
X222261D03*
X220341Y1469695D03*
Y1474895D03*
X227041Y1465195D03*
X222261D03*
X226050Y1550897D03*
X221325Y1550797D03*
X230774Y1550897D03*
X228524Y1594876D03*
X223568D03*
Y1589884D03*
X228524D03*
X222494Y1604876D03*
X217538D03*
X222494Y1599884D03*
X217538D03*
X229598Y1604876D03*
Y1599884D03*
Y1611796D03*
X217538D03*
X222494D03*
X229598Y1616788D03*
X217538D03*
X222494D03*
X223568Y1626788D03*
X228524D03*
X223568Y1621796D03*
X228524D03*
X243486Y23005D03*
X244296Y59765D03*
X242251Y162515D03*
X246250Y204360D03*
X233438Y593556D03*
X236638D03*
X233456Y601598D03*
X236656D03*
X236674Y609640D03*
X233474D03*
X233969Y773564D03*
Y780257D03*
Y803682D03*
Y810375D03*
Y817068D03*
Y840493D03*
Y847186D03*
Y853879D03*
Y877304D03*
Y883997D03*
Y890690D03*
Y914115D03*
Y920808D03*
Y927501D03*
Y950926D03*
Y957619D03*
Y964312D03*
Y971005D03*
Y977698D03*
Y984391D03*
Y991084D03*
Y997777D03*
Y1004470D03*
Y1031241D03*
Y1037934D03*
Y1044627D03*
Y1051320D03*
Y1058013D03*
Y1068052D03*
Y1074745D03*
Y1098171D03*
Y1104863D03*
Y1111556D03*
Y1134982D03*
Y1141675D03*
Y1148367D03*
Y1171793D03*
Y1178486D03*
Y1185178D03*
Y1208604D03*
Y1215297D03*
Y1221989D03*
Y1245415D03*
Y1252108D03*
X232961Y1323904D03*
Y1321404D03*
X239561Y1338124D03*
X243677Y1357409D03*
X241077D03*
X238477D03*
X235877D03*
X246277D03*
X242581Y1367272D03*
X240151D03*
X243677Y1363473D03*
X241077D03*
Y1360516D03*
X243677D03*
X242581Y1372872D03*
X240151D03*
X237721D03*
Y1367272D03*
X238477Y1360516D03*
X235877D03*
X242630Y1385287D03*
X233194Y1407349D03*
X233741Y1450295D03*
Y1455495D03*
X240451Y1472295D03*
X242361Y1469695D03*
Y1474895D03*
X235499Y1550897D03*
X240223D03*
X244947Y1550697D03*
X240584Y1594876D03*
X235628D03*
Y1589884D03*
X240584D03*
X246614Y1604876D03*
Y1599884D03*
X234554Y1604876D03*
Y1599884D03*
X241658Y1604876D03*
Y1599884D03*
X246614Y1611796D03*
X241658D03*
X234554D03*
X246614Y1616788D03*
X241658D03*
X234554D03*
X235628Y1626788D03*
X240584D03*
X235628Y1621796D03*
X240584D03*
X251928Y3001D03*
X247716Y75865D03*
Y71865D03*
X251793Y100846D03*
X261383Y133786D03*
X258253D03*
X249735Y152694D03*
X254095Y209235D03*
X254671Y642138D03*
X258470Y775410D03*
X260671Y1338124D03*
X258071D03*
X247725Y1338141D03*
X257491Y1352271D03*
X256241Y1357371D03*
X257491Y1354871D03*
X254891Y1352271D03*
Y1354871D03*
X251221Y1357425D03*
X248777Y1357409D03*
X257491Y1349671D03*
X254891D03*
X252167Y1363413D03*
Y1360456D03*
X253851Y1452895D03*
X247151Y1462595D03*
X260541Y1450295D03*
X255761D03*
X260541Y1455495D03*
X255761D03*
X253841Y1459995D03*
X249061D03*
X253841Y1465195D03*
X249061D03*
X247141Y1469695D03*
Y1474895D03*
X259120Y1550797D03*
X254396Y1550897D03*
X249671D03*
X259748Y1594876D03*
X247688D03*
X252644D03*
X247688Y1589884D03*
X259748D03*
X252644D03*
X253718Y1604876D03*
X258674D03*
X253718Y1599884D03*
X258674D03*
Y1611796D03*
X253718D03*
X258674Y1616788D03*
X253718D03*
X252644Y1626788D03*
X259748D03*
X252644Y1621796D03*
X259748D03*
X247688Y1626788D03*
Y1621796D03*
X273928Y3001D03*
X272596Y27185D03*
X263276Y34625D03*
X271596Y40165D03*
X270364Y118415D03*
X272361Y120243D03*
X264574Y159206D03*
Y155206D03*
X267500Y220441D03*
X265100Y595078D03*
X270905Y608485D03*
X273905D03*
Y611485D03*
X272603Y692910D03*
Y695510D03*
X271491Y1291740D03*
X274091D03*
X272077Y1314370D03*
X269477D03*
X274677D03*
X272077Y1311263D03*
X269477D03*
X274677D03*
X271321Y1326726D03*
Y1321126D03*
X276181Y1326726D03*
X273751D03*
X274677Y1317327D03*
X264947Y1315271D03*
X276181Y1321126D03*
X273751D03*
X276230Y1339141D03*
X264085Y1339175D03*
X267251Y1452895D03*
X273941Y1450295D03*
X269161D03*
X273941Y1455495D03*
X269161D03*
X276637Y1523953D03*
X270139Y1548563D03*
X271808Y1594876D03*
X264704D03*
X271808Y1589884D03*
X264704D03*
X265778Y1604876D03*
X270734D03*
X265778Y1599790D03*
X270734D03*
Y1611796D03*
X265778D03*
X270734Y1616788D03*
X265778D03*
X271808Y1626788D03*
Y1621796D03*
X264704Y1626788D03*
Y1621796D03*
X291000Y14820D03*
X285896Y23965D03*
X291156Y21395D03*
X286716Y40020D03*
X285499Y53191D03*
X278989Y48720D03*
X286076D03*
X283949Y152506D03*
X288516Y157065D03*
X285260Y234000D03*
X279500Y234075D03*
X290865Y609470D03*
X277105Y608485D03*
X280305D03*
X277105Y611485D03*
X280305D03*
X286665Y609470D03*
X283705Y608485D03*
X284705Y605485D03*
X283705Y611485D03*
X287832Y674150D03*
X283921Y1291740D03*
X281321D03*
X284821Y1311279D03*
X282377Y1311263D03*
X279877D03*
X277277Y1314370D03*
Y1311263D03*
X288491Y1306125D03*
Y1308725D03*
X291091Y1306125D03*
Y1308725D03*
X288491Y1303525D03*
X291091D03*
X289841Y1311225D03*
X285767Y1314310D03*
Y1317267D03*
X277277Y1317327D03*
X283946Y1530595D03*
X286446D03*
X288824Y1594876D03*
X276764D03*
X283868D03*
Y1589884D03*
X276764D03*
X288824D03*
X277838Y1604876D03*
X282794D03*
X277838Y1599884D03*
X282794D03*
X289898Y1604876D03*
Y1599884D03*
Y1611796D03*
X282794D03*
X277838D03*
X289898Y1616788D03*
X282794D03*
X277838D03*
X283868Y1626788D03*
X288824D03*
X283868Y1621796D03*
X288824D03*
X276764Y1626788D03*
Y1621796D03*
X295928Y3001D03*
X296272Y69128D03*
X293443Y78576D03*
X293448Y82486D03*
Y85986D03*
X303043Y79376D03*
X299943Y79276D03*
X299653Y92506D03*
X299628Y149203D03*
X299624Y158706D03*
X294553Y153819D03*
X293000Y216500D03*
X294165Y609570D03*
X297838Y609585D03*
X300965Y609570D03*
X304449D03*
X305121Y726348D03*
X298991D03*
X294541Y1291378D03*
X291941D03*
X302373Y1314342D03*
X304973D03*
X302373Y1311235D03*
X304973D03*
X304217Y1326698D03*
Y1321098D03*
X297843Y1315243D03*
X295388Y1338615D03*
X297046Y1340566D03*
X305199Y1398269D03*
Y1400769D03*
X295116Y1398132D03*
Y1400632D03*
X292516D03*
Y1398132D03*
X301513Y1452895D03*
X294813Y1462595D03*
X303423Y1450295D03*
Y1455495D03*
X301503Y1459995D03*
X296723D03*
X301503Y1465195D03*
X296723D03*
X299950Y1499500D03*
X301550Y1518040D03*
Y1514420D03*
Y1510800D03*
X302042Y1528731D03*
X300884Y1594876D03*
X295928D03*
Y1589884D03*
X300884D03*
X294854Y1604876D03*
Y1599884D03*
X301958Y1604876D03*
Y1599884D03*
Y1611796D03*
X294854D03*
X301958Y1616788D03*
X294854D03*
X295928Y1626788D03*
X300884D03*
X295928Y1621796D03*
X300884D03*
X317928Y3001D03*
X306716Y39985D03*
X320053Y85806D03*
Y88806D03*
X310425Y243925D03*
X317240Y252970D03*
X308925Y260075D03*
X307865Y609570D03*
X311349Y609632D03*
X313961Y607088D03*
Y604588D03*
X319657Y696415D03*
X319621Y1291740D03*
X321387Y1306097D03*
Y1308697D03*
Y1303497D03*
X317717Y1311251D03*
X315273Y1311235D03*
X312773D03*
X307573Y1314342D03*
Y1311235D03*
X310173Y1314342D03*
Y1311235D03*
X318663Y1314282D03*
X309077Y1321098D03*
X306647D03*
X318663Y1317239D03*
X309077Y1326698D03*
X306647D03*
X307573Y1317299D03*
X310173D03*
X309126Y1339113D03*
X307799Y1400769D03*
Y1398269D03*
X318199Y1400549D03*
X314199D03*
X310399D03*
X308203Y1450295D03*
Y1455495D03*
X314913Y1472295D03*
X316823Y1469695D03*
Y1474895D03*
X321040Y1550797D03*
X316316D03*
X320048Y1594876D03*
X307988D03*
X312944D03*
X307988Y1589884D03*
X320048D03*
X312944D03*
X306914Y1604876D03*
Y1599884D03*
X314018Y1604876D03*
X318974D03*
X314018Y1599884D03*
X318974D03*
Y1611796D03*
X314018D03*
X306914D03*
X318974Y1616788D03*
X314018D03*
X306914D03*
X320048Y1626788D03*
X312944D03*
X320048Y1621796D03*
X312944D03*
X307988Y1626788D03*
Y1621796D03*
X329535Y49379D03*
X331000Y270260D03*
X328966Y543012D03*
X334744Y566086D03*
X333500Y582500D03*
Y578500D03*
X333988Y590633D03*
X329471Y1291778D03*
X322221Y1291740D03*
X326761Y1291778D03*
X335277Y1314285D03*
Y1311178D03*
X323987Y1303497D03*
Y1306097D03*
Y1308697D03*
X322737Y1311197D03*
X330747Y1315186D03*
X328292Y1338558D03*
X329950Y1340509D03*
X333830Y1396299D03*
Y1398899D03*
Y1401499D03*
Y1393799D03*
X324309Y1396599D03*
Y1399199D03*
Y1401799D03*
Y1394099D03*
X321999Y1400549D03*
X321613Y1462595D03*
X323523Y1459995D03*
X328303D03*
X328313Y1452895D03*
X335003Y1450295D03*
X330223D03*
X335003Y1455495D03*
X330223D03*
X328313Y1472295D03*
X323523Y1465195D03*
X328303D03*
X321603Y1469695D03*
Y1474895D03*
X325765Y1550897D03*
X330489Y1550697D03*
X335214Y1550897D03*
X332108Y1594876D03*
X325004D03*
X332108Y1589884D03*
X325004D03*
X326078Y1604876D03*
X331034D03*
X326078Y1599884D03*
X331034D03*
Y1611796D03*
X326078D03*
X331034Y1616788D03*
X326078D03*
X332108Y1626788D03*
X325004D03*
X332108Y1621796D03*
X325004D03*
X343036Y122525D03*
X342075Y287925D03*
X351157Y562415D03*
X345500Y574415D03*
X351157D03*
X338664Y699660D03*
X337030Y697750D03*
X340477Y1314285D03*
X337877D03*
Y1311178D03*
X340477D03*
X350621Y1311194D03*
X348177Y1311178D03*
X343077Y1314285D03*
X345677Y1311178D03*
X343077D03*
X341981Y1321041D03*
X339551D03*
X341981Y1326641D03*
X337121Y1321041D03*
X339551Y1326641D03*
X337121D03*
X340477Y1317242D03*
X343077D03*
X342030Y1339056D03*
X347110Y1398312D03*
X351110D03*
X341760Y1401449D03*
X337760D03*
X349760D03*
X345760D03*
X348413Y1462595D03*
X350323Y1459995D03*
X341713Y1472295D03*
X350323Y1465195D03*
X348403Y1469695D03*
X343623D03*
X348403Y1474895D03*
X343623D03*
X339938Y1550897D03*
X349387Y1550797D03*
X344663Y1550697D03*
X349124Y1594876D03*
X337064D03*
X344168D03*
Y1589884D03*
X337064D03*
X349124D03*
X338138Y1604876D03*
X343094D03*
X338138Y1599884D03*
X343094D03*
X350198Y1604876D03*
Y1599884D03*
Y1611796D03*
X343094D03*
X338138D03*
X350198Y1616788D03*
X343094D03*
X338138D03*
X344168Y1626788D03*
X349124D03*
X344168Y1621796D03*
X349124D03*
X337064Y1626788D03*
Y1621796D03*
X351535Y49379D03*
X366874Y135157D03*
X366771Y127665D03*
X359734Y288768D03*
X360433Y294030D03*
X355832Y297855D03*
X353700Y547893D03*
X356850D03*
X365593Y621622D03*
X364788Y1193918D03*
X364457Y1188109D03*
X359541Y1291918D03*
X362311Y1291968D03*
X356551Y1291880D03*
X353951D03*
X356891Y1306040D03*
Y1308640D03*
Y1303440D03*
X354291Y1306040D03*
Y1308640D03*
Y1303440D03*
X355641Y1311140D03*
X351567Y1314225D03*
Y1317182D03*
X363547Y1315386D03*
X361092Y1338758D03*
X362750Y1340709D03*
X355110Y1398312D03*
X359110D03*
X363110D03*
X357760Y1401449D03*
X353760D03*
X355113Y1452895D03*
X361803Y1450295D03*
X357023D03*
X361803Y1455495D03*
X357023D03*
X355103Y1459995D03*
Y1465195D03*
X354112Y1550897D03*
X358836D03*
X363561D03*
X361184Y1594876D03*
X356228D03*
Y1589884D03*
X361184D03*
X355154Y1604876D03*
Y1599884D03*
X362258Y1604876D03*
Y1599790D03*
Y1611796D03*
X355154D03*
X362258Y1616788D03*
X355154D03*
X356228Y1626788D03*
X361184D03*
X356228Y1621796D03*
X361184D03*
X373535Y49379D03*
X375920Y146577D03*
X380012Y243615D03*
X379200Y298772D03*
X367902Y303760D03*
X380771Y524903D03*
X375943D03*
X371724Y699450D03*
X370090Y697482D03*
X372000Y816862D03*
Y826362D03*
Y828862D03*
Y837862D03*
Y840362D03*
Y849362D03*
X378083Y1184949D03*
X367782Y1199648D03*
X380977Y1311378D03*
X375877Y1314485D03*
X378477Y1311378D03*
X375877D03*
X370677Y1314485D03*
X368077D03*
X373277D03*
X368077Y1311378D03*
X370677D03*
X373277D03*
X375877Y1317442D03*
X372351Y1326841D03*
X369921D03*
Y1321241D03*
X374781Y1326841D03*
X373277Y1317442D03*
X374781Y1321241D03*
X372351D03*
X374830Y1339256D03*
X379610Y1391781D03*
X375056Y1393741D03*
X375213Y1462595D03*
X377123Y1459995D03*
X368513Y1472295D03*
X377123Y1465195D03*
X375203Y1469695D03*
X370423D03*
X375203Y1474895D03*
X370423D03*
X368285Y1550897D03*
X373009Y1550697D03*
X377733Y1550897D03*
X368288Y1594876D03*
X373244D03*
X368288Y1589884D03*
X373244D03*
X367214Y1604876D03*
Y1599790D03*
X374318Y1604876D03*
X379274D03*
X374318Y1599884D03*
X379274D03*
Y1611796D03*
X374318D03*
X367214D03*
X379274Y1616788D03*
X374318D03*
X367214D03*
X373244Y1626788D03*
Y1621796D03*
X368288Y1626788D03*
Y1621796D03*
X372313Y1641759D03*
X379895Y1670046D03*
X372350Y1683284D03*
X385024Y-17575D03*
X381771Y-17589D03*
X388049Y-18895D03*
X381756Y-20104D03*
X385009Y-20090D03*
X381725Y-14717D03*
X385008Y-9673D03*
X385023Y-7158D03*
X381755Y-9687D03*
X388048Y-8478D03*
X381770Y-7172D03*
X381740Y-12202D03*
X395535Y49379D03*
X391600Y121178D03*
X387712Y147441D03*
X384600Y221800D03*
X386563Y280370D03*
X387184Y470495D03*
X387440Y525154D03*
X395657Y546894D03*
X391657Y546816D03*
X387657Y546876D03*
X384500Y810862D03*
X384499Y819862D03*
X388361Y1293713D03*
X385701Y1291828D03*
X392176Y1309859D03*
X394951Y1311259D03*
X389691Y1306240D03*
Y1308840D03*
X387091Y1306240D03*
Y1308840D03*
X389691Y1303640D03*
X387091D03*
X383421Y1311394D03*
X388441Y1311340D03*
X384367Y1314425D03*
Y1317382D03*
X392950Y1315280D03*
X392910Y1317880D03*
X395267Y1358621D03*
X393321Y1385630D03*
X388718Y1387386D03*
X384270Y1389875D03*
X395313Y1452895D03*
X381913D03*
X383823Y1450295D03*
X388603D03*
X383823Y1455495D03*
X388603D03*
X381903Y1459995D03*
Y1465195D03*
X382458Y1550897D03*
X387182Y1550797D03*
X393322Y1573347D03*
X394915Y1590018D03*
X387805Y1607802D03*
Y1604802D03*
Y1610802D03*
X387325Y1627212D03*
X385502Y1667154D03*
X394824Y1667120D03*
X389824D03*
X403734Y110326D03*
Y118976D03*
X397426Y112815D03*
Y116215D03*
X402606Y129465D03*
Y126065D03*
X403141Y144300D03*
X396237Y315507D03*
X399657Y546915D03*
X401880Y696220D03*
X404771Y698670D03*
X396129Y1334717D03*
X408459Y1330709D03*
X405859D03*
X400659D03*
X403259D03*
X408459Y1333816D03*
X405859D03*
X403259D03*
X400659D03*
X408459Y1336773D03*
X405859D03*
X402503Y1340572D03*
X407363D03*
X404933D03*
X407412Y1358587D03*
X407363Y1346172D03*
X404933D03*
X402503D03*
X410002Y1375093D03*
X405978Y1377794D03*
X401953Y1380494D03*
X397187Y1383354D03*
X397223Y1450295D03*
X402003D03*
X397223Y1455495D03*
X402003D03*
X401583Y1504872D03*
X404699Y1523953D03*
X398201Y1548563D03*
X410672Y1561170D03*
X400905Y1596091D03*
X403417Y1606224D03*
X403848Y1615354D03*
X400623Y1629772D03*
X406075Y1641000D03*
X399824Y1667120D03*
X409000Y1667025D03*
X405000Y1683500D03*
X401666Y1677925D03*
X417535Y49379D03*
X413949Y69270D03*
X414486Y127579D03*
Y124179D03*
X423521Y1311969D03*
X421091Y1311219D03*
X419673Y1325571D03*
Y1322971D03*
Y1328171D03*
X422273Y1322971D03*
Y1325571D03*
Y1328171D03*
X416949Y1336713D03*
Y1333756D03*
X424333Y1331447D03*
X411059Y1330709D03*
X416003Y1330725D03*
X413559Y1330709D03*
X421023Y1330671D03*
X414132Y1372234D03*
X415862Y1503715D03*
X422557Y1530595D03*
X420057D03*
X421059Y1569168D03*
X416163Y1594450D03*
X422007Y1592330D03*
X413100Y1607600D03*
X418293Y1607495D03*
X423379Y1607675D03*
X413200Y1612700D03*
X423439Y1612407D03*
X411515Y1599649D03*
X413100Y1617900D03*
X418500Y1618000D03*
X423349Y1617857D03*
X416962Y1634123D03*
X415437Y1636382D03*
X417365Y1630495D03*
X420765D03*
X421347Y1636668D03*
X411500Y1653500D03*
X417441Y1643946D03*
X420000Y1668075D03*
X417000Y1683500D03*
X439535Y49379D03*
X430564Y56348D03*
X430500Y72900D03*
X436090Y128007D03*
X440090Y132007D03*
X433124Y222253D03*
Y225205D03*
X439500Y484000D03*
X439284Y1038766D03*
Y1042766D03*
X431830Y1311240D03*
X438561Y1321622D03*
X432561D03*
X435561D03*
X437624Y1452895D03*
X430924Y1462595D03*
X439534Y1450295D03*
Y1455495D03*
X437614Y1459995D03*
X432834D03*
X437614Y1465195D03*
X432834D03*
X436140Y1499320D03*
X437661Y1518040D03*
Y1514420D03*
Y1510800D03*
X438153Y1528731D03*
X430239Y1581726D03*
X426688Y1598003D03*
X439283Y1608704D03*
X432559Y1627500D03*
X439404Y1615146D03*
X428000Y1640500D03*
X450102Y87011D03*
X450414Y92384D03*
X443014D03*
X452090Y116007D03*
Y124007D03*
Y132007D03*
Y128007D03*
X445997Y170701D03*
X453783Y217646D03*
X441320Y304170D03*
Y310170D03*
X449760Y497240D03*
X448688Y1305947D03*
X449440Y1308386D03*
X450220Y1310834D03*
X451083Y1313347D03*
X441561Y1321622D03*
X444561D03*
X452089Y1316074D03*
X452936Y1318775D03*
X453823Y1321436D03*
X454603Y1324033D03*
X454909Y1326721D03*
X444314Y1450295D03*
Y1455495D03*
X451024Y1472295D03*
X452934Y1469695D03*
Y1474895D03*
X452427Y1550797D03*
X440846Y1576526D03*
X451561Y1589884D03*
Y1594876D03*
X444128Y1604200D03*
Y1600200D03*
X451561Y1621796D03*
Y1626788D03*
X448776Y1622266D03*
Y1617166D03*
Y1619766D03*
X452500Y1637559D03*
X447387Y1641441D03*
X454099Y1649575D03*
X461535Y49379D03*
X457502Y87011D03*
X464456Y93101D03*
X457056D03*
X464051Y224799D03*
X460624Y244103D03*
X465925Y489925D03*
X457724Y1462595D03*
X459634Y1459995D03*
X464414D03*
X466334Y1450295D03*
X464424Y1452895D03*
X466334Y1455495D03*
X459634Y1465195D03*
X464414D03*
X457714Y1469695D03*
Y1474895D03*
X461876Y1550897D03*
X457151Y1550797D03*
X466600Y1550697D03*
X468577Y1589884D03*
Y1594876D03*
X456517Y1589884D03*
X463621D03*
Y1594876D03*
X456517D03*
X457591Y1599884D03*
X462547D03*
Y1604876D03*
X457591D03*
X462547Y1611796D03*
X457591D03*
X469651D03*
Y1599884D03*
Y1604876D03*
X462547Y1616788D03*
X457591D03*
X469651D03*
X468577Y1621796D03*
Y1626788D03*
X463621Y1621796D03*
Y1626788D03*
X456517Y1621796D03*
Y1626788D03*
X457240Y1629500D03*
X462500Y1655500D03*
X468350Y1645351D03*
X461000Y1650000D03*
X470309Y1689000D03*
X470500Y1674075D03*
X462500Y1701000D03*
X468500Y1708500D03*
X467416Y1724808D03*
X469975D03*
X464734Y1730518D03*
X483535Y49379D03*
X478949Y60029D03*
Y55135D03*
Y64975D03*
X470895Y128020D03*
X478295D03*
X482255Y127322D03*
Y135722D03*
X479630Y141942D03*
X471371Y231764D03*
X477203Y1015474D03*
X484784D03*
X477203Y1019017D03*
X484784D03*
X477203Y1022560D03*
X484784D03*
X484524Y1462595D03*
X471114Y1450295D03*
Y1455495D03*
X477824Y1472295D03*
X484514Y1469695D03*
X479734D03*
X484514Y1474895D03*
X479734D03*
X480774Y1550697D03*
X476049Y1550897D03*
X471325D03*
X480637Y1589884D03*
Y1594876D03*
X475681D03*
Y1589884D03*
X481711Y1611796D03*
Y1599884D03*
Y1604876D03*
X474607Y1611796D03*
Y1599884D03*
Y1604876D03*
X481711Y1616788D03*
X474607D03*
X475681Y1621796D03*
X480637D03*
X475681Y1626788D03*
X480637D03*
X478500Y1655500D03*
X476000Y1680000D03*
X478500Y1701000D03*
Y1714500D03*
X487590Y105969D03*
X494810D03*
X492300Y121389D03*
X487880Y131442D03*
X496280D03*
X492300Y124389D03*
X488580Y141942D03*
X494200Y158800D03*
X488260Y418980D03*
X488405Y578572D03*
X492284Y1015474D03*
Y1019017D03*
Y1022560D03*
X491224Y1452895D03*
X497914Y1450295D03*
X493134D03*
X497914Y1455495D03*
X493134D03*
X486434Y1459995D03*
X491214D03*
X486434Y1465195D03*
X491214D03*
X485498Y1550797D03*
X490223Y1550897D03*
X494947D03*
X499672D03*
X499801Y1594876D03*
X492697Y1589884D03*
X487741Y1594876D03*
X492697D03*
X499801Y1589884D03*
X487741D03*
X498727Y1611796D03*
Y1599884D03*
Y1604876D03*
X486667Y1611796D03*
X493771D03*
Y1599884D03*
Y1604876D03*
X486667Y1599884D03*
Y1604876D03*
X498727Y1616788D03*
X499801Y1621796D03*
Y1626788D03*
X486667Y1616788D03*
X493771D03*
X492697Y1621796D03*
X487741D03*
X492697Y1626788D03*
X487741D03*
X510815Y69562D03*
X502815Y106984D03*
X512654Y94967D03*
X500836Y119092D03*
X511140Y109829D03*
X511170Y224930D03*
Y227882D03*
X501500Y433000D03*
X511324Y1462595D03*
X513234Y1459995D03*
X504624Y1472295D03*
X513234Y1465195D03*
X511314Y1469695D03*
X506534D03*
X511314Y1474895D03*
X506534D03*
X513844Y1550897D03*
X509120Y1550697D03*
X504396Y1550897D03*
X511861Y1594876D03*
X504757Y1589884D03*
Y1594876D03*
X511861Y1589884D03*
X505831Y1611796D03*
X510787D03*
X505831Y1599884D03*
Y1604876D03*
X510787Y1599884D03*
Y1604876D03*
X511861Y1621796D03*
Y1626788D03*
X505831Y1616788D03*
X510787D03*
X504757Y1621796D03*
Y1626788D03*
X518843Y23788D03*
X517907Y69507D03*
X524993D03*
X516020Y102870D03*
X519240Y94967D03*
X521420Y109829D03*
X516020Y111770D03*
X518418Y137171D03*
X522831Y443712D03*
X518024Y1452895D03*
X519934Y1450295D03*
X524714D03*
X519934Y1455495D03*
X524714D03*
X518014Y1459995D03*
Y1465195D03*
X523293Y1550797D03*
X518569Y1550897D03*
X528940Y1548260D03*
X528877Y1589884D03*
Y1594876D03*
X516817Y1589884D03*
Y1594876D03*
X523921D03*
Y1589884D03*
X529951Y1611796D03*
Y1599790D03*
Y1604876D03*
X517891Y1611796D03*
X522847D03*
Y1599884D03*
X517891D03*
X522847Y1604876D03*
X517891D03*
X529951Y1616788D03*
X528877Y1621796D03*
Y1626788D03*
X517891Y1616788D03*
X522847D03*
X523921Y1621796D03*
X516817D03*
X523921Y1626788D03*
X516817D03*
X540843Y23788D03*
X542723Y39562D03*
X532080Y69507D03*
X539166D03*
X535170Y108730D03*
Y117630D03*
X533097Y246780D03*
X532000Y426500D03*
X544844Y439701D03*
X543500Y463500D03*
X540106Y657325D03*
X531424Y1452895D03*
X533334Y1450295D03*
X538114D03*
X533334Y1455495D03*
X538114D03*
X544814Y1459995D03*
X540810Y1523953D03*
X540937Y1589884D03*
Y1594876D03*
X535981D03*
Y1589884D03*
X542011Y1611796D03*
Y1599884D03*
Y1604876D03*
X534907Y1611796D03*
Y1599790D03*
Y1604876D03*
X542011Y1616788D03*
X540937Y1621796D03*
Y1626788D03*
X534907Y1616788D03*
X535981Y1621796D03*
Y1626788D03*
X548610Y57990D03*
X546253Y69507D03*
X553340D03*
X545935Y77516D03*
X553821D03*
X546400Y120700D03*
X553780Y118740D03*
Y127140D03*
X547196Y195256D03*
X546800Y262800D03*
X548856Y440452D03*
X556993Y616406D03*
X550993D03*
X553993D03*
X547993D03*
X558986Y1462595D03*
X545931Y1451344D03*
X559090Y1452185D03*
X548119Y1530595D03*
X550619D03*
X552997Y1589884D03*
X548041Y1594876D03*
X552997D03*
X548041Y1589884D03*
X559027Y1611796D03*
Y1599884D03*
Y1604876D03*
X546967Y1611796D03*
X554071D03*
Y1599884D03*
Y1604876D03*
X546967Y1599884D03*
Y1604876D03*
X559027Y1616788D03*
X546967D03*
X554071D03*
X552997Y1621796D03*
Y1626788D03*
X548041D03*
Y1621796D03*
X562843Y23788D03*
X560426Y69507D03*
X570860Y118310D03*
X565210Y125819D03*
X570860Y127510D03*
X564603Y197778D03*
Y200304D03*
X573911Y212196D03*
X569004Y228571D03*
X563230Y426508D03*
X563575Y448425D03*
X569464Y462140D03*
X559993Y616406D03*
X561580Y1242740D03*
X565686Y1452895D03*
X567596Y1450295D03*
X572376D03*
X567596Y1455495D03*
X572376D03*
X565676Y1459995D03*
X560896D03*
X565676Y1465195D03*
X560896D03*
X562860Y1499360D03*
X565723Y1510800D03*
Y1514420D03*
Y1518040D03*
X566215Y1528731D03*
X572161Y1594876D03*
X565057Y1589884D03*
X560101Y1594876D03*
X565057D03*
X572161Y1589884D03*
X560101D03*
X571087Y1611796D03*
Y1599884D03*
Y1604876D03*
X566131Y1611796D03*
Y1599884D03*
Y1604876D03*
X571087Y1616788D03*
X572161Y1621796D03*
Y1626788D03*
X566131Y1616788D03*
X565057Y1621796D03*
X560101D03*
X565057Y1626788D03*
X560101D03*
X584843Y23788D03*
X580098Y96439D03*
X576510Y125819D03*
X588554Y221277D03*
X577859Y212196D03*
X588554Y229277D03*
X575917Y421390D03*
X583505Y457925D03*
X587812Y474353D03*
X577801Y466000D03*
X578830Y1238075D03*
X578071Y1244425D03*
X588630Y1255075D03*
X583630D03*
X585786Y1462595D03*
X587696Y1459995D03*
X579086Y1472295D03*
X587696Y1465195D03*
X580996Y1469695D03*
X585776D03*
X580996Y1474895D03*
X585776D03*
X585213Y1550797D03*
X580489D03*
X589177Y1589884D03*
Y1594876D03*
X577117Y1589884D03*
Y1594876D03*
X584221D03*
Y1589884D03*
X578191Y1611796D03*
X583147D03*
Y1599884D03*
X578191D03*
X583147Y1604876D03*
X578191D03*
X589177Y1621796D03*
Y1626788D03*
X578191Y1616788D03*
X583147D03*
X584221Y1621796D03*
X577117D03*
X584221Y1626788D03*
X577117D03*
X603379Y70512D03*
X594430Y463600D03*
X592612Y805986D03*
X594330Y1238075D03*
X595671Y1245688D03*
X595598Y1251075D03*
X599659Y1241734D03*
X603947Y1258575D03*
X595947D03*
X592476Y1459995D03*
X594396Y1450295D03*
X599176D03*
X592486Y1452895D03*
X594396Y1455495D03*
X599176D03*
X592476Y1465195D03*
X599387Y1550897D03*
X604111D03*
X589938D03*
X594662Y1550697D03*
X601237Y1589884D03*
Y1594876D03*
X596281D03*
Y1589884D03*
X602311Y1611796D03*
Y1599884D03*
Y1604876D03*
X590251Y1611796D03*
X595207D03*
Y1599884D03*
X590251D03*
X595207Y1604876D03*
X590251D03*
X602311Y1616788D03*
X601237Y1621796D03*
Y1626788D03*
X590251Y1616788D03*
X595207D03*
X596281Y1621796D03*
Y1626788D03*
X606843Y23788D03*
X615190Y70533D03*
X607834Y222611D03*
X612414Y227041D03*
X605796Y425585D03*
X612969Y447260D03*
X616171Y780364D03*
X606559Y796116D03*
X612871Y1248488D03*
X612947Y1252075D03*
X609159Y1240234D03*
X612447Y1258575D03*
X616527Y1390732D03*
X619286Y1452895D03*
X612586Y1462595D03*
X614496Y1459995D03*
X619276D03*
X605886Y1472295D03*
X614496Y1465195D03*
X619276D03*
X612576Y1469695D03*
X607796D03*
X612576Y1474895D03*
X607796D03*
X613560Y1550797D03*
X618285Y1550897D03*
X608836Y1550697D03*
X613297Y1589884D03*
X608341Y1594876D03*
X613297D03*
X608341Y1589884D03*
X619327Y1611796D03*
Y1599884D03*
Y1604876D03*
X607267Y1611796D03*
X614371D03*
Y1599884D03*
Y1604876D03*
X607267Y1599884D03*
Y1604876D03*
X619327Y1616788D03*
X607267D03*
X614371D03*
X613297Y1621796D03*
X608341D03*
X613297Y1626788D03*
X608341D03*
X628843Y23788D03*
X625574Y150177D03*
X623605Y219277D03*
Y228777D03*
X624760Y424569D03*
X621916Y465088D03*
X632996Y478309D03*
X621309Y483346D03*
X634288Y766646D03*
X625976Y1450295D03*
X621196D03*
X625976Y1455495D03*
X621196D03*
X632686Y1472295D03*
X632458Y1550897D03*
X623009D03*
X627734D03*
X632461Y1594876D03*
X625357Y1589884D03*
X620401Y1594876D03*
X625357D03*
X632461Y1589884D03*
X620401D03*
X631387Y1611796D03*
Y1599790D03*
Y1604876D03*
X626431Y1611796D03*
Y1599790D03*
Y1604876D03*
X631387Y1616788D03*
X632461Y1626788D03*
Y1621796D03*
X626431Y1616788D03*
X620401Y1621796D03*
X625357D03*
X620401Y1626788D03*
X625357D03*
X627958Y1654114D03*
X645151Y69507D03*
X642394Y131172D03*
X642481Y184862D03*
X643012Y201913D03*
Y199313D03*
X635200Y415425D03*
X644673Y425816D03*
X637504Y454352D03*
X636614Y512597D03*
X647354Y776911D03*
Y783604D03*
Y807029D03*
Y813722D03*
Y820415D03*
Y843840D03*
Y850533D03*
Y857226D03*
Y880651D03*
Y887344D03*
Y894037D03*
Y917462D03*
Y924155D03*
Y930848D03*
Y954273D03*
Y960966D03*
Y967659D03*
Y974352D03*
Y981045D03*
Y987737D03*
Y994430D03*
Y1004470D03*
Y1034588D03*
Y1041281D03*
Y1047974D03*
Y1054667D03*
Y1061360D03*
Y1071399D03*
Y1078092D03*
Y1101517D03*
Y1108210D03*
Y1114903D03*
Y1138328D03*
Y1145021D03*
Y1151714D03*
Y1175139D03*
Y1181832D03*
Y1188525D03*
Y1211950D03*
Y1218643D03*
Y1225336D03*
Y1248761D03*
Y1255454D03*
X642436Y1350877D03*
X646236D03*
X638436D03*
X643563Y1392581D03*
X647445Y1392605D03*
X646086Y1452895D03*
X639386Y1462595D03*
X647996Y1450295D03*
Y1455495D03*
X641296Y1459995D03*
X646076D03*
X641296Y1465195D03*
X646076D03*
X639376Y1469695D03*
X634596D03*
X639376Y1474895D03*
X634596D03*
X646631Y1550897D03*
X637182Y1550697D03*
X641906Y1550897D03*
X637417Y1589884D03*
Y1594876D03*
X643447Y1599884D03*
X638491D03*
X643447Y1604876D03*
X638491D03*
X643447Y1611796D03*
X638491D03*
X643447Y1616788D03*
X637417Y1626788D03*
X638491Y1616788D03*
X637417Y1621796D03*
X640520Y1635483D03*
X649266Y1650126D03*
X642151Y1649961D03*
X639284Y1683049D03*
X647500Y1682850D03*
X635210Y1721545D03*
X650843Y23788D03*
X649585Y29298D03*
X663703Y32574D03*
X653570Y58363D03*
X660775Y78330D03*
X649441Y177003D03*
X662740Y375240D03*
X649500Y382500D03*
X660885Y412588D03*
X650268Y479141D03*
X649771Y505736D03*
X659398Y516260D03*
X658946Y756766D03*
X651904D03*
Y760266D03*
X663496Y773564D03*
X658946Y763766D03*
X651904Y767266D03*
X658046Y786950D03*
X663496Y780257D03*
X651754Y795316D03*
X658046Y796989D03*
X663496Y803682D03*
Y810375D03*
Y817068D03*
X651754Y832127D03*
X658046Y833800D03*
Y823761D03*
X663496Y840493D03*
Y847186D03*
X658046Y860572D03*
X663496Y853879D03*
X651754Y868938D03*
X658046Y870611D03*
X663496Y877304D03*
Y883997D03*
Y890690D03*
X651754Y905750D03*
X658046Y897383D03*
Y907423D03*
X663496Y914115D03*
Y920808D03*
X658046Y934194D03*
X663496Y927501D03*
X651754Y942561D03*
X658046Y944234D03*
X663496Y950926D03*
Y957619D03*
Y964312D03*
Y971005D03*
Y977698D03*
Y984391D03*
Y991084D03*
Y997777D03*
Y1004470D03*
Y1031241D03*
Y1037934D03*
Y1044627D03*
Y1051320D03*
Y1058013D03*
Y1068052D03*
Y1074745D03*
X651754Y1089805D03*
X658046Y1081438D03*
Y1091478D03*
X663496Y1098171D03*
Y1104863D03*
X658046Y1118249D03*
X663496Y1111556D03*
X651754Y1126616D03*
X658046Y1128289D03*
X663496Y1134982D03*
Y1141675D03*
Y1148367D03*
X651754Y1163427D03*
X658046Y1155060D03*
Y1165100D03*
X663496Y1171793D03*
Y1178486D03*
X658046Y1191871D03*
X663496Y1185178D03*
X651754Y1200238D03*
X658046Y1201911D03*
X663496Y1208604D03*
Y1215297D03*
Y1221989D03*
X651754Y1237049D03*
X658046Y1238722D03*
Y1228682D03*
X663496Y1245415D03*
Y1252108D03*
X657836Y1350877D03*
X653836D03*
X650036D03*
X661713Y1373981D03*
X655702Y1391107D03*
X659559Y1391027D03*
X655873Y1428844D03*
X652189Y1421276D03*
X659486Y1452895D03*
X661396Y1450295D03*
X652776D03*
X661396Y1455495D03*
X652776D03*
X662374Y1548563D03*
X651355Y1550797D03*
X651840Y1567752D03*
X660542Y1638169D03*
X657392Y1628137D03*
X652274Y1630366D03*
X650895Y1648115D03*
X655914Y1668744D03*
X659436Y1694697D03*
X649526Y1709274D03*
X663997Y1703111D03*
X659673Y1722174D03*
X661845Y1717340D03*
X654508Y1728000D03*
X654527Y1718229D03*
X659673Y1732836D03*
X672843Y23788D03*
X668739Y45262D03*
X677594Y36205D03*
X675887Y45262D03*
X666411Y69507D03*
X678664Y88080D03*
X673751Y78092D03*
X673691Y200672D03*
X673301Y211332D03*
X671753Y397936D03*
X670000Y457844D03*
X669955Y495468D03*
X671500Y529500D03*
X677055Y776911D03*
X667896Y791970D03*
X677055Y783604D03*
Y807029D03*
Y813722D03*
Y820415D03*
X667896Y828781D03*
X677055Y843840D03*
Y850533D03*
X667896Y865592D03*
X677055Y857226D03*
Y880651D03*
Y887344D03*
Y894037D03*
X667896Y902403D03*
X677055Y917462D03*
Y924155D03*
X667896Y939214D03*
X677055Y930848D03*
Y954273D03*
Y960966D03*
Y967659D03*
Y974352D03*
Y981045D03*
Y987737D03*
Y994430D03*
Y1004470D03*
Y1034588D03*
Y1041281D03*
Y1047974D03*
Y1054667D03*
Y1061360D03*
Y1071399D03*
X667896Y1086458D03*
X677055Y1078092D03*
Y1101517D03*
Y1108210D03*
Y1114903D03*
X667896Y1123269D03*
X677055Y1138328D03*
Y1145021D03*
X667896Y1160080D03*
X677055Y1151714D03*
Y1175139D03*
Y1181832D03*
Y1188525D03*
X667896Y1196891D03*
X677055Y1211950D03*
Y1218643D03*
X667896Y1233702D03*
X677055Y1225336D03*
Y1248761D03*
Y1255454D03*
X674552Y1351988D03*
Y1349488D03*
X666176Y1450295D03*
Y1455495D03*
X666050Y1501670D03*
X672684Y1522690D03*
X674687Y1519726D03*
X665800Y1530575D03*
X674620Y1535271D03*
Y1542125D03*
X672617Y1545089D03*
Y1538235D03*
X674894Y1629042D03*
X673982Y1639289D03*
X665802Y1652337D03*
X674486Y1647842D03*
X673480Y1662668D03*
X671631Y1690786D03*
X693672Y32684D03*
X686855Y43701D03*
X679719Y59066D03*
X682946Y69982D03*
X682891Y72642D03*
X688552Y79166D03*
X681895Y82212D03*
X685783Y78768D03*
X684954Y104968D03*
X691058Y131408D03*
X684521Y152482D03*
X688521D03*
X692521D03*
X682264Y224116D03*
X691547Y386834D03*
X688249Y405628D03*
X679862Y409320D03*
X679500Y526834D03*
X691496Y575081D03*
X688078Y675493D03*
X681605Y756766D03*
X681671Y760178D03*
X688647Y756766D03*
X693197Y773564D03*
X688647Y763766D03*
X681605Y767266D03*
X687747Y786950D03*
X693197Y780257D03*
X681455Y795316D03*
X687747Y796989D03*
X693197Y803682D03*
Y810375D03*
Y817068D03*
X681455Y832127D03*
X687747Y833800D03*
Y823761D03*
X693197Y840493D03*
Y847186D03*
X687747Y860572D03*
X693197Y853879D03*
X681455Y868938D03*
X687747Y870611D03*
X693197Y877304D03*
Y883997D03*
Y890690D03*
X681455Y905750D03*
X687747Y897383D03*
Y907423D03*
X693197Y914115D03*
Y920808D03*
X687747Y934194D03*
X693197Y927501D03*
X681455Y942561D03*
X687747Y944234D03*
X693197Y950926D03*
Y957619D03*
Y964312D03*
Y971005D03*
Y977698D03*
Y984391D03*
Y991084D03*
Y997777D03*
Y1004470D03*
Y1031241D03*
Y1037934D03*
Y1044627D03*
Y1051320D03*
Y1058013D03*
Y1068052D03*
Y1074745D03*
X681455Y1089805D03*
X687747Y1081438D03*
Y1091478D03*
X693197Y1098171D03*
Y1104863D03*
X687747Y1118249D03*
X693197Y1111556D03*
X681455Y1126616D03*
X687747Y1128289D03*
X693197Y1134982D03*
Y1141675D03*
Y1148367D03*
X681455Y1163427D03*
X687747Y1155060D03*
Y1165100D03*
X693197Y1171793D03*
Y1178486D03*
X687747Y1191871D03*
X693197Y1185178D03*
X681455Y1200238D03*
X687747Y1201911D03*
X693197Y1208604D03*
Y1215297D03*
Y1221989D03*
X681455Y1237049D03*
X687747Y1238722D03*
Y1228682D03*
X693197Y1245415D03*
Y1252108D03*
X688076Y1297506D03*
Y1305206D03*
Y1300006D03*
Y1302606D03*
X683052Y1352048D03*
Y1349548D03*
X685187Y1368700D03*
Y1363500D03*
Y1366100D03*
X687577Y1425054D03*
X688120Y1519601D03*
X683352Y1530526D03*
Y1526526D03*
X682016Y1539067D03*
X688308Y1631636D03*
X693150Y1640773D03*
X682925Y1657116D03*
X686825Y1647430D03*
X685485Y1682259D03*
X694843Y23788D03*
X701839Y45112D03*
X707608Y69718D03*
X705570Y133760D03*
X704144Y122602D03*
X707243Y123946D03*
X701927Y166535D03*
Y172441D03*
Y178346D03*
Y184252D03*
Y196063D03*
Y190157D03*
Y201968D03*
Y207874D03*
Y213779D03*
Y219685D03*
X696105Y364149D03*
X696500Y529862D03*
X700500Y545862D03*
X704500Y555862D03*
X701496Y580556D03*
X697392Y601686D03*
X697642Y733401D03*
X706756Y776911D03*
X697597Y791970D03*
X706756Y783604D03*
Y807029D03*
Y813722D03*
Y820415D03*
X697597Y828781D03*
X706756Y843840D03*
Y850533D03*
X697597Y865592D03*
X706756Y857226D03*
Y880651D03*
Y887344D03*
Y894037D03*
X697597Y902403D03*
X706756Y924155D03*
Y917462D03*
X697597Y939214D03*
X706756Y930848D03*
Y954273D03*
Y960966D03*
Y967659D03*
Y974352D03*
Y981045D03*
Y987737D03*
Y994430D03*
Y1004470D03*
Y1041281D03*
Y1034588D03*
Y1047974D03*
Y1054667D03*
Y1071399D03*
Y1061360D03*
Y1078092D03*
X697597Y1086458D03*
X706756Y1101517D03*
Y1114903D03*
Y1108210D03*
X697597Y1123269D03*
X706756Y1145021D03*
Y1138328D03*
Y1151714D03*
X697597Y1160080D03*
X706756Y1175139D03*
Y1181832D03*
Y1188525D03*
X697597Y1196891D03*
X706756Y1211950D03*
Y1218643D03*
Y1225336D03*
X697597Y1233702D03*
X706756Y1248761D03*
Y1255454D03*
X697483Y1297506D03*
Y1305206D03*
Y1300006D03*
Y1302606D03*
X701771Y1351988D03*
Y1349488D03*
X699467Y1368710D03*
Y1363510D03*
Y1366110D03*
X703568Y1379476D03*
X699610Y1580523D03*
X706681Y1627361D03*
X705833Y1633568D03*
X706089Y1643411D03*
X705815Y1654918D03*
X703473Y1663001D03*
X695400Y1685887D03*
X705366Y1684064D03*
X723479Y-28508D03*
X716843Y23788D03*
X717342Y57098D03*
X720328Y344824D03*
X711500Y360862D03*
X719500D03*
X711556Y575081D03*
X714583Y587642D03*
X715037Y603278D03*
X713280Y636897D03*
X712319Y654954D03*
X711306Y756766D03*
Y760178D03*
X718348Y756766D03*
X722898Y773564D03*
X718348Y763766D03*
X711306Y767266D03*
X722898Y780257D03*
X717448Y786950D03*
X722898Y803682D03*
X711156Y795316D03*
X717448Y796989D03*
X722898Y810375D03*
Y817068D03*
X717448Y823761D03*
Y833800D03*
X711156Y832127D03*
X722898Y847186D03*
Y840493D03*
Y853879D03*
X717448Y860572D03*
X722898Y877304D03*
X717448Y870611D03*
X711156Y868938D03*
X722898Y883997D03*
Y890690D03*
X717448Y897383D03*
Y907423D03*
X711156Y905750D03*
X722898Y920808D03*
Y914115D03*
Y927501D03*
X717448Y934194D03*
X722898Y950926D03*
X717448Y944234D03*
X711156Y942561D03*
X722898Y957619D03*
Y971005D03*
Y964312D03*
Y984391D03*
Y977698D03*
Y991084D03*
Y997777D03*
Y1004470D03*
Y1031241D03*
Y1037934D03*
Y1044627D03*
Y1051320D03*
Y1058013D03*
Y1068052D03*
Y1074745D03*
X717448Y1081438D03*
X711156Y1089805D03*
X717448Y1091478D03*
X722898Y1098171D03*
Y1104863D03*
Y1111556D03*
X717448Y1118249D03*
Y1128289D03*
X711156Y1126616D03*
X722898Y1134982D03*
Y1148367D03*
Y1141675D03*
X717448Y1165100D03*
X711156Y1163427D03*
X717448Y1155060D03*
X722898Y1178486D03*
Y1171793D03*
Y1185178D03*
X717448Y1191871D03*
X722898Y1208604D03*
X711156Y1200238D03*
X717448Y1201911D03*
X722898Y1215297D03*
Y1221989D03*
X717448Y1228682D03*
Y1238722D03*
X711156Y1237049D03*
X722898Y1252108D03*
Y1245415D03*
X721361Y1297546D03*
X711954D03*
X721361Y1305246D03*
Y1302646D03*
Y1300046D03*
X711954Y1305246D03*
Y1302646D03*
Y1300046D03*
X710221Y1351988D03*
Y1349488D03*
X716707Y1385281D03*
X719137D03*
X720233Y1378525D03*
Y1381482D03*
Y1375418D03*
X722833D03*
X714277Y1385281D03*
X715033Y1378525D03*
X717633D03*
X712433D03*
X717633Y1381482D03*
X715033Y1375418D03*
X717633D03*
X712433D03*
X719186Y1403296D03*
X719137Y1390881D03*
X714277D03*
X716707D03*
X709551Y1406578D03*
X716770Y1531459D03*
X715122Y1533378D03*
X716989Y1537249D03*
X713357Y1535212D03*
X715224Y1539083D03*
X713459Y1540917D03*
X722876Y1611343D03*
X717749Y1654921D03*
X709771Y1654927D03*
X712354Y1682279D03*
X738843Y23788D03*
X728981Y39872D03*
X736791Y39832D03*
X730131Y60757D03*
X736524Y58069D03*
X730958Y71014D03*
X738044Y71526D03*
X727944Y88972D03*
X727986Y101979D03*
X729900Y98090D03*
X727986Y105477D03*
X737624Y98858D03*
X734524Y98758D03*
X735734Y111988D03*
X726720Y574910D03*
X724001Y636790D03*
X726952Y648667D03*
X736457Y776911D03*
Y783604D03*
X727298Y791970D03*
X736457Y807029D03*
Y813722D03*
Y820415D03*
X727298Y828781D03*
X736457Y843840D03*
Y850533D03*
X727298Y865592D03*
X736457Y857226D03*
Y880651D03*
Y887344D03*
Y894037D03*
X727298Y902403D03*
X736457Y924155D03*
Y917462D03*
X727298Y939214D03*
X736457Y930848D03*
Y954273D03*
Y960966D03*
Y967659D03*
Y974352D03*
Y981045D03*
Y987737D03*
Y994430D03*
Y1004470D03*
Y1034588D03*
Y1041281D03*
Y1047974D03*
Y1054667D03*
Y1071399D03*
Y1061360D03*
X727298Y1086458D03*
X736457Y1078092D03*
Y1101517D03*
Y1114903D03*
Y1108210D03*
X727298Y1123269D03*
X736457Y1145021D03*
Y1138328D03*
X727298Y1160080D03*
X736457Y1151714D03*
Y1175139D03*
Y1181832D03*
Y1188525D03*
X727298Y1196891D03*
X736457Y1211950D03*
Y1218643D03*
X727298Y1233702D03*
X736457Y1225336D03*
Y1248761D03*
Y1255454D03*
X735954Y1297546D03*
Y1305246D03*
Y1302646D03*
Y1300046D03*
X727098Y1351977D03*
X730900Y1352131D03*
X727098Y1349077D03*
X730900Y1349231D03*
X734047Y1372880D03*
X731447D03*
X734047Y1370280D03*
Y1367680D03*
X731447D03*
Y1370280D03*
X728348Y1380832D03*
Y1377875D03*
X736280Y1379580D03*
X732797Y1375380D03*
X725333Y1375418D03*
X727777Y1375434D03*
X738230Y1402898D03*
X734925Y1657826D03*
X730302Y1658050D03*
X726302Y1658022D03*
X738370Y1677909D03*
X736001Y1695509D03*
X728454Y1690491D03*
X732434Y1690660D03*
X738550Y1693215D03*
X742841Y39832D03*
X744477Y58373D03*
X744988Y49062D03*
X747488D03*
X752261Y59782D03*
X745131Y69507D03*
X750090Y72820D03*
X745712Y212760D03*
X746705Y315647D03*
X742278Y566667D03*
X753500Y675800D03*
X748049Y756766D03*
X741007D03*
Y760266D03*
X752599Y773564D03*
X741007Y767266D03*
X748049Y763766D03*
X752599Y780257D03*
X747149Y786950D03*
X752599Y803682D03*
X747149Y796989D03*
X740857Y795316D03*
X752599Y810375D03*
Y817068D03*
X747149Y823761D03*
Y833800D03*
X740857Y832127D03*
X752599Y840493D03*
Y847186D03*
Y853879D03*
X747149Y860572D03*
X752599Y877304D03*
X747149Y870611D03*
X740857Y868938D03*
X752599Y890690D03*
Y883997D03*
X747149Y897383D03*
Y907423D03*
X740857Y905750D03*
X752599Y920808D03*
Y914115D03*
X747149Y934194D03*
X752599Y927501D03*
Y950926D03*
X747149Y944234D03*
X740857Y942561D03*
X752599Y957619D03*
Y971005D03*
Y964312D03*
Y984391D03*
Y977698D03*
Y991084D03*
Y997777D03*
Y1004470D03*
Y1031241D03*
Y1037934D03*
Y1044627D03*
Y1051320D03*
Y1058013D03*
Y1068052D03*
Y1074745D03*
X747149Y1081438D03*
X740857Y1089805D03*
X752599Y1098171D03*
Y1104863D03*
X747149Y1091478D03*
X752599Y1111556D03*
X747149Y1118249D03*
Y1128289D03*
X740857Y1126616D03*
X752599Y1134982D03*
Y1148367D03*
Y1141675D03*
X740857Y1163427D03*
X747149Y1165100D03*
Y1155060D03*
X752599Y1178486D03*
Y1171793D03*
Y1185178D03*
X747149Y1191871D03*
X752599Y1208604D03*
X740857Y1200238D03*
X747149Y1201911D03*
X752599Y1215297D03*
Y1221989D03*
X747149Y1228682D03*
Y1238722D03*
X740857Y1237049D03*
X752599Y1252108D03*
Y1245415D03*
X745475Y1297246D03*
Y1304946D03*
Y1302346D03*
Y1299746D03*
X739500Y1352031D03*
Y1349131D03*
X753015Y1381582D03*
Y1378625D03*
Y1375518D03*
X747059Y1385381D03*
X745215Y1378625D03*
X747815D03*
Y1375518D03*
X745215D03*
X750415Y1381582D03*
Y1378625D03*
Y1375518D03*
X749489Y1385381D03*
X751919D03*
X751968Y1403396D03*
X751919Y1390981D03*
X747059D03*
X749489D03*
X739888Y1404849D03*
X743740Y1657327D03*
X743039Y1643326D03*
X760843Y23788D03*
X754621Y74562D03*
X754634Y105288D03*
Y108288D03*
X762173Y123898D03*
X770073Y143438D03*
X756083Y220240D03*
X757464Y284087D03*
X754556Y283976D03*
X755335Y295589D03*
X758959Y319596D03*
X753959Y343790D03*
X766158Y776911D03*
Y783604D03*
X756999Y791970D03*
X766158Y807029D03*
Y813722D03*
Y820415D03*
X756999Y828781D03*
X766158Y843840D03*
Y850533D03*
Y857226D03*
X756999Y865592D03*
X766158Y880651D03*
Y887344D03*
Y894037D03*
X756999Y902403D03*
X766158Y924155D03*
Y917462D03*
X756999Y939214D03*
X766158Y930848D03*
Y954273D03*
Y960966D03*
Y967659D03*
Y974352D03*
Y981045D03*
Y987737D03*
Y994430D03*
Y1004470D03*
Y1041281D03*
Y1034588D03*
Y1047974D03*
Y1054667D03*
Y1071399D03*
Y1061360D03*
X756999Y1086458D03*
X766158Y1078092D03*
Y1101517D03*
Y1114903D03*
Y1108210D03*
X756999Y1123269D03*
X766158Y1145021D03*
Y1138328D03*
X756999Y1160080D03*
X766158Y1151714D03*
Y1175139D03*
Y1181832D03*
Y1188525D03*
X756999Y1196891D03*
X766158Y1211950D03*
Y1218643D03*
Y1225336D03*
X756999Y1233702D03*
X766158Y1248761D03*
Y1255454D03*
X759854Y1297246D03*
Y1304946D03*
Y1302346D03*
Y1299746D03*
X761800Y1352031D03*
Y1349131D03*
X764229Y1372880D03*
X766829D03*
Y1370380D03*
Y1367780D03*
X764229D03*
Y1370380D03*
X761130Y1380932D03*
Y1377975D03*
X755615Y1375518D03*
X758115D03*
X760559Y1375534D03*
X765579Y1375480D03*
X767381Y1676594D03*
X769475Y75360D03*
X771356Y167518D03*
X773221Y296262D03*
X780618Y296345D03*
X779121Y306155D03*
X773944Y312588D03*
X780808Y419865D03*
X777900Y756766D03*
X770708D03*
Y760266D03*
X782300Y773564D03*
X770708Y767266D03*
X777900Y763766D03*
X776850Y786950D03*
X782300Y780257D03*
X776850Y796989D03*
X770558Y795316D03*
X782300Y803682D03*
Y810375D03*
Y817068D03*
X770558Y832127D03*
X776850Y823761D03*
Y833800D03*
X782300Y847186D03*
Y840493D03*
X776850Y860572D03*
X782300Y853879D03*
Y877304D03*
X776850Y870611D03*
X770558Y868938D03*
X782300Y890690D03*
Y883997D03*
X776850Y897383D03*
Y907423D03*
X770558Y905750D03*
X782300Y920808D03*
Y914115D03*
X776850Y934194D03*
X782300Y927501D03*
X776850Y944234D03*
X770558Y942561D03*
X782300Y950926D03*
Y957619D03*
Y971005D03*
Y964312D03*
Y984391D03*
Y977698D03*
Y991084D03*
Y997777D03*
Y1004470D03*
Y1031241D03*
Y1037934D03*
Y1044627D03*
Y1051320D03*
Y1058013D03*
Y1068052D03*
Y1074745D03*
X776850Y1081438D03*
X770558Y1089805D03*
X782300Y1098171D03*
Y1104863D03*
X776850Y1091478D03*
Y1118249D03*
X782300Y1111556D03*
X776850Y1128289D03*
X770558Y1126616D03*
X782300Y1134982D03*
Y1148367D03*
Y1141675D03*
X776850Y1165100D03*
X770558Y1163427D03*
X776850Y1155060D03*
X782300Y1178486D03*
Y1171793D03*
Y1185178D03*
X776850Y1191871D03*
X782300Y1208604D03*
X770558Y1200238D03*
X776850Y1201911D03*
X782300Y1215297D03*
Y1221989D03*
X776850Y1228682D03*
Y1238722D03*
X770558Y1237049D03*
X782300Y1252108D03*
Y1245415D03*
X769521Y1297199D03*
Y1304899D03*
Y1299699D03*
Y1302299D03*
X770990Y1349091D03*
Y1351991D03*
X773069Y1375500D03*
X770469D03*
X776010Y1380750D03*
X787456Y49379D03*
X797594Y282233D03*
X797444Y271469D03*
X795668Y298801D03*
X792488Y377452D03*
X797252Y459344D03*
Y471344D03*
X794425Y541425D03*
X794059Y553559D03*
X791500Y560000D03*
X785000Y563500D03*
X795858Y776911D03*
Y783604D03*
X786700Y791970D03*
X795858Y807029D03*
Y820415D03*
Y813722D03*
X786700Y828781D03*
X795858Y843840D03*
Y850533D03*
X786700Y865592D03*
X795858Y857226D03*
Y880651D03*
Y894037D03*
Y887344D03*
X786700Y902403D03*
X795858Y924155D03*
Y917462D03*
X786700Y939214D03*
X795858Y930848D03*
Y954273D03*
Y960966D03*
Y967659D03*
Y981045D03*
Y974352D03*
Y994430D03*
Y987737D03*
Y1004470D03*
Y1041281D03*
Y1034588D03*
Y1054667D03*
Y1047974D03*
Y1071399D03*
Y1061360D03*
X786700Y1086458D03*
X795858Y1078092D03*
Y1101517D03*
Y1114903D03*
Y1108210D03*
X786700Y1123269D03*
X795858Y1145021D03*
Y1138328D03*
X786700Y1160080D03*
X795858Y1151714D03*
Y1175139D03*
Y1181832D03*
Y1188525D03*
X786700Y1196891D03*
X795858Y1218643D03*
Y1211950D03*
X786700Y1233702D03*
X795858Y1225336D03*
Y1248761D03*
Y1255454D03*
X809456Y49379D03*
X806984Y265653D03*
X798621Y312773D03*
X803264Y330102D03*
X808401Y341670D03*
X811569Y387674D03*
X813175Y422687D03*
X810360Y442079D03*
X802752Y455344D03*
X812500Y504000D03*
X807450Y756766D03*
X800408D03*
Y760266D03*
X812000Y773564D03*
X800408Y767266D03*
X812000Y780257D03*
X806550Y786950D03*
X812000Y803682D03*
X806550Y796989D03*
X800258Y795316D03*
X812000Y817068D03*
Y810375D03*
X800258Y832127D03*
X806550Y833800D03*
Y823761D03*
X812000Y847186D03*
Y840493D03*
X806550Y860572D03*
X812000Y853879D03*
Y877304D03*
X806550Y870611D03*
X800258Y868938D03*
X812000Y890690D03*
Y883997D03*
X806550Y897383D03*
Y907423D03*
X800258Y905750D03*
X812000Y920808D03*
Y914115D03*
Y927501D03*
X806550Y934194D03*
X812000Y950926D03*
X800258Y942561D03*
X806550Y944234D03*
X812000Y957619D03*
Y971005D03*
Y964312D03*
Y984391D03*
Y977698D03*
Y997777D03*
Y991084D03*
Y1004470D03*
Y1044627D03*
Y1037934D03*
Y1031241D03*
Y1058013D03*
Y1051320D03*
Y1068052D03*
Y1074745D03*
X806550Y1081438D03*
X800258Y1089805D03*
X812000Y1098171D03*
Y1104863D03*
X806550Y1091478D03*
X812000Y1111556D03*
X806550Y1118249D03*
Y1128289D03*
X800258Y1126616D03*
X812000Y1134982D03*
Y1148367D03*
Y1141675D03*
X806550Y1165100D03*
X800258Y1163427D03*
X806550Y1155060D03*
X812000Y1178486D03*
Y1171793D03*
Y1185178D03*
X806550Y1191871D03*
X812000Y1208604D03*
X806550Y1201911D03*
X800258Y1200238D03*
X812000Y1221989D03*
Y1215297D03*
X806550Y1228682D03*
Y1238722D03*
X800258Y1237049D03*
X812000Y1245415D03*
Y1252108D03*
X822699Y56712D03*
X821119Y134632D03*
X825699Y139062D03*
X816322Y284369D03*
X826665Y423425D03*
X817426Y487232D03*
X824500Y514500D03*
X817441Y517941D03*
X822559Y530876D03*
X826552Y543612D03*
X823777Y560988D03*
X816400Y828781D03*
Y865592D03*
Y902403D03*
Y939214D03*
Y1086458D03*
Y1123269D03*
Y1160080D03*
Y1196891D03*
Y1233702D03*
X826112Y1269546D03*
X833407Y-26181D03*
X836660Y-26167D03*
Y-16167D03*
X833407Y-16181D03*
X839700Y-14972D03*
X833422Y-13666D03*
X836675Y-13652D03*
X833412Y-19948D03*
X836674D03*
X836675Y-23652D03*
X833422Y-23666D03*
X839700Y-24972D03*
X833412Y52D03*
X836674D03*
X833412Y-9948D03*
X836674D03*
X836675Y-3652D03*
X833422Y-3666D03*
X839700Y-4972D03*
X833407Y-6181D03*
X836660Y-6167D03*
X836675Y16348D03*
X833422Y16334D03*
X839700Y15028D03*
X833407Y13819D03*
X836660Y13833D03*
X836674Y10052D03*
X833412D03*
X836675Y6348D03*
X833422Y6334D03*
X839700Y5028D03*
X833407Y3819D03*
X836660Y3833D03*
X836659Y24250D03*
X836674Y26765D03*
X833406Y24236D03*
X839699Y25445D03*
X833421Y26751D03*
X833376Y19206D03*
X833391Y21721D03*
X831456Y49379D03*
X836127Y62681D03*
X837792Y85186D03*
X831298Y104206D03*
X834616Y94324D03*
X842865Y110296D03*
X830340Y228143D03*
X832525Y268579D03*
X829572Y296511D03*
X840288Y287593D03*
X829167Y288063D03*
X832686Y331028D03*
X836840Y382003D03*
X841862Y390441D03*
X834430Y434634D03*
X834251Y459578D03*
X835425Y477890D03*
X830743Y500740D03*
X831756Y901318D03*
X835554Y1281324D03*
X835682Y1285472D03*
X836670Y1291355D03*
X836587Y1295333D03*
X842500Y1310000D03*
Y1306000D03*
Y1302000D03*
X834017Y1333584D03*
X834071Y1342457D03*
X839188Y1348937D03*
X841203Y1361376D03*
X853456Y49379D03*
X854108Y91232D03*
X851895Y160141D03*
X853800Y265057D03*
X847939Y265092D03*
X854334Y276117D03*
X854225Y280027D03*
Y283527D03*
X857334Y276117D03*
X852780Y291559D03*
X852801Y288562D03*
X853201Y297462D03*
X856701Y304862D03*
X846275Y335575D03*
X849750Y401280D03*
X852240Y470946D03*
X849126Y530138D03*
X845126D03*
X848660Y651127D03*
X846725Y1269785D03*
X861351Y61672D03*
X858528Y262382D03*
X860834Y276817D03*
X863934Y276917D03*
X862044Y290047D03*
X862075Y398537D03*
X872020Y413300D03*
X867590Y642420D03*
X864700Y836100D03*
X859446Y1284288D03*
X875345Y51595D03*
X877462Y139540D03*
X878221Y192055D03*
X880944Y283347D03*
Y286347D03*
X875447Y301500D03*
X884740Y316000D03*
X874500Y328000D03*
X873884Y453383D03*
X886707Y1254742D03*
Y1251742D03*
X881807Y1248920D03*
Y1245920D03*
X881937Y1251857D03*
X877480Y1248844D03*
X886707Y1257742D03*
X885000Y1307500D03*
X877000Y1340241D03*
X884462Y1446974D03*
X876044Y1444317D03*
X898720Y145206D03*
X888560Y469527D03*
X902376Y594657D03*
X903556Y614062D03*
X899678Y601043D03*
X897824Y909093D03*
X891648Y1137843D03*
X900723Y1146553D03*
X896107Y1254742D03*
Y1251742D03*
X896907Y1245920D03*
Y1248920D03*
X896107Y1257742D03*
X917386Y179500D03*
Y177000D03*
Y169500D03*
Y172000D03*
Y174500D03*
Y167000D03*
X909298Y195925D03*
X909161Y203012D03*
X909320Y210098D03*
Y217185D03*
Y224271D03*
Y231358D03*
X914575Y560027D03*
X906597Y579695D03*
X907035Y590172D03*
X906597Y628426D03*
X906734Y619373D03*
X906570Y663930D03*
X906387Y818471D03*
X903941Y874000D03*
X917622Y887545D03*
X909000Y909000D03*
X905000D03*
X904719Y921792D03*
X911500Y931000D03*
X908500Y927500D03*
X909890Y950217D03*
X910066Y960332D03*
X909203Y970709D03*
X916763Y972343D03*
X908799Y985291D03*
X910707Y1254742D03*
Y1251742D03*
X905007Y1248920D03*
Y1245920D03*
X905074Y1252177D03*
X910707Y1257742D03*
X920720Y145206D03*
X919886Y167000D03*
Y169500D03*
Y172000D03*
Y174500D03*
Y177000D03*
Y179500D03*
X927134Y189386D03*
X925321Y203399D03*
X926983Y604751D03*
X927127Y619251D03*
X930926Y664791D03*
X923916Y843990D03*
X918500Y856925D03*
X930925Y860925D03*
X929603Y889000D03*
X931948Y891397D03*
X919916Y908916D03*
X920276Y900554D03*
X931877Y918168D03*
X928535Y913454D03*
X920409Y918274D03*
X918000Y928000D03*
X926062Y938727D03*
X926004Y952716D03*
X925200Y1110443D03*
Y1107843D03*
Y1117443D03*
Y1114843D03*
Y1124443D03*
Y1121843D03*
Y1131443D03*
Y1128843D03*
X920107Y1251742D03*
Y1254742D03*
Y1248920D03*
Y1245920D03*
Y1257742D03*
X924000Y1310000D03*
X920738Y1321363D03*
X927869Y1317417D03*
X923680Y1339520D03*
X919758Y1348990D03*
X931798Y1660762D03*
X923798D03*
X945006Y593609D03*
X935649Y590751D03*
X939391Y600571D03*
X946366Y668811D03*
X940391Y859947D03*
X944057Y882886D03*
X940514Y918134D03*
X933021Y933979D03*
X939670Y945169D03*
X942924Y982547D03*
X943135Y977129D03*
X938507Y1137843D03*
X945691Y1254742D03*
Y1251742D03*
X940791Y1248920D03*
Y1245920D03*
X940921Y1251857D03*
X936464Y1248844D03*
X945691Y1257742D03*
X938000Y1309500D03*
Y1301500D03*
Y1304500D03*
X933586Y1325501D03*
X933041Y1315920D03*
X939798Y1660762D03*
X955529Y614017D03*
X951839Y812730D03*
X958051Y859384D03*
X952425Y876575D03*
X948060Y891468D03*
X951367Y913648D03*
X951500Y930925D03*
X955091Y1254742D03*
Y1251742D03*
X955891Y1245920D03*
Y1248920D03*
X955000Y1267000D03*
X955091Y1257742D03*
X955000Y1271000D03*
Y1275000D03*
Y1279000D03*
X960518Y1656185D03*
X957758D03*
X957848Y1659375D03*
X960608D03*
X960558Y1662015D03*
X957798D03*
X947798Y1660762D03*
X964720Y145206D03*
X975689Y156950D03*
Y153950D03*
X971192Y219589D03*
X968692D03*
X973616Y317648D03*
X963134Y882936D03*
X968919Y1116177D03*
Y1118777D03*
Y1109177D03*
Y1111777D03*
X968800Y1130046D03*
Y1132646D03*
X968919Y1123177D03*
Y1125777D03*
X969691Y1254742D03*
Y1251742D03*
X963991Y1248920D03*
Y1245920D03*
X964058Y1252177D03*
X969691Y1257742D03*
X975000Y1307500D03*
X967500Y1340241D03*
X976858Y1656185D03*
X976898Y1662015D03*
X976948Y1659375D03*
X986720Y145206D03*
X988593Y189347D03*
X981445Y185389D03*
X982455Y264781D03*
Y275443D03*
X989227Y389311D03*
X992037Y485369D03*
X979091Y1251742D03*
Y1254742D03*
Y1248920D03*
Y1245920D03*
Y1257742D03*
X985318Y1656105D03*
X988078D03*
X979618Y1656185D03*
X985358Y1661935D03*
X988118D03*
X985408Y1659295D03*
X988168D03*
X979658Y1662015D03*
X979708Y1659375D03*
X995189Y263340D03*
Y274002D03*
X992915Y280389D03*
X1007083Y363461D03*
X996232Y424440D03*
X999304Y1282574D03*
Y1289215D03*
X999303Y1285693D03*
X1004418Y1656105D03*
X1007178D03*
X1004508Y1659295D03*
X1004458Y1661935D03*
X1008720Y145206D03*
X1020661Y146580D03*
X1023221Y191574D03*
X1019803Y218099D03*
X1017870Y294386D03*
X1009618Y396125D03*
X1021425Y404925D03*
X1013365Y433426D03*
X1008789Y488642D03*
Y493655D03*
X1012211Y547574D03*
X1015061D03*
X1015961Y554432D03*
X1007703Y759012D03*
X1007587Y800384D03*
Y802884D03*
Y811352D03*
Y813852D03*
Y822252D03*
Y824752D03*
Y833356D03*
Y835856D03*
Y844256D03*
X1021908Y1289124D03*
X1019314Y1289159D03*
X1017069Y1290346D03*
X1013500Y1312500D03*
X1013000Y1306500D03*
X1013500Y1325500D03*
X1011500Y1335000D03*
X1013500Y1344500D03*
X1007268Y1659295D03*
X1007218Y1661935D03*
X1023187Y146580D03*
X1027724Y397726D03*
X1030525Y391362D03*
X1027760Y451832D03*
X1022461Y558932D03*
X1027579D03*
X1032579Y559934D03*
X1025493Y768719D03*
X1035645Y773582D03*
X1033798Y1656675D03*
X1033748Y1659315D03*
X1040199Y49379D03*
X1040891Y406586D03*
X1045100Y427059D03*
X1045015Y444404D03*
X1041254Y523874D03*
X1043180Y547027D03*
X1040890Y735717D03*
X1050015Y756765D03*
Y760265D03*
X1045465Y776910D03*
X1050015Y767265D03*
X1045465Y783603D03*
X1041065Y795315D03*
X1045465Y807028D03*
Y813721D03*
Y820414D03*
X1041065Y832126D03*
X1045465Y850532D03*
Y843839D03*
Y857225D03*
X1041065Y868937D03*
X1045465Y880650D03*
Y887343D03*
Y894036D03*
X1041065Y905749D03*
X1045465Y917461D03*
Y924154D03*
Y930847D03*
X1041065Y942560D03*
X1045465Y954272D03*
Y967658D03*
Y960965D03*
Y974351D03*
Y981044D03*
Y987736D03*
Y994429D03*
Y1004469D03*
Y1041280D03*
Y1034587D03*
Y1047973D03*
Y1054666D03*
Y1061359D03*
Y1071398D03*
Y1078091D03*
X1041065Y1089804D03*
X1045465Y1101516D03*
Y1108209D03*
Y1114902D03*
X1041065Y1126615D03*
X1045465Y1138327D03*
Y1145020D03*
Y1151713D03*
X1041065Y1163426D03*
X1045465Y1175138D03*
Y1188524D03*
Y1181831D03*
X1041065Y1200237D03*
X1045465Y1211949D03*
Y1218642D03*
X1041065Y1237048D03*
X1045465Y1225335D03*
Y1248760D03*
Y1255453D03*
X1048684Y1350724D03*
X1051684D03*
X1050866Y1659548D03*
X1062199Y49379D03*
X1061456Y406560D03*
X1063614Y733409D03*
X1057057Y756765D03*
X1061607Y773563D03*
X1057057Y763765D03*
X1057207Y791969D03*
X1056157Y786949D03*
X1061607Y780256D03*
Y803681D03*
X1056157Y796988D03*
X1061607Y810374D03*
Y817067D03*
X1056157Y823760D03*
Y833799D03*
X1057207Y828780D03*
X1061607Y847185D03*
Y840492D03*
Y853878D03*
X1056157Y860571D03*
X1057207Y865591D03*
X1056157Y870610D03*
X1061607Y877303D03*
Y883996D03*
Y890689D03*
X1056157Y907422D03*
Y897382D03*
X1057207Y902402D03*
X1061607Y914114D03*
Y920807D03*
Y927500D03*
X1056157Y934193D03*
X1057207Y939213D03*
X1061607Y950925D03*
X1056157Y944233D03*
X1061607Y964311D03*
Y971004D03*
Y957618D03*
Y977697D03*
Y984390D03*
Y991083D03*
Y997776D03*
Y1004469D03*
Y1037933D03*
Y1044626D03*
Y1031240D03*
Y1051319D03*
Y1058012D03*
Y1074744D03*
Y1068051D03*
X1057207Y1086457D03*
X1056157Y1081437D03*
Y1091477D03*
X1061607Y1098170D03*
Y1104862D03*
X1056157Y1118248D03*
X1061607Y1111555D03*
Y1134981D03*
X1057207Y1123268D03*
X1056157Y1128288D03*
X1061607Y1141674D03*
Y1148366D03*
X1056157Y1155059D03*
Y1165099D03*
X1057207Y1160079D03*
X1061607Y1171792D03*
Y1178485D03*
X1056157Y1191870D03*
X1061607Y1185177D03*
X1056157Y1201910D03*
X1057207Y1196890D03*
X1061607Y1208603D03*
Y1215296D03*
Y1221988D03*
X1056157Y1238721D03*
X1057207Y1233701D03*
X1056157Y1228681D03*
X1061607Y1245414D03*
Y1252107D03*
X1060684Y1350724D03*
X1057684D03*
X1054684D03*
X1063751Y1653834D03*
X1064221Y1662726D03*
X1068221Y1662778D03*
X1068827Y389734D03*
X1074800Y391262D03*
X1077418Y411322D03*
Y416763D03*
Y421922D03*
X1081133Y461516D03*
X1071239Y479655D03*
X1081632Y648854D03*
X1079716Y756765D03*
Y760265D03*
Y767265D03*
X1075166Y776910D03*
Y783603D03*
X1070766Y795315D03*
X1075166Y807028D03*
Y813721D03*
Y820414D03*
X1070766Y832126D03*
X1075166Y850532D03*
Y843839D03*
Y857225D03*
X1070766Y868937D03*
X1075166Y880650D03*
Y887343D03*
Y894036D03*
X1070766Y905749D03*
X1075166Y917461D03*
Y924154D03*
Y930847D03*
X1070766Y942560D03*
X1075166Y954272D03*
Y967658D03*
Y960965D03*
Y974351D03*
Y981044D03*
Y987736D03*
Y994429D03*
Y1004469D03*
Y1034587D03*
Y1041280D03*
Y1047973D03*
Y1054666D03*
Y1061359D03*
Y1071398D03*
Y1078091D03*
X1070766Y1089804D03*
X1075166Y1101516D03*
Y1108209D03*
Y1114902D03*
X1070766Y1126615D03*
X1075166Y1138327D03*
Y1145020D03*
Y1151713D03*
X1070766Y1163426D03*
X1075166Y1175138D03*
Y1188524D03*
Y1181831D03*
X1070766Y1200237D03*
X1075166Y1211949D03*
Y1218642D03*
X1070766Y1237048D03*
X1075166Y1225335D03*
Y1248760D03*
Y1255453D03*
X1070949Y1337752D03*
X1067929Y1337702D03*
X1079215Y1357390D03*
X1076615D03*
X1071908Y1361660D03*
X1080889Y1367253D03*
X1076615Y1360497D03*
X1079215D03*
X1078459Y1367253D03*
Y1372853D03*
X1080889D03*
X1073733Y1388198D03*
X1068094Y1654099D03*
X1084199Y49379D03*
X1086936Y370532D03*
X1083583Y395195D03*
X1093722Y427960D03*
X1087000Y477500D03*
X1096473Y484391D03*
Y489391D03*
X1088730Y509362D03*
X1086758Y756765D03*
X1091308Y773563D03*
X1086758Y763765D03*
X1086908Y791969D03*
X1091308Y780256D03*
X1085858Y786949D03*
X1091308Y803681D03*
X1085858Y796988D03*
X1091308Y810374D03*
Y817067D03*
X1085858Y823760D03*
Y833799D03*
X1086908Y828780D03*
X1091308Y840492D03*
Y847185D03*
Y853878D03*
X1085858Y860571D03*
X1086908Y865591D03*
X1085858Y870610D03*
X1091308Y877303D03*
Y883996D03*
Y890689D03*
X1085858Y907422D03*
Y897382D03*
X1086908Y902402D03*
X1091308Y914114D03*
Y920807D03*
X1085858Y934193D03*
X1091308Y927500D03*
X1086908Y939213D03*
X1085858Y944233D03*
X1091308Y950925D03*
Y964311D03*
Y971004D03*
Y957618D03*
Y977697D03*
Y984390D03*
Y991083D03*
Y997776D03*
Y1004469D03*
Y1031240D03*
Y1037933D03*
Y1044626D03*
Y1051319D03*
Y1058012D03*
Y1074744D03*
Y1068051D03*
X1086908Y1086457D03*
X1085858Y1081437D03*
Y1091477D03*
X1091308Y1098170D03*
Y1104862D03*
X1085858Y1118248D03*
X1091308Y1111555D03*
Y1134981D03*
X1086908Y1123268D03*
X1085858Y1128288D03*
X1091308Y1141674D03*
Y1148366D03*
X1085858Y1155059D03*
Y1165099D03*
X1086908Y1160079D03*
X1091308Y1171792D03*
Y1178485D03*
X1085858Y1191870D03*
X1091308Y1185177D03*
X1085858Y1201910D03*
X1086908Y1196890D03*
X1091308Y1208603D03*
Y1215296D03*
Y1221988D03*
X1085858Y1238721D03*
Y1228681D03*
X1086908Y1233701D03*
X1091308Y1245414D03*
Y1252107D03*
X1095809Y1337824D03*
X1087015Y1357390D03*
X1095629Y1352252D03*
Y1349652D03*
Y1354852D03*
X1089515Y1357390D03*
X1091959Y1357406D03*
X1084415Y1357390D03*
X1081815D03*
X1092905Y1363394D03*
Y1360437D03*
X1083319Y1367253D03*
X1081815Y1360497D03*
X1084415D03*
X1081815Y1363454D03*
X1084415D03*
X1083319Y1372853D03*
X1083368Y1385268D03*
X1096469Y1643468D03*
X1090143Y1643625D03*
X1091026Y1653031D03*
X1092030Y1720841D03*
X1106199Y49379D03*
X1101942Y395361D03*
X1109416Y756765D03*
Y760265D03*
Y767265D03*
X1104866Y776910D03*
Y783603D03*
X1100466Y795315D03*
X1104866Y807028D03*
Y813721D03*
Y820414D03*
X1100466Y832126D03*
X1104866Y850532D03*
Y843839D03*
Y857225D03*
X1100466Y868937D03*
X1104866Y880650D03*
Y887343D03*
Y894036D03*
X1100466Y905749D03*
X1104866Y917461D03*
Y924154D03*
Y930847D03*
X1100466Y942560D03*
X1104866Y954272D03*
Y967658D03*
Y960965D03*
Y974351D03*
Y981044D03*
Y987736D03*
Y994429D03*
Y1004469D03*
Y1034587D03*
Y1041280D03*
Y1047973D03*
Y1054666D03*
Y1071398D03*
Y1061359D03*
Y1078091D03*
X1100466Y1089804D03*
X1104866Y1101516D03*
Y1108209D03*
Y1114902D03*
X1100466Y1126615D03*
X1104866Y1138327D03*
Y1145020D03*
Y1151713D03*
X1100466Y1163426D03*
X1104866Y1175138D03*
Y1188524D03*
Y1181831D03*
X1100466Y1200237D03*
X1104866Y1211949D03*
Y1218642D03*
X1100466Y1237048D03*
X1104866Y1225335D03*
Y1248760D03*
Y1255453D03*
X1103529Y1337792D03*
X1109289Y1337752D03*
X1098409Y1337824D03*
X1109215Y1357390D03*
X1098229Y1352252D03*
Y1349652D03*
X1096979Y1357352D03*
X1098229Y1354852D03*
X1104448Y1361680D03*
X1109215Y1360497D03*
X1111059Y1367253D03*
Y1372853D03*
X1103888Y1386721D03*
X1102230Y1384770D03*
X1105000Y1682132D03*
X1109521Y1724109D03*
X1113943Y452055D03*
X1116458Y756765D03*
X1121008Y773563D03*
X1116459Y763765D03*
X1116608Y791969D03*
X1121008Y780256D03*
X1115558Y786949D03*
X1121008Y803681D03*
X1115558Y796988D03*
X1121008Y810374D03*
Y817067D03*
X1115558Y823760D03*
Y833799D03*
X1116608Y828780D03*
X1121008Y847185D03*
Y840492D03*
Y853878D03*
X1115558Y860571D03*
X1116608Y865591D03*
X1115558Y870610D03*
X1121008Y877303D03*
Y883996D03*
Y890689D03*
X1115558Y907422D03*
Y897382D03*
X1116608Y902402D03*
X1121008Y914114D03*
Y920807D03*
X1115558Y934193D03*
X1121008Y927500D03*
X1116608Y939213D03*
X1115558Y944233D03*
X1121008Y950925D03*
Y964311D03*
Y971004D03*
Y957618D03*
Y977697D03*
Y984390D03*
Y991083D03*
Y997776D03*
Y1004469D03*
Y1031240D03*
Y1037933D03*
Y1044626D03*
Y1051319D03*
Y1058012D03*
Y1074744D03*
Y1068051D03*
X1116608Y1086457D03*
X1115558Y1081437D03*
Y1091477D03*
X1121008Y1098170D03*
Y1104862D03*
X1115558Y1118248D03*
X1121008Y1111555D03*
Y1134981D03*
X1116608Y1123268D03*
X1115558Y1128288D03*
X1121008Y1141674D03*
Y1148366D03*
X1115558Y1155059D03*
Y1165099D03*
X1116608Y1160079D03*
X1121008Y1171792D03*
Y1178485D03*
X1115558Y1191870D03*
X1121008Y1185177D03*
X1115558Y1201910D03*
X1116608Y1196890D03*
X1121008Y1208603D03*
Y1215296D03*
Y1221988D03*
X1115558Y1238721D03*
Y1228681D03*
X1116608Y1233701D03*
X1121008Y1245414D03*
Y1252107D03*
X1119615Y1357390D03*
X1122115D03*
X1124559Y1357406D03*
X1117015Y1357390D03*
X1111815D03*
X1114415D03*
X1117015Y1363454D03*
Y1360497D03*
X1115919Y1372853D03*
X1125505Y1363394D03*
Y1360437D03*
X1115919Y1367253D03*
X1113489D03*
X1114415Y1363454D03*
X1111815Y1360497D03*
X1114415D03*
X1113489Y1372853D03*
X1115968Y1385268D03*
X1117946Y1467955D03*
X1117828Y1473091D03*
X1118326Y1594118D03*
X1118004Y1584908D03*
X1113785Y1601462D03*
X1117263Y1601526D03*
X1115394Y1620306D03*
X1120376Y1641684D03*
X1125487Y1641754D03*
X1125771Y1652189D03*
X1120595Y1652037D03*
X1120200Y1646597D03*
X1116000Y1671029D03*
X1125732Y1666072D03*
X1120303Y1682055D03*
X1113948Y1714244D03*
X1128199Y49379D03*
X1142830Y53186D03*
X1139200Y380533D03*
Y385698D03*
X1127471Y404788D03*
X1132387Y615658D03*
X1139117Y756765D03*
Y760265D03*
Y767265D03*
X1134567Y776910D03*
Y783603D03*
X1130167Y795315D03*
X1134567Y807028D03*
Y813721D03*
Y820414D03*
X1130167Y832126D03*
X1134567Y850532D03*
Y843839D03*
Y857225D03*
X1130167Y868937D03*
X1134567Y880650D03*
Y887343D03*
Y894036D03*
X1130167Y905749D03*
X1134567Y917461D03*
Y924154D03*
Y930847D03*
X1130167Y942560D03*
X1134567Y954272D03*
Y967658D03*
Y960965D03*
Y974351D03*
Y981044D03*
Y987736D03*
Y994429D03*
Y1004469D03*
Y1034587D03*
Y1041280D03*
Y1047973D03*
Y1054666D03*
Y1061359D03*
Y1071398D03*
X1130167Y1089804D03*
X1134567Y1078091D03*
Y1101516D03*
Y1108209D03*
Y1114902D03*
X1130167Y1126615D03*
X1134567Y1138327D03*
Y1145020D03*
X1130167Y1163426D03*
X1134567Y1151713D03*
Y1175138D03*
Y1188524D03*
Y1181831D03*
X1130167Y1200237D03*
X1134567Y1211949D03*
Y1218642D03*
X1130167Y1237048D03*
X1134567Y1225335D03*
Y1248760D03*
Y1255453D03*
X1136219Y1337794D03*
X1133619D03*
X1130829Y1352252D03*
Y1349652D03*
Y1354852D03*
X1128229Y1352252D03*
Y1349652D03*
X1129579Y1357352D03*
X1128229Y1354852D03*
X1137218Y1361660D03*
X1136588Y1386721D03*
X1134930Y1384770D03*
X1137846Y1453487D03*
X1135043Y1553371D03*
X1137523Y1579453D03*
X1136173Y1573638D03*
X1131790Y1597984D03*
X1131832Y1607245D03*
X1132168Y1620860D03*
X1138752Y1624627D03*
X1130772Y1641753D03*
X1130684Y1646949D03*
X1130245Y1652189D03*
X1140117Y1671421D03*
X1132209Y1672033D03*
X1129230Y1666174D03*
X1137492Y1685240D03*
X1128934Y1688600D03*
X1150199Y49379D03*
X1155577Y73939D03*
X1147813Y492319D03*
X1146159Y756765D03*
X1150709Y773563D03*
X1146160Y763765D03*
X1146309Y791969D03*
X1145259Y786949D03*
X1150709Y780256D03*
X1145259Y796988D03*
X1150709Y803681D03*
Y810374D03*
Y817067D03*
X1146309Y828780D03*
X1145259Y823760D03*
Y833799D03*
X1150709Y840492D03*
Y847185D03*
X1146309Y865591D03*
X1145259Y860571D03*
X1150709Y853878D03*
X1145259Y870610D03*
X1150709Y877303D03*
Y883996D03*
Y890689D03*
X1145259Y907422D03*
X1146309Y902402D03*
X1145259Y897382D03*
X1150709Y914114D03*
Y920807D03*
X1145259Y934193D03*
X1146309Y939213D03*
X1150709Y927500D03*
X1145259Y944233D03*
X1150709Y950925D03*
Y964311D03*
Y971004D03*
Y957618D03*
Y977697D03*
Y984390D03*
Y991083D03*
Y997776D03*
Y1004469D03*
Y1031240D03*
Y1037933D03*
Y1044626D03*
Y1051319D03*
Y1058012D03*
Y1074744D03*
Y1068051D03*
X1146309Y1086457D03*
X1145259Y1081437D03*
Y1091477D03*
X1150709Y1098170D03*
Y1104862D03*
X1145259Y1118248D03*
X1150709Y1111555D03*
Y1134981D03*
X1146309Y1123268D03*
X1145259Y1128288D03*
X1150709Y1141674D03*
Y1148366D03*
X1145259Y1155059D03*
X1146309Y1160079D03*
X1145259Y1165099D03*
X1150709Y1171792D03*
Y1178485D03*
X1145259Y1191870D03*
X1150709Y1185177D03*
X1145259Y1201910D03*
X1146309Y1196890D03*
X1150709Y1208603D03*
Y1215296D03*
Y1221988D03*
X1145259Y1238721D03*
X1146309Y1233701D03*
X1145259Y1228681D03*
X1150709Y1245414D03*
Y1252107D03*
X1154839Y1337834D03*
X1145819D03*
X1143219D03*
X1152315Y1357390D03*
X1154815D03*
X1147115D03*
X1149715D03*
X1141915D03*
X1144515D03*
X1147115Y1360497D03*
X1149715Y1363454D03*
Y1360497D03*
X1147115Y1363454D03*
X1146189Y1372853D03*
X1148619D03*
Y1367253D03*
X1146189D03*
X1141915Y1360497D03*
X1144515D03*
X1143759Y1367253D03*
Y1372853D03*
X1148668Y1385268D03*
X1150458Y1433146D03*
X1144118Y1449628D03*
X1151384Y1556029D03*
X1143063Y1580334D03*
X1152186Y1570567D03*
X1149278Y1589453D03*
X1145060Y1588837D03*
X1141645Y1640017D03*
X1146316Y1649422D03*
X1143127Y1649068D03*
X1144107Y1671118D03*
X1146477Y1658441D03*
X1168687Y74202D03*
X1163113Y481691D03*
X1165589Y569118D03*
X1168818Y756765D03*
Y760265D03*
X1164268Y776910D03*
X1168818Y767265D03*
X1164268Y783603D03*
X1159868Y795315D03*
X1164268Y807028D03*
Y820414D03*
Y813721D03*
X1159868Y832126D03*
X1164268Y850532D03*
Y843839D03*
Y857225D03*
X1159868Y868937D03*
X1164268Y880650D03*
Y887343D03*
Y894036D03*
X1159868Y905749D03*
X1164268Y917461D03*
Y924154D03*
Y930847D03*
X1159868Y942560D03*
X1164268Y954272D03*
Y960965D03*
Y967658D03*
Y974351D03*
Y981044D03*
Y987736D03*
Y994429D03*
Y1004469D03*
Y1034587D03*
Y1041280D03*
Y1047973D03*
Y1054666D03*
Y1061359D03*
Y1071398D03*
X1159868Y1089804D03*
X1164268Y1078091D03*
Y1101516D03*
Y1108209D03*
Y1114902D03*
X1159868Y1126615D03*
X1164268Y1138327D03*
Y1145020D03*
X1159868Y1163426D03*
X1164268Y1151713D03*
Y1175138D03*
Y1181831D03*
Y1188524D03*
X1159868Y1200237D03*
X1164268Y1211949D03*
Y1218642D03*
X1159868Y1237048D03*
X1164268Y1225335D03*
Y1248760D03*
Y1255453D03*
X1167509Y1337884D03*
X1164909D03*
X1157439Y1337834D03*
X1160929Y1352252D03*
X1163529D03*
X1160929Y1349652D03*
X1163529D03*
X1162279Y1357352D03*
X1163529Y1354852D03*
X1157259Y1357406D03*
X1170138Y1361800D03*
X1158205Y1363394D03*
Y1360437D03*
X1169488Y1386721D03*
X1167830Y1384770D03*
X1161311Y1548204D03*
X1172523Y1573250D03*
X1160031Y1591163D03*
X1162144Y1658042D03*
X1159741Y1669759D03*
X1169187Y1687117D03*
X1174958Y-24648D03*
Y5352D03*
Y15352D03*
X1177429Y89556D03*
Y93556D03*
X1185952Y432202D03*
Y440202D03*
Y448202D03*
X1185707Y465272D03*
Y460202D03*
Y470392D03*
X1185117Y571807D03*
X1181445Y592868D03*
X1175860Y756765D03*
X1180410Y773563D03*
X1175860Y763765D03*
X1176010Y791969D03*
X1180410Y780256D03*
X1174960Y786949D03*
X1180410Y803681D03*
X1174960Y796988D03*
X1180410Y817067D03*
Y810374D03*
X1176010Y828780D03*
X1174960Y833799D03*
Y823760D03*
X1180410Y847185D03*
Y840492D03*
X1176010Y865591D03*
X1180410Y853878D03*
X1174960Y860571D03*
X1180410Y877303D03*
X1174960Y870610D03*
X1180410Y890689D03*
Y883996D03*
X1176010Y902402D03*
X1174960Y897382D03*
Y907422D03*
X1180410Y914114D03*
Y920807D03*
X1176010Y939213D03*
X1174960Y934193D03*
X1180410Y927500D03*
X1174960Y944233D03*
X1180410Y950925D03*
Y957618D03*
Y964311D03*
Y971004D03*
Y977697D03*
Y984390D03*
Y991083D03*
Y997776D03*
Y1004469D03*
Y1031240D03*
Y1037933D03*
Y1044626D03*
Y1051319D03*
Y1058012D03*
Y1068051D03*
Y1074744D03*
X1176010Y1086457D03*
X1174960Y1081437D03*
Y1091477D03*
X1180410Y1098170D03*
Y1104862D03*
X1174960Y1118248D03*
X1180410Y1111555D03*
X1176010Y1123268D03*
X1174960Y1128288D03*
X1180410Y1134981D03*
Y1141674D03*
Y1148366D03*
X1176010Y1160079D03*
X1174960Y1155059D03*
Y1165099D03*
X1180410Y1171792D03*
Y1178485D03*
X1174960Y1191870D03*
X1180410Y1185177D03*
X1176010Y1196890D03*
X1174960Y1201910D03*
X1180410Y1208603D03*
Y1215296D03*
Y1221988D03*
X1176010Y1233701D03*
X1174960Y1238721D03*
Y1228681D03*
X1180410Y1245414D03*
Y1252107D03*
X1182615Y1357390D03*
X1185215D03*
X1177415D03*
X1174815D03*
X1180015D03*
X1182615Y1363454D03*
Y1360497D03*
X1180015Y1363454D03*
X1174815Y1360497D03*
X1177415D03*
X1180015D03*
X1176659Y1367253D03*
Y1372853D03*
X1179089D03*
X1181519D03*
Y1367253D03*
X1179089D03*
X1181568Y1385268D03*
X1185000Y1396500D03*
Y1401000D03*
X1184100Y1410000D03*
X1185000Y1405500D03*
X1178400Y1433000D03*
X1181324Y1485895D03*
X1183234Y1483295D03*
Y1488495D03*
X1181314Y1492995D03*
X1176534D03*
X1174624Y1495595D03*
X1181314Y1498195D03*
X1176534D03*
X1180047Y1533247D03*
X1181853Y1561731D03*
X1172523Y1562350D03*
X1179187Y1666429D03*
X1175454Y1668046D03*
X1178932Y1686698D03*
X1185676Y1697249D03*
X1194199Y49379D03*
X1198694Y57015D03*
X1191488Y87125D03*
Y91125D03*
X1200518Y100875D03*
X1189701Y173187D03*
X1201157Y431875D03*
X1189540Y481691D03*
X1188192Y589263D03*
X1191646Y589567D03*
X1195729Y591022D03*
X1198519Y756765D03*
Y760265D03*
X1193969Y776910D03*
X1198519Y767265D03*
X1193969Y783603D03*
X1189569Y795315D03*
X1193969Y807028D03*
Y820414D03*
Y813721D03*
X1189569Y832126D03*
X1193969Y850532D03*
Y843839D03*
Y857225D03*
X1189569Y868937D03*
X1193969Y880650D03*
Y887343D03*
Y894036D03*
X1189569Y905749D03*
X1193969Y917461D03*
Y924154D03*
Y930847D03*
Y954272D03*
X1189569Y942560D03*
X1193969Y960965D03*
Y967658D03*
Y974351D03*
Y981044D03*
Y987736D03*
Y994429D03*
Y1004469D03*
Y1034587D03*
Y1041280D03*
Y1047973D03*
Y1054666D03*
Y1061359D03*
Y1071398D03*
X1189569Y1089804D03*
X1193969Y1078091D03*
Y1101516D03*
Y1108209D03*
Y1114902D03*
X1189569Y1126615D03*
X1193969Y1138327D03*
Y1145020D03*
X1189569Y1163426D03*
X1193969Y1151713D03*
Y1175138D03*
Y1181831D03*
Y1188524D03*
X1189569Y1200237D03*
X1193969Y1211949D03*
Y1218642D03*
X1189569Y1237048D03*
X1193969Y1225335D03*
Y1248760D03*
Y1255453D03*
X1196159Y1326549D03*
X1193659Y1326589D03*
Y1324049D03*
X1196259D03*
X1193659Y1321549D03*
X1196259D03*
X1199899Y1338065D03*
X1193829Y1352252D03*
X1196429D03*
X1193829Y1349652D03*
X1196429D03*
X1193829Y1354852D03*
X1190159Y1357406D03*
X1195179Y1357352D03*
X1196429Y1354852D03*
X1187715Y1357390D03*
X1191105Y1363394D03*
Y1360437D03*
X1200690Y1384572D03*
X1194000Y1418000D03*
X1187925Y1417000D03*
X1194000Y1428500D03*
Y1433000D03*
X1187925Y1440400D03*
X1188014Y1483295D03*
Y1488495D03*
X1194724Y1505295D03*
X1196634Y1502695D03*
Y1507895D03*
X1196127Y1583797D03*
X1195261Y1622884D03*
X1200217D03*
X1195050Y1620040D03*
X1195261Y1627876D03*
X1200217D03*
Y1654796D03*
X1195261D03*
X1200217Y1659788D03*
X1195261D03*
X1192903Y1666276D03*
X1189462Y1691366D03*
X1196767Y1712261D03*
X1196814Y1726261D03*
X1215528Y172395D03*
X1214156Y292066D03*
X1214856Y421018D03*
X1213866Y455376D03*
X1208400Y591631D03*
X1201440Y668138D03*
X1207177Y668115D03*
X1205561Y756765D03*
X1210111Y773563D03*
X1205561Y763765D03*
X1205711Y791969D03*
X1210111Y780256D03*
X1204661Y786949D03*
X1210111Y803681D03*
X1204661Y796988D03*
X1210111Y817067D03*
Y810374D03*
X1205711Y828780D03*
X1204661Y833799D03*
Y823760D03*
X1210111Y847185D03*
Y840492D03*
X1205711Y865591D03*
X1210111Y853878D03*
X1204661Y860571D03*
X1210111Y877303D03*
X1204661Y870610D03*
X1210111Y890689D03*
Y883996D03*
X1205711Y902402D03*
X1204661Y897382D03*
Y907422D03*
X1210111Y914114D03*
Y920807D03*
X1205711Y939213D03*
X1204661Y934193D03*
X1210111Y927500D03*
X1204661Y944233D03*
X1210111Y950925D03*
Y957618D03*
Y964311D03*
Y971004D03*
Y977697D03*
Y984390D03*
Y991083D03*
Y997776D03*
Y1004469D03*
Y1031240D03*
Y1037933D03*
Y1044626D03*
Y1051319D03*
Y1058012D03*
Y1068051D03*
Y1074744D03*
X1205711Y1086457D03*
X1204661Y1081437D03*
Y1091477D03*
X1210111Y1098170D03*
Y1104862D03*
X1204661Y1118248D03*
X1210111Y1111555D03*
X1205711Y1123268D03*
X1204661Y1128288D03*
X1210111Y1134981D03*
Y1141674D03*
Y1148366D03*
X1205711Y1160079D03*
X1204661Y1155059D03*
Y1165099D03*
X1210111Y1171792D03*
Y1178485D03*
X1204661Y1191870D03*
X1210111Y1185177D03*
X1205711Y1196890D03*
X1204661Y1201910D03*
X1210111Y1208603D03*
Y1215296D03*
Y1221988D03*
X1205711Y1233701D03*
X1204661Y1228681D03*
Y1238721D03*
X1210111Y1245414D03*
Y1252107D03*
X1205189Y1321492D03*
Y1323992D03*
X1202689Y1321492D03*
Y1324032D03*
X1211299Y1338105D03*
X1202399D03*
X1215415Y1357390D03*
X1212815D03*
X1210215D03*
X1207615D03*
X1202988Y1361490D03*
X1215415Y1363454D03*
Y1360497D03*
X1212815Y1363454D03*
Y1360497D03*
X1210215D03*
X1207615D03*
X1214319Y1372853D03*
X1211889D03*
X1209459D03*
Y1367253D03*
X1214319D03*
X1211889D03*
X1214368Y1385268D03*
X1202288Y1386721D03*
X1202484Y1402467D03*
X1203334Y1492995D03*
X1208114D03*
X1210034Y1483295D03*
X1214814D03*
X1208124Y1485895D03*
X1210034Y1488495D03*
X1214814D03*
X1201424Y1495595D03*
X1203334Y1498195D03*
X1208114D03*
X1201414Y1502695D03*
Y1507895D03*
X1200851Y1583797D03*
X1205576Y1583897D03*
X1210300Y1583697D03*
X1215025Y1583897D03*
X1207321Y1622884D03*
X1212277D03*
X1201291Y1637876D03*
Y1632884D03*
X1206247D03*
Y1637876D03*
X1213351D03*
Y1632884D03*
X1207321Y1627876D03*
X1212277D03*
X1207321Y1654796D03*
X1206247Y1649788D03*
X1201291D03*
X1212277Y1654796D03*
X1213351Y1649788D03*
X1206247Y1644796D03*
X1201291D03*
X1213351D03*
X1207321Y1659788D03*
X1212277D03*
X1204804Y1691375D03*
X1216199Y49379D03*
X1230156Y292066D03*
X1222094Y286948D03*
X1219463Y1338122D03*
X1229809Y1338105D03*
X1226629Y1352252D03*
X1229229D03*
X1226629Y1349652D03*
X1229229D03*
X1222959Y1357406D03*
X1227979Y1357352D03*
X1226629Y1354852D03*
X1229229D03*
X1220515Y1357390D03*
X1218015D03*
X1223905Y1363394D03*
Y1360437D03*
X1230134Y1492995D03*
X1228224Y1495595D03*
X1221524Y1505295D03*
X1230134Y1498195D03*
X1228214Y1502695D03*
X1223434D03*
Y1507895D03*
X1228214D03*
X1219749Y1583897D03*
X1224474Y1583697D03*
X1229198Y1583797D03*
X1219381Y1622884D03*
X1224337D03*
X1218307Y1637876D03*
Y1632884D03*
X1230367Y1637876D03*
X1225411D03*
X1230367Y1632884D03*
X1225411D03*
X1219381Y1627876D03*
X1224337D03*
Y1654796D03*
X1219381D03*
X1218307Y1649788D03*
X1225411D03*
X1230367D03*
X1218307Y1644796D03*
X1225411D03*
X1230367D03*
X1224337Y1659788D03*
X1219381D03*
X1219738Y1717011D03*
Y1731011D03*
X1236844Y-34348D03*
X1236829Y-36863D03*
X1236798Y-31476D03*
X1236813Y-28961D03*
X1240097Y-34334D03*
X1243122Y-35654D03*
X1240082Y-36849D03*
X1236877Y-26227D03*
X1236932Y-19948D03*
X1236942Y-13666D03*
X1236927Y-16181D03*
X1236892Y-23712D03*
X1240130Y-26213D03*
X1240194Y-19948D03*
X1240195Y-13652D03*
X1243220Y-14972D03*
X1240180Y-16167D03*
X1240145Y-23698D03*
X1243170Y-25018D03*
X1236932Y-9948D03*
Y52D03*
X1236942Y-3666D03*
X1236927Y-6181D03*
X1240194Y-9948D03*
Y52D03*
X1240195Y-3652D03*
X1243220Y-4972D03*
X1240180Y-6167D03*
X1236927Y13819D03*
X1236942Y16334D03*
X1236932Y10052D03*
X1236942Y6334D03*
X1236927Y3819D03*
X1240180Y13833D03*
X1243220Y15028D03*
X1240195Y16348D03*
X1240194Y10052D03*
X1240195Y6348D03*
X1243220Y5028D03*
X1240180Y3833D03*
X1236911Y21721D03*
X1236896Y19206D03*
X1236941Y26751D03*
X1236926Y24236D03*
X1243219Y25445D03*
X1240194Y26765D03*
X1240179Y24250D03*
X1238199Y49379D03*
X1245606Y1314351D03*
Y1311244D03*
X1240899Y1315460D03*
X1240240Y1339578D03*
X1232409Y1338105D03*
X1242500Y1430075D03*
X1237100Y1442500D03*
X1242500Y1437075D03*
X1234924Y1485895D03*
X1241614Y1483295D03*
X1236834D03*
X1241614Y1488495D03*
X1236834D03*
X1234914Y1492995D03*
Y1498195D03*
X1233923Y1583897D03*
X1238647D03*
X1243372D03*
X1231441Y1622884D03*
X1236397D03*
X1243501D03*
X1237471Y1637876D03*
Y1632884D03*
X1242427Y1637876D03*
Y1632884D03*
X1236397Y1627876D03*
X1231441D03*
X1243501D03*
X1231441Y1654796D03*
X1236397D03*
X1237471Y1649788D03*
X1243501Y1654796D03*
X1242427Y1649788D03*
X1237471Y1644796D03*
X1242427D03*
X1231441Y1659788D03*
X1236397D03*
X1243501D03*
X1260199Y49379D03*
X1256064Y101100D03*
X1254094Y286948D03*
X1245825Y305275D03*
X1260227Y407128D03*
Y411128D03*
X1248902Y470733D03*
X1257016Y467253D03*
X1246490Y483302D03*
X1257450Y1291721D03*
X1260050D03*
X1249650D03*
X1247050D03*
X1258506Y1311244D03*
X1256006D03*
X1253406Y1314351D03*
X1250806D03*
X1253406Y1311244D03*
X1250806D03*
X1248206Y1314351D03*
Y1311244D03*
X1252310Y1321107D03*
X1249880D03*
X1252310Y1326707D03*
X1253406Y1317308D03*
X1250806D03*
X1247450Y1326707D03*
Y1321107D03*
X1249880Y1326707D03*
X1252359Y1339122D03*
X1252315Y1417085D03*
X1254905Y1417026D03*
X1256934Y1492995D03*
X1255024Y1495595D03*
X1248324Y1505295D03*
X1256934Y1498195D03*
X1255014Y1502695D03*
X1250234D03*
X1255014Y1507895D03*
X1250234D03*
X1248096Y1583897D03*
X1252820Y1583697D03*
X1257544Y1583897D03*
X1248457Y1622884D03*
X1255561D03*
X1254487Y1637876D03*
Y1632884D03*
X1249531Y1637876D03*
Y1632884D03*
X1248457Y1627876D03*
X1255561D03*
X1248457Y1654796D03*
X1254487Y1649788D03*
X1249531D03*
X1255561Y1654796D03*
X1254487Y1644796D03*
X1249531D03*
X1248657Y1659588D03*
X1255561Y1659788D03*
X1266146Y121022D03*
X1263582Y164051D03*
Y160051D03*
Y180551D03*
Y176051D03*
Y172051D03*
Y168051D03*
Y185051D03*
X1270094Y286948D03*
X1262156Y292066D03*
X1270670Y1291624D03*
X1268070D03*
X1261896Y1314291D03*
X1260950Y1311260D03*
X1267220Y1306106D03*
Y1308706D03*
Y1303506D03*
X1265970Y1311206D03*
X1264620Y1303506D03*
Y1306106D03*
Y1308706D03*
X1273869Y1315300D03*
X1261896Y1317248D03*
X1273175Y1340547D03*
X1271517Y1338596D03*
X1275124Y1485895D03*
X1261724D03*
X1263634Y1483295D03*
X1268414D03*
X1263634Y1488495D03*
X1268414D03*
X1261714Y1492995D03*
Y1498195D03*
X1262269Y1583897D03*
X1266993Y1583797D03*
X1267621Y1622884D03*
X1260517D03*
X1272577D03*
X1261591Y1637876D03*
X1266547D03*
X1261591Y1632884D03*
X1266547D03*
X1273651Y1637876D03*
Y1632790D03*
X1267621Y1627876D03*
X1260517D03*
X1272577D03*
X1260517Y1654796D03*
X1267621D03*
X1266547Y1649788D03*
X1261591D03*
X1272577Y1654796D03*
X1273651Y1649788D03*
X1266547Y1644796D03*
X1261591D03*
X1273651D03*
X1260517Y1659788D03*
X1267621D03*
X1272577D03*
X1282199Y49379D03*
X1278111Y150030D03*
X1285391Y142553D03*
X1286094Y286948D03*
X1278156Y292066D03*
X1277598Y404428D03*
X1282165Y408987D03*
X1288202Y405741D03*
X1288902Y1311216D03*
X1286302Y1314323D03*
X1283702D03*
X1286302Y1311216D03*
X1283702D03*
X1278502Y1314323D03*
X1281102D03*
Y1311216D03*
X1278502D03*
X1285206Y1326679D03*
X1286302Y1317280D03*
X1283702D03*
X1285206Y1321079D03*
X1282776D03*
Y1326679D03*
X1280346Y1321079D03*
Y1326679D03*
X1285255Y1339094D03*
X1277034Y1483295D03*
X1281814D03*
X1277034Y1488495D03*
X1281814D03*
X1284510Y1556953D03*
X1278012Y1581563D03*
X1279681Y1622884D03*
X1284637D03*
X1278607Y1637876D03*
Y1632790D03*
X1285711Y1637876D03*
Y1632884D03*
X1279681Y1627876D03*
X1284637D03*
X1279681Y1654796D03*
X1278607Y1649788D03*
X1284637Y1654796D03*
X1285711Y1649788D03*
X1278607Y1644796D03*
X1285711D03*
X1279681Y1659788D03*
X1284637D03*
X1304199Y49379D03*
X1300668Y125739D03*
Y133739D03*
Y129739D03*
X1306431Y149330D03*
X1300668Y145739D03*
X1292082Y166051D03*
Y162051D03*
Y171551D03*
Y184051D03*
X1302094Y298066D03*
Y286948D03*
X1294156Y292066D03*
X1293277Y401125D03*
X1296228Y408125D03*
X1299076Y530023D03*
X1297487Y590607D03*
X1302890Y1291759D03*
X1298350Y1291721D03*
X1295750D03*
X1300116Y1306078D03*
Y1303478D03*
Y1308678D03*
X1298866Y1311178D03*
X1294792Y1314263D03*
X1297516Y1306078D03*
Y1303478D03*
Y1308678D03*
X1291402Y1311216D03*
X1293846Y1311232D03*
X1294792Y1317220D03*
X1304421Y1338539D03*
X1304596Y1492995D03*
X1302686Y1495595D03*
X1304596Y1498195D03*
X1291819Y1563595D03*
X1294319D03*
X1300560Y1554261D03*
X1291741Y1622884D03*
X1296697D03*
X1303801D03*
X1290667Y1637876D03*
Y1632884D03*
X1297771Y1637876D03*
Y1632884D03*
X1302727Y1637876D03*
Y1632884D03*
X1296697Y1627876D03*
X1291741D03*
X1303801D03*
X1291741Y1654796D03*
X1296697D03*
X1297771Y1649788D03*
X1290667D03*
X1303801Y1654796D03*
X1302727Y1649788D03*
X1297771Y1644796D03*
X1290667D03*
X1302727D03*
X1291741Y1659788D03*
X1296697D03*
X1303801D03*
X1306449Y92185D03*
X1306431Y152830D03*
X1310156Y292066D03*
X1305600Y1291759D03*
X1316606Y1314266D03*
Y1311159D03*
X1314006Y1314266D03*
Y1311159D03*
X1319206Y1314266D03*
Y1311159D03*
X1311406Y1314266D03*
Y1311159D03*
X1306799Y1315440D03*
X1315680Y1326622D03*
X1318110D03*
X1316606Y1317223D03*
X1319206D03*
X1318110Y1321022D03*
X1315680D03*
X1313250D03*
Y1326622D03*
X1318159Y1339037D03*
X1306079Y1340490D03*
X1314580Y1425240D03*
X1310580D03*
X1318580D03*
X1309386Y1485895D03*
X1311296Y1483295D03*
X1316076D03*
X1311296Y1488495D03*
X1316076D03*
X1309376Y1492995D03*
Y1498195D03*
X1308290Y1533380D03*
X1309423Y1543800D03*
Y1547420D03*
Y1551040D03*
X1309915Y1561731D03*
X1308757Y1622884D03*
X1315861D03*
X1309831Y1637876D03*
Y1632884D03*
X1314787Y1637876D03*
Y1632884D03*
X1308757Y1627876D03*
X1315861D03*
X1308757Y1654796D03*
X1309831Y1649788D03*
X1315861Y1654796D03*
X1314787Y1649788D03*
X1309831Y1644796D03*
X1314787D03*
X1308757Y1659788D03*
X1315861D03*
X1326199Y49379D03*
X1334156Y292066D03*
X1326094Y286948D03*
X1330277Y857388D03*
X1329477Y1222158D03*
X1331202Y1211488D03*
X1332680Y1291861D03*
X1330080D03*
X1333020Y1308621D03*
X1331770Y1311121D03*
X1333020Y1306021D03*
Y1303421D03*
X1330420Y1306021D03*
Y1303421D03*
Y1308621D03*
X1327696Y1314206D03*
X1321806Y1311159D03*
X1324306D03*
X1326750Y1311175D03*
X1327696Y1317163D03*
X1334580Y1425240D03*
X1330580D03*
X1326580D03*
X1322580D03*
X1331396Y1492995D03*
X1322786Y1505295D03*
X1329486Y1495595D03*
X1331396Y1498195D03*
X1324696Y1502695D03*
X1329476D03*
X1324696Y1507895D03*
X1329476D03*
X1328913Y1583797D03*
X1333638Y1583897D03*
X1324189Y1583797D03*
X1327921Y1622884D03*
X1320817D03*
X1332877D03*
X1321891Y1637876D03*
X1326847D03*
X1321891Y1632884D03*
X1326847D03*
X1333951Y1637876D03*
Y1632884D03*
X1327921Y1627876D03*
X1320817D03*
X1332877D03*
X1320817Y1654796D03*
X1327921D03*
X1326847Y1649788D03*
X1321891D03*
X1332877Y1654796D03*
X1333951Y1649788D03*
X1326847Y1644796D03*
X1321891D03*
X1333951D03*
X1320817Y1659788D03*
X1327921D03*
X1332877D03*
X1348199Y49379D03*
X1351750Y72826D03*
X1339840Y72860D03*
X1342094Y286948D03*
X1339347Y857388D03*
X1337975Y1177999D03*
X1338142Y1181642D03*
X1338440Y1291949D03*
X1335670Y1291899D03*
X1346806Y1311359D03*
X1349406D03*
X1346806Y1314466D03*
X1349406D03*
X1344206Y1311359D03*
Y1314466D03*
X1339429Y1315570D03*
X1348480Y1326822D03*
X1349406Y1317423D03*
X1346050Y1321222D03*
Y1326822D03*
X1348480Y1321222D03*
X1338879Y1340690D03*
X1337221Y1338739D03*
X1346580Y1425240D03*
X1342580D03*
X1338580D03*
X1336176Y1492995D03*
X1338096Y1483295D03*
X1342876D03*
X1336186Y1485895D03*
X1338096Y1488495D03*
X1342876D03*
X1349586Y1505295D03*
X1336176Y1498195D03*
X1343087Y1583897D03*
X1347811D03*
X1338362Y1583697D03*
X1339981Y1622884D03*
X1344937D03*
X1338907Y1637876D03*
Y1632884D03*
X1346011Y1637876D03*
Y1632884D03*
X1339981Y1627876D03*
X1344937D03*
X1339981Y1654796D03*
X1338907Y1649788D03*
X1344937Y1654796D03*
X1346011Y1649788D03*
X1338907Y1644796D03*
X1346011D03*
X1339981Y1659788D03*
X1344937D03*
X1361550Y67264D03*
X1350156Y292066D03*
X1358094Y286948D03*
X1354257Y675765D03*
X1364490Y1293694D03*
X1361830Y1291809D03*
X1360496Y1314406D03*
X1363220Y1308821D03*
X1364570Y1311321D03*
X1363220Y1306221D03*
Y1303621D03*
X1359550Y1311375D03*
X1352006Y1311359D03*
X1357106D03*
X1354606D03*
X1352006Y1314466D03*
X1360496Y1317363D03*
X1350910Y1326822D03*
X1352006Y1317423D03*
X1350910Y1321222D03*
X1350959Y1339237D03*
X1362580Y1425240D03*
X1358580D03*
X1354580D03*
X1350580D03*
X1362986Y1485895D03*
X1364896Y1483295D03*
Y1488495D03*
X1358196Y1492995D03*
X1362976D03*
X1356286Y1495595D03*
X1358196Y1498195D03*
X1362976D03*
X1356276Y1502695D03*
X1351496D03*
X1356276Y1507895D03*
X1351496D03*
X1357260Y1583797D03*
X1361985Y1583897D03*
X1352536Y1583697D03*
X1352041Y1622884D03*
X1356997D03*
X1364101D03*
X1350967Y1637876D03*
Y1632884D03*
X1358071Y1637876D03*
Y1632884D03*
X1363027Y1637876D03*
Y1632884D03*
X1356997Y1627876D03*
X1352041D03*
X1364101D03*
X1352041Y1654796D03*
X1356997D03*
X1358071Y1649788D03*
X1350967D03*
X1364101Y1654796D03*
X1363027Y1649788D03*
X1358071Y1644796D03*
X1350967D03*
X1363027D03*
X1352041Y1659788D03*
X1356997D03*
X1364101D03*
X1370199Y49379D03*
X1371259Y98000D03*
X1366156Y292066D03*
X1377862Y485552D03*
Y511052D03*
X1368305Y1307340D03*
X1365820Y1308821D03*
X1368305Y1309840D03*
X1365820Y1306221D03*
Y1303621D03*
X1372149Y1334890D03*
X1379388Y1330690D03*
Y1333797D03*
X1378632Y1340553D03*
X1376788Y1330690D03*
Y1333797D03*
X1378632Y1346153D03*
X1371422Y1359024D03*
X1368922D03*
X1379101Y1418621D03*
X1368299Y1425240D03*
X1372164Y1423810D03*
X1375341Y1421268D03*
X1369676Y1483295D03*
Y1488495D03*
X1376386Y1505295D03*
X1378296Y1502695D03*
Y1507895D03*
X1376158Y1583897D03*
X1366709D03*
X1371434D03*
X1369057Y1622884D03*
X1376161D03*
X1370131Y1637876D03*
Y1632790D03*
X1375087Y1637876D03*
Y1632790D03*
X1369057Y1627876D03*
X1376161D03*
X1369057Y1654796D03*
X1370131Y1649788D03*
X1376161Y1654796D03*
X1375087Y1649788D03*
X1370131Y1644796D03*
X1375087D03*
X1369057Y1659788D03*
X1376161D03*
X1392199Y49379D03*
X1389688Y1330690D03*
X1392132Y1330706D03*
X1393078Y1333737D03*
Y1336694D03*
X1383492Y1340553D03*
X1381062D03*
X1381988Y1336754D03*
X1384588D03*
X1387188Y1330690D03*
X1381988D03*
Y1333797D03*
X1384588Y1330690D03*
Y1333797D03*
X1383541Y1358568D03*
X1381062Y1346153D03*
X1383492D03*
X1383284Y1415973D03*
X1387308Y1413643D03*
X1392021Y1410360D03*
X1389786Y1485895D03*
X1391696Y1483295D03*
Y1488495D03*
X1384996Y1492995D03*
X1389776D03*
X1383086Y1495595D03*
X1384996Y1498195D03*
X1389776D03*
X1383076Y1502695D03*
Y1507895D03*
X1390331Y1583897D03*
X1380882Y1583697D03*
X1385606Y1583897D03*
X1381117Y1622884D03*
X1382191Y1637876D03*
X1387147D03*
X1382191Y1632884D03*
X1387147D03*
X1381117Y1627876D03*
Y1654796D03*
X1382191Y1649788D03*
X1387147D03*
X1382191Y1644796D03*
X1387147D03*
X1392068Y1667907D03*
X1381918D03*
X1381117Y1659788D03*
X1387620Y1721418D03*
X1385061D03*
X1403500Y458377D03*
X1402452Y642825D03*
X1405716Y1310618D03*
X1401740Y1311980D03*
X1399240D03*
X1408690Y1324803D03*
X1396302Y1328152D03*
Y1325552D03*
X1398902Y1328152D03*
Y1325552D03*
X1396302Y1322952D03*
X1398902D03*
X1401406Y1334918D03*
X1397652Y1330652D03*
X1398375Y1403688D03*
X1401764Y1399928D03*
X1405207Y1395480D03*
X1408543Y1391826D03*
X1395463Y1406918D03*
X1403186Y1485895D03*
X1405096Y1483295D03*
X1396476D03*
X1405096Y1488495D03*
X1396476D03*
X1409456Y1537872D03*
X1406074Y1581563D03*
X1395055Y1583797D03*
X1398058Y1619683D03*
X1409660Y1619853D03*
X1397367Y1639951D03*
X1402425Y1649532D03*
X1414199Y49379D03*
X1414000Y460362D03*
X1415426Y1042765D03*
Y1038765D03*
X1424561Y1305566D03*
X1420690Y1324803D03*
X1417690D03*
X1414690D03*
X1411690D03*
X1424163Y1373240D03*
X1411508Y1388384D03*
X1414950Y1384942D03*
X1417491Y1381183D03*
X1420774Y1377106D03*
X1409876Y1483295D03*
Y1488495D03*
X1423735Y1536715D03*
X1412572Y1556953D03*
X1421232Y1606126D03*
X1422914Y1601663D03*
X1421392Y1621706D03*
X1416357Y1644027D03*
X1420042Y1649716D03*
X1433817Y-34648D03*
Y-4648D03*
Y5352D03*
X1436199Y49379D03*
X1434513Y106950D03*
X1439232Y596291D03*
X1425437Y1308184D03*
X1426202Y1310752D03*
X1427314Y1313482D03*
X1428458Y1316481D03*
X1429517Y1319447D03*
X1430312Y1322412D03*
X1431106Y1325219D03*
X1426441Y1369427D03*
X1428559Y1365296D03*
X1430465Y1361060D03*
X1438798Y1495595D03*
X1430431Y1563595D03*
X1427931D03*
X1424971Y1566764D03*
Y1564264D03*
X1435584Y1596545D03*
X1430075Y1613904D03*
X1430319Y1623504D03*
X1425390Y1635496D03*
X1433327Y1643287D03*
X1446869Y105129D03*
X1451353Y116158D03*
X1443551Y539318D03*
Y535318D03*
X1453345Y1015473D03*
Y1019016D03*
Y1022559D03*
X1445498Y1485895D03*
X1447408Y1483295D03*
X1452188D03*
X1447408Y1488495D03*
X1452188D03*
X1445488Y1492995D03*
X1440708D03*
X1445488Y1498195D03*
X1440708D03*
X1444200Y1533240D03*
X1445535Y1551040D03*
Y1547420D03*
Y1543800D03*
X1446027Y1561731D03*
X1445500Y1611500D03*
X1448500Y1601000D03*
X1442579Y1673303D03*
X1447579D03*
X1452579D03*
X1453950Y1681450D03*
X1458199Y49379D03*
X1459682Y450372D03*
X1468395Y487582D03*
X1464257Y552977D03*
Y564977D03*
X1468257Y696265D03*
X1460926Y1015473D03*
X1467926D03*
X1460926Y1019016D03*
Y1022559D03*
X1467926Y1019016D03*
Y1022559D03*
X1467508Y1492995D03*
X1458898Y1505295D03*
X1465598Y1495595D03*
X1467508Y1498195D03*
X1460808Y1502695D03*
X1465588D03*
X1460808Y1507895D03*
X1465588D03*
X1465025Y1583797D03*
X1460301D03*
X1464391Y1622884D03*
X1459435D03*
X1465465Y1637876D03*
Y1632884D03*
X1459435Y1627876D03*
X1464391D03*
Y1654796D03*
X1465465Y1649788D03*
Y1644796D03*
X1459435Y1654796D03*
X1464391Y1659788D03*
X1466500Y1666000D03*
X1469034Y1667794D03*
X1459435Y1659788D03*
X1456852Y1673320D03*
X1466599Y1679401D03*
X1466260Y1675155D03*
X1460457Y1685160D03*
X1480199Y49379D03*
X1483820Y122713D03*
X1482257Y552977D03*
Y560477D03*
Y567977D03*
X1481934Y699670D03*
X1480300Y697750D03*
X1472288Y1492995D03*
X1474208Y1483295D03*
X1478988D03*
X1472298Y1485895D03*
X1474208Y1488495D03*
X1478988D03*
X1472288Y1498195D03*
X1479199Y1583897D03*
X1483923D03*
X1469750D03*
X1474474Y1583697D03*
X1476451Y1622884D03*
X1471495D03*
X1483555D03*
X1470421Y1632884D03*
Y1637876D03*
X1482481D03*
X1477525D03*
X1482481Y1632884D03*
X1477525D03*
X1471495Y1627876D03*
X1483555D03*
X1476451D03*
X1471495Y1654796D03*
X1470421Y1649788D03*
X1476451Y1654796D03*
X1483555D03*
X1482481Y1649788D03*
X1477525D03*
X1470421Y1644796D03*
X1477525D03*
X1482481D03*
X1471495Y1659788D03*
X1476451D03*
X1483555D03*
X1471616Y1670098D03*
X1479375Y1685984D03*
X1495539Y131237D03*
X1492237Y123842D03*
X1489757Y552977D03*
X1497257D03*
Y560477D03*
X1489757Y567977D03*
X1497257D03*
X1494371Y594462D03*
X1492673Y828513D03*
X1494386Y1178743D03*
X1499098Y1485895D03*
X1494308Y1492995D03*
X1499088D03*
X1492398Y1495595D03*
X1485698Y1505295D03*
X1494308Y1498195D03*
X1499088D03*
X1492388Y1502695D03*
X1487608D03*
X1492388Y1507895D03*
X1487608D03*
X1493372Y1583797D03*
X1498097Y1583897D03*
X1488648Y1583697D03*
X1488511Y1622884D03*
X1495615D03*
X1494541Y1637876D03*
X1489585D03*
X1494541Y1632884D03*
X1489585D03*
X1488511Y1627876D03*
X1495615D03*
X1488511Y1654796D03*
X1495615D03*
X1489585Y1649788D03*
X1494541D03*
X1489585Y1644796D03*
X1494541D03*
X1488511Y1659788D03*
X1495615D03*
X1502199Y49379D03*
X1514576Y219730D03*
X1513348Y253954D03*
X1500757Y537438D03*
X1504757Y537378D03*
X1508757Y537456D03*
X1512757Y537477D03*
X1513382Y697750D03*
X1499243Y803513D03*
X1501730Y811872D03*
X1501338Y825147D03*
X1513470Y1178265D03*
X1504470D03*
X1505788Y1483295D03*
X1501008D03*
X1505788Y1488495D03*
X1501008D03*
X1512498Y1505295D03*
X1512270Y1583897D03*
X1502821D03*
X1507546D03*
X1500571Y1622884D03*
X1512631D03*
X1507675D03*
X1501645Y1637876D03*
Y1632884D03*
X1506601Y1637876D03*
Y1632884D03*
X1513705Y1637876D03*
Y1632884D03*
X1500571Y1627876D03*
X1512631D03*
X1507675D03*
X1500571Y1654796D03*
X1501645Y1649788D03*
X1507675Y1654796D03*
X1512631D03*
X1513705Y1649788D03*
X1506601D03*
X1501645Y1644796D03*
X1513705D03*
X1506601D03*
X1500571Y1659788D03*
X1507675D03*
X1512831Y1659588D03*
X1524124Y47570D03*
X1522917Y119912D03*
X1529384Y201245D03*
X1516452Y249724D03*
X1514900Y251839D03*
X1515016Y699670D03*
X1515192Y814294D03*
X1525898Y1485895D03*
X1527808Y1483295D03*
Y1488495D03*
X1521108Y1492995D03*
X1525888D03*
X1525898Y1505295D03*
X1519198Y1495595D03*
X1521108Y1498195D03*
X1525888D03*
X1519188Y1502695D03*
X1527808D03*
X1514408D03*
X1519188Y1507895D03*
X1514408D03*
X1526443Y1583897D03*
X1516994Y1583697D03*
X1521718Y1583897D03*
X1524691Y1622884D03*
X1519735D03*
X1518661Y1637876D03*
Y1632884D03*
X1525765Y1637876D03*
Y1632884D03*
X1519735Y1627876D03*
X1524691D03*
X1518661Y1649788D03*
X1524691Y1654796D03*
X1519735D03*
X1525765Y1649788D03*
X1518661Y1644796D03*
X1525765D03*
X1524991Y1659788D03*
X1519735D03*
X1530064Y-27930D03*
X1530049Y-30445D03*
X1533317Y-27916D03*
X1536342Y-29236D03*
X1533302Y-30431D03*
X1530048Y-20028D03*
X1530063Y-17513D03*
X1530018Y-25058D03*
X1530033Y-22543D03*
X1533301Y-20014D03*
X1533316Y-17499D03*
X1536341Y-18819D03*
X1543862Y75343D03*
X1539756Y71839D03*
X1534776D03*
X1539756Y66847D03*
X1534776D03*
X1532866Y69340D03*
X1536542Y300819D03*
Y304819D03*
X1539693Y535212D03*
X1542902Y543641D03*
X1540850Y1240863D03*
X1539298Y1485895D03*
X1541208Y1483295D03*
X1532588D03*
X1541208Y1488495D03*
X1532588D03*
X1542186Y1581563D03*
X1531167Y1583797D03*
X1536751Y1622884D03*
X1531795D03*
X1530721Y1637876D03*
Y1632884D03*
X1537825Y1637876D03*
X1542781D03*
X1537825Y1632790D03*
X1542781D03*
X1531795Y1627876D03*
X1536751D03*
X1531795Y1654796D03*
X1530721Y1649788D03*
X1536751Y1654796D03*
X1542781Y1649788D03*
X1537825D03*
X1530721Y1644796D03*
X1542781D03*
X1537825D03*
X1531795Y1659788D03*
X1536751D03*
X1550965Y3001D03*
X1555568Y17045D03*
Y22037D03*
X1553601Y19541D03*
X1555452Y25977D03*
X1553452Y23981D03*
X1548496D03*
X1546496Y25977D03*
X1554520Y37106D03*
X1547434D03*
X1554520Y48720D03*
X1547434D03*
X1556776Y71839D03*
X1550756Y72850D03*
X1545776D03*
X1554866Y69340D03*
X1556776Y66847D03*
X1550756Y77842D03*
X1545776D03*
X1552981Y220826D03*
X1555481Y218326D03*
X1553913Y298119D03*
X1558480Y302678D03*
X1545960Y565162D03*
X1551887Y606938D03*
X1555570Y1235968D03*
X1555367Y1248078D03*
X1555303Y1242557D03*
X1547062Y1258468D03*
X1553811Y1264488D03*
X1545988Y1483295D03*
Y1488495D03*
X1548684Y1556953D03*
X1555993Y1563595D03*
X1558493D03*
X1548811Y1622884D03*
X1543855D03*
X1555915D03*
X1549885Y1637876D03*
X1554841D03*
X1549885Y1632884D03*
X1554841D03*
X1543855Y1627876D03*
X1548811D03*
X1555915D03*
X1543855Y1654796D03*
X1555915D03*
X1548811D03*
X1554841Y1649788D03*
X1549885D03*
X1554841Y1644796D03*
X1549885D03*
X1543855Y1659788D03*
X1555915D03*
X1548811D03*
X1572965Y3001D03*
X1569742Y17045D03*
X1560548D03*
X1567774Y19541D03*
X1569742Y22037D03*
X1560548D03*
X1562669Y23981D03*
X1567625D03*
X1560669Y25977D03*
X1569625D03*
X1562557Y19541D03*
X1561607Y37106D03*
X1568693D03*
Y48720D03*
X1561607D03*
X1572756Y72847D03*
X1561756Y71839D03*
X1565866Y75340D03*
X1567776Y72847D03*
X1561756Y66847D03*
X1572756Y77839D03*
X1567776D03*
X1564517Y299432D03*
X1569592Y294816D03*
X1572283Y301816D03*
X1562995Y789522D03*
X1569518Y806684D03*
X1564267Y1253158D03*
X1573560Y1485895D03*
X1573550Y1492995D03*
X1568770D03*
X1566860Y1495595D03*
X1573550Y1498195D03*
X1568770D03*
X1572230Y1533000D03*
X1573597Y1543800D03*
Y1547420D03*
Y1551040D03*
X1564839Y1554561D03*
X1560871Y1622884D03*
X1572931D03*
X1567975D03*
X1561945Y1637876D03*
Y1632884D03*
X1566901Y1637876D03*
Y1632884D03*
X1560871Y1627876D03*
X1572931D03*
X1567975D03*
X1560871Y1654796D03*
X1561945Y1649788D03*
X1567975Y1654796D03*
X1572931D03*
X1566901Y1649788D03*
X1561945Y1644796D03*
X1566901D03*
X1560871Y1659788D03*
X1567975D03*
X1572931D03*
X1583915Y17045D03*
X1574722D03*
X1581947Y19541D03*
X1583915Y22037D03*
X1576730Y19541D03*
X1574722Y22037D03*
X1576842Y23981D03*
X1581798D03*
X1574842Y25977D03*
X1583798D03*
X1575780Y37106D03*
X1582867D03*
Y48720D03*
X1575780D03*
X1587866Y75340D03*
X1578776Y71839D03*
X1583756D03*
X1576866Y69340D03*
X1578776Y66847D03*
X1583756D03*
X1574546Y251294D03*
X1575370Y1252770D03*
X1581327Y1252858D03*
X1586835Y1271918D03*
X1583007Y1288958D03*
X1577913Y1341623D03*
X1575504Y1356103D03*
X1578336D03*
X1575470Y1483295D03*
X1580250D03*
X1575470Y1488495D03*
X1580250D03*
X1586960Y1505295D03*
X1574089Y1561731D03*
X1588363Y1583797D03*
X1584991Y1622884D03*
X1580035D03*
X1574005Y1637876D03*
Y1632884D03*
X1578961Y1637876D03*
Y1632884D03*
X1586065Y1637876D03*
Y1632884D03*
X1580035Y1627876D03*
X1584991D03*
X1574005Y1649788D03*
X1580035Y1654796D03*
X1578961Y1649788D03*
X1584991Y1654796D03*
X1586065Y1649788D03*
X1574005Y1644796D03*
X1578961D03*
X1586065D03*
X1580035Y1659788D03*
X1584991D03*
X1594965Y3001D03*
X1603072Y17045D03*
X1598092D03*
X1588895D03*
X1603072Y22037D03*
X1598092D03*
X1596121Y19541D03*
X1590903D03*
X1588895Y22037D03*
X1595972Y23981D03*
X1591016D03*
X1589016Y25977D03*
X1597972D03*
X1589953Y37106D03*
X1597040D03*
Y48720D03*
X1589953D03*
X1589776Y72847D03*
X1594756D03*
X1600776Y71842D03*
X1598866Y69343D03*
X1600776Y66850D03*
X1589776Y77839D03*
X1594756D03*
X1597562Y555463D03*
X1595036D03*
X1591962D03*
X1589436D03*
X1589557Y1252778D03*
X1590097Y1246768D03*
X1603507Y1306262D03*
X1601772Y1337293D03*
X1601959Y1351773D03*
X1599139Y1400464D03*
X1595570Y1492995D03*
X1600350D03*
X1602270Y1483295D03*
X1600360Y1485895D03*
X1602270Y1488495D03*
X1593660Y1495595D03*
X1595570Y1498195D03*
X1600350D03*
X1588870Y1502695D03*
X1593650D03*
X1588870Y1507895D03*
X1593650D03*
X1593087Y1583797D03*
X1597812Y1583897D03*
X1602536Y1583697D03*
X1597051Y1622884D03*
X1592095D03*
X1591021Y1637876D03*
Y1632884D03*
X1598125Y1637876D03*
X1603081D03*
X1598125Y1632884D03*
X1603081D03*
X1592095Y1627876D03*
X1597051D03*
X1592095Y1654796D03*
X1591021Y1649788D03*
X1597051Y1654796D03*
X1603081Y1649788D03*
X1598125D03*
X1591021Y1644796D03*
X1603081D03*
X1598125D03*
X1592095Y1659788D03*
X1597051D03*
X1616965Y3001D03*
X1605077Y19541D03*
X1604127Y37106D03*
Y48720D03*
X1609866Y75340D03*
X1611776Y72847D03*
X1616756D03*
X1605756Y71842D03*
Y66850D03*
X1611776Y77839D03*
X1616756D03*
X1608640Y640660D03*
X1607050Y1483295D03*
Y1488495D03*
X1613760Y1505295D03*
X1615670Y1502695D03*
Y1507895D03*
X1607261Y1583897D03*
X1611985D03*
X1616710Y1583697D03*
X1609111Y1622884D03*
X1604155D03*
X1616215D03*
X1610185Y1637876D03*
X1615141D03*
X1610185Y1632884D03*
X1615141D03*
X1604155Y1627876D03*
X1609111D03*
X1616215D03*
X1604155Y1654796D03*
X1616215D03*
X1609111D03*
X1615141Y1649788D03*
X1610185D03*
X1615141Y1644796D03*
X1610185D03*
X1604155Y1659788D03*
X1616215D03*
X1609111D03*
X1631987Y19541D03*
X1626882Y23981D03*
X1631838D03*
X1624882Y25977D03*
X1632906Y37106D03*
X1625819D03*
X1632906Y48720D03*
X1625819D03*
X1629662Y69343D03*
X1633070Y75340D03*
X1627756Y71842D03*
X1622776D03*
X1627756Y66850D03*
X1622776D03*
X1620862Y69343D03*
X1627410Y172008D03*
X1632500Y381500D03*
X1630927Y398002D03*
X1628046Y756765D03*
Y760265D03*
Y767265D03*
X1623496Y776910D03*
Y783603D03*
X1627896Y795315D03*
X1623496Y807028D03*
Y813721D03*
Y820414D03*
X1627896Y832126D03*
X1623496Y843839D03*
Y850532D03*
Y857225D03*
X1627896Y868937D03*
X1623496Y880650D03*
Y887343D03*
Y894036D03*
X1627896Y905749D03*
X1623496Y917461D03*
Y924154D03*
Y930847D03*
X1627896Y942560D03*
X1623496Y954272D03*
Y960965D03*
Y967658D03*
Y974351D03*
Y981044D03*
Y987736D03*
Y994429D03*
Y1004469D03*
Y1034587D03*
Y1041280D03*
Y1047973D03*
Y1054666D03*
Y1061359D03*
Y1071398D03*
X1627896Y1089804D03*
X1623496Y1078091D03*
Y1101516D03*
Y1108209D03*
Y1114902D03*
X1627896Y1126615D03*
X1623496Y1138327D03*
Y1145020D03*
X1627896Y1163426D03*
X1623496Y1151713D03*
Y1175138D03*
Y1181831D03*
Y1188524D03*
X1627896Y1200237D03*
X1623496Y1211949D03*
Y1218642D03*
X1627896Y1237048D03*
X1623496Y1225335D03*
Y1248760D03*
Y1255453D03*
X1627052Y1424716D03*
X1627160Y1485895D03*
X1629070Y1483295D03*
Y1488495D03*
X1622370Y1492995D03*
X1627150D03*
X1620460Y1495595D03*
X1622370Y1498195D03*
X1627150D03*
X1620450Y1502695D03*
Y1507895D03*
X1621434Y1583797D03*
X1626159Y1583897D03*
X1630883D03*
X1621171Y1622884D03*
X1628275D03*
X1622245Y1637876D03*
Y1632884D03*
X1627201Y1637876D03*
Y1632884D03*
X1621171Y1627876D03*
X1628275D03*
X1621171Y1654796D03*
X1622245Y1649788D03*
X1628275Y1654796D03*
X1627201Y1649788D03*
X1622245Y1644796D03*
X1627201D03*
X1621171Y1659788D03*
X1628275D03*
X1638965Y3001D03*
X1648128Y17045D03*
X1633954D03*
X1638934D03*
X1648128Y22037D03*
X1648011Y25977D03*
X1633954Y22037D03*
X1638934D03*
X1646160Y19541D03*
X1640943D03*
X1641055Y23981D03*
X1646011D03*
X1639055Y25977D03*
X1633838D03*
X1647079Y37106D03*
X1639993D03*
X1647079Y48720D03*
X1639993D03*
X1634980Y72847D03*
X1639960D03*
X1645980Y71839D03*
X1644070Y69340D03*
X1645980Y66847D03*
X1634980Y77839D03*
X1639960D03*
X1642240Y399603D03*
X1642135Y414202D03*
X1639800Y426982D03*
X1636800D03*
X1639800Y429982D03*
X1636800D03*
X1639800Y432982D03*
X1636800D03*
X1647110Y434177D03*
X1639800Y435982D03*
X1636800D03*
X1639800Y438982D03*
X1636800D03*
X1635088Y756765D03*
Y763765D03*
X1639638Y773563D03*
X1644038Y791969D03*
X1634188Y786949D03*
X1639638Y780256D03*
X1634188Y796988D03*
X1639638Y803681D03*
Y810374D03*
Y817067D03*
X1644038Y828780D03*
X1634188Y823760D03*
Y833799D03*
X1639638Y840492D03*
Y847185D03*
X1644038Y865591D03*
X1634188Y860571D03*
X1639638Y853878D03*
X1634188Y870610D03*
X1639638Y877303D03*
Y883996D03*
Y890689D03*
X1644038Y902402D03*
X1634188Y897382D03*
Y907422D03*
X1639638Y914114D03*
Y920807D03*
X1644038Y939213D03*
X1634188Y934193D03*
X1639638Y927500D03*
X1634188Y944233D03*
X1639638Y950925D03*
Y957618D03*
Y964311D03*
Y971004D03*
Y977697D03*
Y984390D03*
Y991083D03*
Y997776D03*
Y1004469D03*
Y1031240D03*
Y1037933D03*
Y1044626D03*
Y1051319D03*
Y1058012D03*
Y1068051D03*
Y1074744D03*
X1644038Y1086457D03*
X1634188Y1081437D03*
Y1091477D03*
X1639638Y1098170D03*
Y1104862D03*
X1634188Y1118248D03*
X1639638Y1111555D03*
X1644038Y1123268D03*
X1634188Y1128288D03*
X1639638Y1134981D03*
Y1141674D03*
Y1148366D03*
X1644038Y1160079D03*
X1634188Y1155059D03*
Y1165099D03*
X1639638Y1171792D03*
Y1178485D03*
X1634188Y1191870D03*
X1639638Y1185177D03*
X1644038Y1196890D03*
X1634188Y1201910D03*
X1639638Y1208603D03*
Y1215296D03*
Y1221988D03*
X1644038Y1233701D03*
X1634188Y1228681D03*
Y1238721D03*
X1639638Y1245414D03*
Y1252107D03*
X1641904Y1351467D03*
Y1348567D03*
X1633850Y1483295D03*
Y1488495D03*
X1647260Y1495595D03*
X1640560Y1505295D03*
X1647250Y1502695D03*
X1642470D03*
X1647250Y1507895D03*
X1642470D03*
X1640332Y1583897D03*
X1645056Y1583697D03*
X1635608Y1583897D03*
X1633231Y1622884D03*
X1645291D03*
X1640335D03*
X1634305Y1637876D03*
Y1632790D03*
X1639261Y1637876D03*
Y1632790D03*
X1646365Y1637876D03*
Y1632884D03*
X1633231Y1627876D03*
X1640335D03*
X1645291D03*
X1633231Y1654796D03*
X1634305Y1649788D03*
X1640335Y1654796D03*
X1639261Y1649788D03*
X1645291Y1654796D03*
X1646365Y1649788D03*
X1634305Y1644796D03*
X1639261D03*
X1646365D03*
X1633231Y1659788D03*
X1640335D03*
X1645291D03*
X1647700Y1674228D03*
X1648013Y1713684D03*
Y1728834D03*
X1660965Y3001D03*
X1653108Y17045D03*
X1655116Y19541D03*
X1653108Y22037D03*
X1654166Y37106D03*
Y48720D03*
X1650960Y66847D03*
X1655066Y75343D03*
X1662065Y72850D03*
X1656980D03*
X1650960Y71839D03*
X1662065Y77842D03*
X1656980D03*
X1652610Y394727D03*
X1659610D03*
X1652810Y407402D03*
X1661110Y434177D03*
X1657747Y756765D03*
Y760265D03*
Y767265D03*
X1653197Y776910D03*
Y783603D03*
X1657597Y795315D03*
X1653197Y807028D03*
Y813721D03*
Y820414D03*
X1657597Y832126D03*
X1653197Y843839D03*
Y850532D03*
Y857225D03*
X1657597Y868937D03*
X1653197Y880650D03*
Y887343D03*
Y894036D03*
X1657597Y905749D03*
X1653197Y917461D03*
Y924154D03*
Y930847D03*
X1657597Y942560D03*
X1653197Y954272D03*
Y960965D03*
Y967658D03*
Y974351D03*
Y981044D03*
Y987736D03*
Y994429D03*
Y1004469D03*
Y1034587D03*
Y1041280D03*
Y1047973D03*
Y1054666D03*
Y1061359D03*
Y1071398D03*
X1657597Y1089804D03*
X1653197Y1078091D03*
Y1101516D03*
Y1108209D03*
Y1114902D03*
X1657597Y1126615D03*
X1653197Y1138327D03*
Y1145020D03*
X1657597Y1163426D03*
X1653197Y1151713D03*
Y1175138D03*
Y1188524D03*
Y1181831D03*
X1657597Y1200237D03*
X1653197Y1211949D03*
Y1218642D03*
X1657597Y1237048D03*
X1653197Y1225335D03*
Y1248760D03*
Y1255453D03*
X1660594Y1298735D03*
X1651187D03*
X1660594Y1303935D03*
Y1306535D03*
Y1301335D03*
X1651187Y1303935D03*
Y1306535D03*
Y1301335D03*
X1650177Y1351467D03*
Y1348567D03*
X1658904Y1351467D03*
Y1348567D03*
X1662010Y1384570D03*
X1662766Y1377814D03*
X1660166D03*
X1662766Y1374707D03*
X1660166D03*
X1651301Y1378765D03*
X1662010Y1390170D03*
X1654774Y1402619D03*
X1648857Y1403424D03*
X1662465Y1444358D03*
X1653960Y1485895D03*
X1655870Y1483295D03*
X1660650D03*
X1655870Y1488495D03*
X1660650D03*
X1649170Y1492995D03*
X1653950D03*
X1649170Y1498195D03*
X1653950D03*
X1654505Y1583897D03*
X1659229Y1583797D03*
X1649780Y1583897D03*
X1651321Y1637876D03*
Y1632884D03*
Y1649788D03*
Y1644796D03*
X1653464Y1668416D03*
X1661101Y1671631D03*
X1651101Y1700478D03*
X1660541Y1704237D03*
X1677972Y25977D03*
X1676121Y19541D03*
X1675972Y23981D03*
X1671016D03*
X1669016Y25977D03*
X1677040Y37106D03*
X1669953D03*
X1677040Y48720D03*
X1669953D03*
X1677204Y75340D03*
X1672960Y71839D03*
X1667980Y66847D03*
X1672960D03*
X1667980Y71839D03*
X1666070Y69340D03*
X1663610Y394727D03*
X1664789Y756765D03*
Y763765D03*
X1669339Y773563D03*
X1673739Y791969D03*
X1663889Y786949D03*
X1669339Y780256D03*
X1663889Y796988D03*
X1669339Y803681D03*
Y810374D03*
Y817067D03*
X1673739Y828780D03*
X1663889Y823760D03*
Y833799D03*
X1669339Y840492D03*
Y847185D03*
X1673739Y865591D03*
X1663889Y860571D03*
X1669339Y853878D03*
X1663889Y870610D03*
X1669339Y877303D03*
Y883996D03*
Y890689D03*
X1673739Y902402D03*
X1663889Y897382D03*
Y907422D03*
X1669339Y914114D03*
Y920807D03*
X1673739Y939213D03*
X1663889Y934193D03*
X1669339Y927500D03*
X1663889Y944233D03*
X1669339Y950925D03*
Y957618D03*
Y964311D03*
Y971004D03*
Y977697D03*
Y984390D03*
Y991083D03*
Y997776D03*
Y1004469D03*
Y1031240D03*
Y1037933D03*
Y1044626D03*
Y1051319D03*
Y1058012D03*
Y1068051D03*
Y1074744D03*
X1673739Y1086457D03*
X1663889Y1081437D03*
Y1091477D03*
X1669339Y1098170D03*
Y1104862D03*
X1663889Y1118248D03*
X1669339Y1111555D03*
X1673739Y1123268D03*
X1663889Y1128288D03*
X1669339Y1134981D03*
Y1141674D03*
Y1148366D03*
X1673739Y1160079D03*
X1663889Y1155059D03*
Y1165099D03*
X1669339Y1171792D03*
Y1178485D03*
X1663889Y1191870D03*
X1669339Y1185177D03*
X1673739Y1196890D03*
X1663889Y1201910D03*
X1669339Y1208603D03*
Y1215296D03*
Y1221988D03*
X1673739Y1233701D03*
X1663889Y1228681D03*
Y1238721D03*
X1669339Y1245414D03*
Y1252107D03*
X1675187Y1298735D03*
Y1303935D03*
Y1306535D03*
Y1301335D03*
X1674831Y1351266D03*
Y1348366D03*
X1675901Y1377594D03*
Y1380551D03*
X1666870Y1384570D03*
X1664440D03*
X1675510Y1374723D03*
X1667966Y1374707D03*
X1670566D03*
X1665366Y1377814D03*
Y1380771D03*
Y1374707D03*
X1667966Y1377814D03*
Y1380771D03*
X1673066Y1374707D03*
X1666870Y1390170D03*
X1664440D03*
X1666919Y1402585D03*
X1671067Y1405418D03*
X1672277Y1407694D03*
X1674777D03*
X1672907Y1429928D03*
X1672273Y1420567D03*
X1666290Y1444391D03*
X1667360Y1485895D03*
X1669270Y1483295D03*
X1674050D03*
X1669270Y1488495D03*
X1674050D03*
X1673674Y1563575D03*
X1670248Y1581563D03*
X1670534Y1670149D03*
X1673245Y1673475D03*
X1664256Y1690794D03*
X1673132Y1690741D03*
X1665520Y1716877D03*
Y1732027D03*
X1682965Y3001D03*
X1692262Y17045D03*
X1678088D03*
X1683068D03*
X1692262Y22037D03*
X1692145Y25977D03*
X1678088Y22037D03*
X1683068D03*
X1690294Y19541D03*
X1685077D03*
X1690145Y23981D03*
X1685189D03*
X1683189Y25977D03*
X1684127Y37106D03*
X1691213D03*
Y48720D03*
X1684127D03*
X1679114Y72847D03*
X1688200Y69343D03*
X1690114Y66850D03*
Y71842D03*
X1684094Y72847D03*
X1679114Y77839D03*
X1684094D03*
X1687448Y756765D03*
Y760265D03*
X1682898Y776910D03*
X1687448Y767265D03*
X1682898Y783603D03*
X1687298Y795315D03*
X1682898Y807028D03*
Y820414D03*
Y813721D03*
X1687298Y832126D03*
X1682898Y850532D03*
Y843839D03*
Y857225D03*
X1687298Y868937D03*
X1682898Y880650D03*
Y894036D03*
Y887343D03*
X1687298Y905749D03*
X1682898Y917461D03*
Y924154D03*
Y930847D03*
X1687298Y942560D03*
X1682898Y954272D03*
Y967658D03*
Y960965D03*
Y981044D03*
Y974351D03*
Y994429D03*
Y987736D03*
Y1004469D03*
Y1041280D03*
Y1034587D03*
Y1054666D03*
Y1047973D03*
Y1061359D03*
Y1071398D03*
Y1078091D03*
X1687298Y1089804D03*
X1682898Y1101516D03*
Y1108209D03*
Y1114902D03*
X1687298Y1126615D03*
X1682898Y1138327D03*
Y1145020D03*
Y1151713D03*
X1687298Y1163426D03*
X1682898Y1175138D03*
Y1188524D03*
Y1181831D03*
X1687298Y1200237D03*
X1682898Y1211949D03*
Y1218642D03*
Y1225335D03*
X1687298Y1237048D03*
X1682898Y1248760D03*
Y1255453D03*
X1684708Y1298435D03*
Y1303635D03*
Y1306235D03*
Y1301035D03*
X1687233Y1351320D03*
X1679133Y1351420D03*
X1687233Y1348420D03*
X1679133Y1348520D03*
X1679180Y1372169D03*
X1681780D03*
X1679180Y1366969D03*
X1681780D03*
Y1369569D03*
X1679180D03*
X1683896Y1378765D03*
X1692948Y1377914D03*
Y1374807D03*
X1680530Y1374669D03*
X1685963Y1402187D03*
X1687621Y1404138D03*
X1684172Y1538135D03*
X1682561Y1552726D03*
X1691226Y1563526D03*
X1680558Y1555690D03*
X1691226Y1559526D03*
X1682494Y1568271D03*
Y1575125D03*
X1680491Y1578089D03*
Y1571235D03*
X1689880Y1572067D03*
X1679420Y1683597D03*
X1683013Y1713684D03*
X1680519Y1726825D03*
X1689383Y1729187D03*
X1704965Y3001D03*
X1697242Y17045D03*
X1699250Y19541D03*
X1697242Y22037D03*
X1698300Y37106D03*
X1705381Y37108D03*
X1698300Y48720D03*
X1705386D03*
X1701114Y72847D03*
X1706094D03*
X1699204Y75340D03*
X1695094Y66850D03*
Y71842D03*
X1706094Y77839D03*
X1701114D03*
X1694490Y756765D03*
Y763765D03*
X1699040Y773563D03*
X1703440Y791969D03*
X1699040Y780256D03*
X1693590Y786949D03*
X1699040Y803681D03*
X1693590Y796988D03*
X1699040Y817067D03*
Y810374D03*
X1693590Y823760D03*
X1703440Y828780D03*
X1693590Y833799D03*
X1699040Y847185D03*
Y840492D03*
Y853878D03*
X1693590Y860571D03*
X1703440Y865591D03*
X1693590Y870610D03*
X1699040Y877303D03*
Y883996D03*
Y890689D03*
X1693590Y907422D03*
X1703440Y902402D03*
X1693590Y897382D03*
X1699040Y914114D03*
Y920807D03*
X1693590Y934193D03*
X1699040Y927500D03*
X1703440Y939213D03*
X1693590Y944233D03*
X1699040Y950925D03*
Y964311D03*
Y971004D03*
Y957618D03*
Y977697D03*
Y984390D03*
Y997776D03*
Y991083D03*
Y1004469D03*
Y1044626D03*
Y1037933D03*
Y1031240D03*
Y1058012D03*
Y1051319D03*
Y1074744D03*
Y1068051D03*
X1703440Y1086457D03*
X1693590Y1081437D03*
Y1091477D03*
X1699040Y1104862D03*
Y1098170D03*
Y1111555D03*
X1693590Y1118248D03*
X1699040Y1134981D03*
X1703440Y1123268D03*
X1693590Y1128288D03*
X1699040Y1141674D03*
Y1148366D03*
X1693590Y1155059D03*
Y1165099D03*
X1703440Y1160079D03*
X1699040Y1171792D03*
Y1178485D03*
X1693590Y1191870D03*
X1699040Y1185177D03*
X1693590Y1201910D03*
X1703440Y1196890D03*
X1699040Y1208603D03*
Y1221988D03*
Y1215296D03*
X1693590Y1228681D03*
Y1238721D03*
X1703440Y1233701D03*
X1699040Y1245414D03*
Y1252107D03*
X1699087Y1298435D03*
Y1303635D03*
Y1306235D03*
Y1301035D03*
X1695533Y1351320D03*
Y1348420D03*
X1694792Y1384670D03*
X1700748Y1377914D03*
Y1380871D03*
Y1374807D03*
X1703348D03*
X1705848D03*
X1698148Y1377914D03*
X1695548D03*
X1698148Y1380871D03*
X1695548Y1374807D03*
X1698148D03*
X1699652Y1384670D03*
X1697222D03*
X1699652Y1390270D03*
X1694792D03*
X1697222D03*
X1699701Y1402685D03*
X1700520Y1716877D03*
X1702777Y1723593D03*
X1695166Y1717606D03*
X1720148Y22910D03*
X1710886Y82208D03*
X1715550Y102923D03*
X1721400Y374462D03*
X1718241Y652105D03*
X1717149Y756765D03*
Y760265D03*
X1712599Y776910D03*
X1717149Y767265D03*
X1712599Y783603D03*
Y807028D03*
X1716999Y795315D03*
X1712599Y820414D03*
Y813721D03*
X1716999Y832126D03*
X1712599Y850532D03*
Y843839D03*
Y857225D03*
X1716999Y868937D03*
X1712599Y880650D03*
Y894036D03*
Y887343D03*
X1716999Y905749D03*
X1712599Y917461D03*
Y924154D03*
Y930847D03*
X1716999Y942560D03*
X1712599Y954272D03*
Y967658D03*
Y960965D03*
Y981044D03*
Y974351D03*
Y994429D03*
Y987736D03*
Y1004469D03*
Y1041280D03*
Y1034587D03*
Y1054666D03*
Y1047973D03*
Y1061359D03*
Y1071398D03*
Y1078091D03*
X1716999Y1089804D03*
X1712599Y1101516D03*
Y1108209D03*
Y1114902D03*
X1716999Y1126615D03*
X1712599Y1138327D03*
Y1145020D03*
Y1151713D03*
X1716999Y1163426D03*
X1712599Y1175138D03*
Y1188524D03*
Y1181831D03*
X1716999Y1200237D03*
X1712599Y1218642D03*
Y1211949D03*
Y1225335D03*
X1716999Y1237048D03*
X1712599Y1248760D03*
Y1255453D03*
X1721754Y1299488D03*
X1708754Y1298388D03*
X1721847Y1307298D03*
X1721754Y1304688D03*
X1708754Y1300988D03*
X1721754Y1302088D03*
X1708754Y1303588D03*
Y1306188D03*
X1718813Y1348450D03*
Y1351350D03*
X1709533Y1351520D03*
Y1348620D03*
X1711962Y1367069D03*
X1714562D03*
X1711962Y1369669D03*
X1714562D03*
X1719902Y1368509D03*
Y1365909D03*
Y1363409D03*
X1708678Y1380621D03*
Y1377664D03*
X1716267Y1375178D03*
X1713312Y1374769D03*
X1708292Y1374823D03*
X1720210Y1435330D03*
X1719893Y1594940D03*
Y1612940D03*
Y1599740D03*
Y1603040D03*
Y1606340D03*
Y1609640D03*
X1722133Y1725340D03*
X1727111Y-38849D03*
Y-28849D03*
X1726965Y3001D03*
X1732286Y28208D03*
X1728786D03*
X1725286D03*
X1727336Y57024D03*
X1726596Y61784D03*
X1729836Y57024D03*
X1726596Y64284D03*
X1726814Y102968D03*
X1733344Y134953D03*
X1736474D03*
X1730364Y177588D03*
X1725400Y372062D03*
X1737260Y368132D03*
X1732660Y372692D03*
X1725500Y383662D03*
X1723259Y653641D03*
X1726334Y670345D03*
X1724191Y756765D03*
Y763765D03*
X1728741Y773563D03*
X1733141Y791969D03*
X1723291Y786949D03*
X1728741Y780256D03*
Y803681D03*
X1723291Y796988D03*
X1728741Y817067D03*
Y810374D03*
X1733141Y828780D03*
X1723291Y823760D03*
Y833799D03*
X1728741Y847185D03*
Y840492D03*
Y853878D03*
X1733141Y865591D03*
X1723291Y860571D03*
Y870610D03*
X1728741Y877303D03*
Y883996D03*
Y890689D03*
X1723291Y907422D03*
X1733141Y902402D03*
X1723291Y897382D03*
X1728741Y914114D03*
Y920807D03*
X1723291Y934193D03*
X1728741Y927500D03*
X1733141Y939213D03*
X1723291Y944233D03*
X1728741Y950925D03*
Y964311D03*
Y971004D03*
Y957618D03*
Y977697D03*
Y984390D03*
Y997776D03*
Y991083D03*
Y1004469D03*
Y1044626D03*
Y1037933D03*
Y1031240D03*
Y1058012D03*
Y1051319D03*
Y1074744D03*
Y1068051D03*
X1733141Y1086457D03*
X1723291Y1081437D03*
Y1091477D03*
X1728741Y1104862D03*
Y1098170D03*
Y1111555D03*
X1723291Y1118248D03*
X1728741Y1134981D03*
X1733141Y1123268D03*
X1723291Y1128288D03*
X1728741Y1141674D03*
Y1148366D03*
X1723291Y1155059D03*
X1733141Y1160079D03*
X1723291Y1165099D03*
X1728741Y1171792D03*
Y1178485D03*
X1723291Y1191870D03*
X1728741Y1185177D03*
X1723291Y1201910D03*
X1733141Y1196890D03*
X1728741Y1208603D03*
Y1221988D03*
Y1215296D03*
X1733141Y1233701D03*
X1723291Y1228681D03*
Y1238721D03*
X1728741Y1245414D03*
Y1252107D03*
X1732624Y1299718D03*
X1732717Y1307528D03*
X1732624Y1302318D03*
Y1304918D03*
X1735202Y1368279D03*
Y1365679D03*
Y1363179D03*
X1723917Y1380518D03*
Y1377178D03*
X1737126Y1403838D03*
Y1401238D03*
X1722810Y1435330D03*
X1737541Y1543707D03*
X1734575Y1562068D03*
X1724323Y1676965D03*
X1748965Y3001D03*
X1752008Y25146D03*
X1748116Y37058D03*
X1745451Y119585D03*
X1747448Y121413D03*
X1750325Y179827D03*
X1750851Y216427D03*
X1748325D03*
X1752461Y255337D03*
Y252337D03*
X1742652Y671494D03*
X1746850Y756765D03*
Y760265D03*
X1742300Y776910D03*
X1746850Y767265D03*
X1742300Y783603D03*
X1746700Y795315D03*
X1742300Y807028D03*
Y820414D03*
Y813721D03*
X1746700Y832126D03*
X1742300Y850532D03*
Y843839D03*
Y857225D03*
X1746700Y868937D03*
X1742300Y880650D03*
Y894036D03*
Y887343D03*
X1746700Y905749D03*
X1742300Y917461D03*
Y924154D03*
Y930847D03*
X1746700Y942560D03*
X1742300Y954272D03*
Y960965D03*
Y967658D03*
Y981044D03*
Y974351D03*
Y994429D03*
Y987736D03*
Y1004469D03*
Y1041280D03*
Y1034587D03*
Y1054666D03*
Y1047973D03*
Y1061359D03*
Y1071398D03*
Y1078091D03*
X1746700Y1089804D03*
X1742300Y1101516D03*
Y1108209D03*
Y1114902D03*
X1746700Y1126615D03*
X1742300Y1138327D03*
Y1145020D03*
Y1151713D03*
X1746700Y1163426D03*
X1742300Y1175138D03*
Y1188524D03*
Y1181831D03*
X1746700Y1200237D03*
X1742300Y1218642D03*
Y1211949D03*
Y1225335D03*
X1746700Y1237048D03*
X1742300Y1248760D03*
Y1255453D03*
X1743072Y1432211D03*
X1743188Y1543871D03*
Y1547871D03*
X1740587Y1547946D03*
X1737738Y1548021D03*
X1740400Y1543682D03*
X1752364Y1556323D03*
Y1559430D03*
X1744564Y1556323D03*
Y1559430D03*
X1749764Y1556323D03*
Y1559430D03*
X1747164Y1556323D03*
Y1559430D03*
X1752564Y1562537D03*
X1751518Y1566186D03*
X1740079Y1559505D03*
X1740188Y1556371D03*
X1746558Y1566186D03*
X1749038D03*
X1749964Y1562537D03*
X1751518Y1571786D03*
X1746558D03*
X1749038D03*
X1739640Y1713383D03*
Y1728533D03*
X1762420Y17031D03*
X1763840Y37790D03*
X1753398Y48720D03*
X1760485D03*
X1759666Y57708D03*
X1764366Y57508D03*
X1758047Y68637D03*
X1758539Y87153D03*
Y83653D03*
X1758534Y79743D03*
X1765034Y80443D03*
X1766244Y93673D03*
X1766911Y179890D03*
X1752851Y179827D03*
X1757385Y179890D03*
X1764385D03*
X1759911D03*
X1757951Y216427D03*
X1755425D03*
X1762485Y216490D03*
X1765011D03*
X1758859Y251544D03*
Y248544D03*
X1766399Y251361D03*
Y248361D03*
X1753892Y756765D03*
Y763765D03*
X1758442Y773563D03*
X1762842Y791969D03*
X1752992Y786949D03*
X1758442Y780256D03*
Y803681D03*
X1752992Y796988D03*
X1758442Y817067D03*
Y810374D03*
X1752992Y823760D03*
Y833799D03*
X1762842Y828780D03*
X1758442Y847185D03*
Y840492D03*
X1752992Y860571D03*
X1758442Y853878D03*
X1762842Y865591D03*
X1752992Y870610D03*
X1758442Y877303D03*
Y883996D03*
Y890689D03*
X1752992Y907422D03*
Y897382D03*
X1762842Y902402D03*
X1758442Y914114D03*
Y920807D03*
X1752992Y934193D03*
X1758442Y927500D03*
X1762842Y939213D03*
X1752992Y944233D03*
X1758442Y950925D03*
Y964311D03*
Y971004D03*
Y957618D03*
Y977697D03*
Y984390D03*
Y997776D03*
Y991083D03*
Y1004469D03*
Y1044626D03*
Y1037933D03*
Y1031240D03*
Y1058012D03*
Y1051319D03*
Y1074744D03*
Y1068051D03*
X1752992Y1081437D03*
X1762842Y1086457D03*
X1752992Y1091477D03*
X1758442Y1104862D03*
Y1098170D03*
X1752992Y1118248D03*
X1758442Y1111555D03*
Y1134981D03*
X1752992Y1128288D03*
X1762842Y1123268D03*
X1758442Y1141674D03*
Y1148366D03*
X1752992Y1155059D03*
Y1165099D03*
X1762842Y1160079D03*
X1758442Y1171792D03*
Y1178485D03*
X1752992Y1191870D03*
X1758442Y1185177D03*
X1752992Y1201910D03*
X1762842Y1196890D03*
X1758442Y1208603D03*
Y1221988D03*
Y1215296D03*
X1752992Y1228681D03*
Y1238721D03*
X1762842Y1233701D03*
X1758442Y1245414D03*
Y1252107D03*
X1758238Y1556238D03*
X1761108Y1556339D03*
Y1559446D03*
X1761079Y1562605D03*
X1755038Y1556238D03*
X1765709Y1556050D03*
X1754479Y1585905D03*
X1754763Y1641665D03*
X1752864Y1716383D03*
X1770965Y3001D03*
X1772886Y37430D03*
X1768134Y80543D03*
X1771385Y179890D03*
X1773911D03*
X1778500Y183790D03*
X1769585Y215090D03*
X1772111D03*
X1776585D03*
X1779111D03*
X1778874Y253799D03*
Y256799D03*
X1770520Y364148D03*
Y368148D03*
X1771236Y557224D03*
X1776550Y756765D03*
Y760265D03*
X1772000Y776910D03*
X1776550Y767265D03*
X1772000Y783603D03*
Y807028D03*
X1776400Y795315D03*
X1772000Y813721D03*
Y820414D03*
X1776400Y832126D03*
X1772000Y850532D03*
Y843839D03*
Y857225D03*
X1776400Y868937D03*
X1772000Y880650D03*
Y894036D03*
Y887343D03*
X1776400Y905749D03*
X1772000Y917461D03*
Y924154D03*
Y930847D03*
X1776400Y942560D03*
X1772000Y954272D03*
Y967658D03*
Y960965D03*
Y981044D03*
Y974351D03*
Y994429D03*
Y987736D03*
Y1004469D03*
Y1041280D03*
Y1034587D03*
Y1047973D03*
Y1054666D03*
Y1061359D03*
Y1071398D03*
Y1078091D03*
X1776400Y1089804D03*
X1772000Y1101516D03*
Y1108209D03*
Y1114902D03*
X1776400Y1126615D03*
X1772000Y1138327D03*
Y1145020D03*
Y1151713D03*
X1776400Y1163426D03*
X1772000Y1175138D03*
Y1188524D03*
Y1181831D03*
X1776400Y1200237D03*
X1772000Y1218642D03*
Y1211949D03*
Y1225335D03*
X1776400Y1237048D03*
X1772000Y1248760D03*
Y1255453D03*
X1776188Y1543871D03*
Y1546871D03*
X1769188D03*
Y1543871D03*
X1768688Y1552871D03*
Y1549871D03*
X1772688Y1543871D03*
Y1546871D03*
X1776113Y1541172D03*
X1769113D03*
X1772613D03*
X1780307Y1559430D03*
Y1556323D03*
X1775979Y1556805D03*
Y1559805D03*
X1782301Y1566186D03*
X1768209Y1556000D03*
X1769826Y1562559D03*
X1782301Y1571786D03*
X1792965Y3001D03*
X1796781Y46686D03*
X1785144Y86973D03*
Y89973D03*
X1783448Y212957D03*
X1795794Y253719D03*
X1787534Y253769D03*
X1795794Y256719D03*
X1787534Y256769D03*
X1795479Y408056D03*
X1795468Y421334D03*
X1783592Y756765D03*
X1788142Y773563D03*
X1792542Y791969D03*
X1782692Y786949D03*
X1788142Y780256D03*
X1782692Y796988D03*
X1788142Y803681D03*
Y817067D03*
Y810374D03*
X1782692Y823760D03*
Y833799D03*
X1792542Y828780D03*
X1788142Y847185D03*
Y840492D03*
Y853878D03*
X1792542Y865591D03*
X1782692Y860571D03*
Y870610D03*
X1788142Y877303D03*
Y883996D03*
Y890689D03*
X1782692Y907422D03*
Y897382D03*
X1792542Y902402D03*
X1788142Y914114D03*
Y920807D03*
X1782692Y934193D03*
X1788142Y927500D03*
X1792542Y939213D03*
X1782692Y944233D03*
X1788142Y950925D03*
Y964311D03*
Y971004D03*
Y957618D03*
Y977697D03*
Y984390D03*
Y997776D03*
Y991083D03*
Y1004469D03*
Y1044626D03*
Y1037933D03*
Y1031240D03*
Y1058012D03*
Y1051319D03*
Y1074744D03*
Y1068051D03*
X1782692Y1081437D03*
X1792542Y1086457D03*
X1782692Y1091477D03*
X1788142Y1098170D03*
Y1104862D03*
X1782692Y1118248D03*
X1788142Y1111555D03*
Y1134981D03*
X1782692Y1128288D03*
X1792542Y1123268D03*
X1788142Y1141674D03*
Y1148366D03*
X1782692Y1155059D03*
Y1165099D03*
X1792542Y1160079D03*
X1788142Y1171792D03*
Y1178485D03*
X1782692Y1191870D03*
X1788142Y1185177D03*
X1782692Y1201910D03*
X1792542Y1196890D03*
X1788142Y1208603D03*
Y1221988D03*
Y1215296D03*
X1782692Y1228681D03*
Y1238721D03*
X1792542Y1233701D03*
X1788142Y1245414D03*
Y1252107D03*
X1796838Y1556125D03*
X1788107Y1556323D03*
X1793833Y1556195D03*
X1790633D03*
X1788107Y1559430D03*
X1788307Y1562537D03*
X1787261Y1566186D03*
X1782907Y1559430D03*
Y1556323D03*
X1784781Y1566186D03*
X1785507Y1559430D03*
Y1556323D03*
X1785707Y1562537D03*
X1796257Y1561255D03*
Y1558755D03*
X1787261Y1571786D03*
X1784781D03*
X1788679Y1585805D03*
X1807515Y56461D03*
X1807546Y59443D03*
X1807296Y255033D03*
X1804174Y253739D03*
Y256739D03*
X1803129Y362293D03*
X1802929Y385293D03*
X1804688Y1545871D03*
Y1542371D03*
Y1552871D03*
Y1549371D03*
X1801688Y1545871D03*
Y1542371D03*
Y1552871D03*
Y1549371D03*
X1804688Y1555871D03*
X1801688D03*
X1804688Y1559371D03*
X1818615Y49379D03*
X1818155Y149325D03*
X1819529Y320321D03*
X1820307Y373829D03*
X1820656Y388051D03*
X1820144Y398052D03*
X1819374Y410432D03*
X1818874Y423932D03*
X1840615Y49379D03*
X1853692Y308447D03*
G54D38*
X311115Y1214093D03*
X310957Y1219126D03*
X388805Y1218420D03*
X388647Y1223453D03*
X386461Y1235718D03*
X386303Y1240751D03*
X1898799Y1810398D03*
X1908799D03*
X1931395Y572237D03*
X1921395D03*
X1942395Y1184617D03*
X1940886Y1810370D03*
X1963362Y572379D03*
X1952395Y1184617D03*
X1950886Y1810370D03*
X1973362Y572379D03*
X1984482Y1184589D03*
X1992856Y1810550D03*
X1982856D03*
X2005452Y572389D03*
X1994482Y1184589D03*
X2015452Y572389D03*
X2036452Y1184769D03*
X2026452D03*
X2047419Y572531D03*
X2057419D03*
X2078539Y1184741D03*
X2068539D03*
G54D55*
X828780Y1684890D03*
X818780D03*
X828780Y1694890D03*
X818780D03*
X828780Y1704890D03*
X818780D03*
X828780Y1714890D03*
X818780D03*
X853780Y1684890D03*
Y1694890D03*
Y1704890D03*
Y1714890D03*
X863780Y1684890D03*
Y1694890D03*
Y1704890D03*
Y1714890D03*
X888780Y1684890D03*
Y1694890D03*
Y1704890D03*
Y1714890D03*
X898780Y1684890D03*
Y1694890D03*
Y1704890D03*
Y1714890D03*
X918780Y1704890D03*
X958780Y1684890D03*
Y1694890D03*
Y1704890D03*
Y1714890D03*
X968780Y1684890D03*
Y1694890D03*
Y1704890D03*
Y1714890D03*
X993780Y1684890D03*
Y1694890D03*
Y1704890D03*
Y1714890D03*
X1003780Y1684890D03*
Y1694890D03*
Y1704890D03*
Y1714890D03*
X1028780Y1684890D03*
X1038780D03*
X1028780Y1694890D03*
X1038780D03*
X1028780Y1704890D03*
Y1714890D03*
X1038780Y1704890D03*
Y1714890D03*
G54D29*
X182947Y1507512D03*
X186530Y1521453D03*
X185688Y1519195D03*
X186860Y1514243D03*
X186579Y1536063D03*
X177579Y1528725D03*
Y1523810D03*
X183051Y1542425D03*
X185966Y1592380D03*
Y1624292D03*
X188254Y1507295D03*
X192979D03*
X197703D03*
X191254Y1521453D03*
X195979D03*
X200703D03*
X196309Y1514243D03*
X201033D03*
X191584D03*
X187081Y1528853D03*
X191805D03*
X196530D03*
X201254D03*
X196029Y1536063D03*
X200753D03*
X191304D03*
X197703Y1542641D03*
X188254D03*
X192979D03*
X198026Y1592380D03*
X193766D03*
X192006Y1602380D03*
X199786D03*
X193766Y1624292D03*
X198026D03*
X199786Y1614292D03*
X192006D03*
X202427Y1507295D03*
X207152D03*
X211876D03*
X216601D03*
X205427Y1521453D03*
X210152D03*
X214876D03*
X205758Y1514243D03*
X215206D03*
X210482D03*
X205978Y1528853D03*
X210703D03*
X215427D03*
X214926Y1536063D03*
X211876Y1542641D03*
X202427D03*
X207152D03*
X216601D03*
X210086Y1592380D03*
X205826D03*
X216126Y1602380D03*
X204066D03*
X211846D03*
X205826Y1624292D03*
X210086D03*
X216126Y1614292D03*
X211846D03*
X204066D03*
X221325Y1507295D03*
X226049D03*
X230774D03*
X219601Y1521453D03*
X224325D03*
X229049D03*
X219931Y1514243D03*
X224655D03*
X229380D03*
X220152Y1528853D03*
X224876D03*
X229600D03*
X224375Y1536063D03*
X226049Y1542641D03*
X230774D03*
X221325D03*
X229946Y1592380D03*
X217886D03*
X222146D03*
X223906Y1602380D03*
X228186D03*
X229946Y1624292D03*
X222146D03*
X217886D03*
X228186Y1614292D03*
X223906D03*
X235498Y1507295D03*
X240223D03*
X244947D03*
X243223Y1521453D03*
X238498D03*
X233774D03*
X234104Y1514243D03*
X238828D03*
X243553D03*
X243774Y1528853D03*
X239049D03*
X234325D03*
X238548Y1536063D03*
X240223Y1542641D03*
X235498D03*
X244947D03*
X242006Y1592380D03*
X234206D03*
X246266D03*
X235966Y1602380D03*
X240246D03*
X246266Y1624292D03*
X242006D03*
X234206D03*
X240246Y1614292D03*
X235966D03*
X241141Y1679320D03*
Y1683857D03*
X233267Y1675383D03*
Y1679920D03*
Y1684454D03*
X241141Y1688391D03*
Y1693493D03*
Y1698030D03*
X233267Y1689556D03*
Y1694093D03*
Y1698627D03*
X241141Y1702564D03*
Y1707666D03*
Y1712203D03*
Y1716737D03*
X233267Y1703729D03*
Y1708266D03*
Y1712800D03*
X241141Y1721840D03*
Y1726377D03*
Y1730911D03*
X233267Y1717903D03*
Y1722440D03*
Y1726974D03*
X259120Y1507295D03*
X249671D03*
X254396D03*
X257396Y1521453D03*
X252672D03*
X247947D03*
X248277Y1514243D03*
X257726D03*
X257947Y1528853D03*
X253223D03*
X248498D03*
X257446Y1536063D03*
X247997D03*
X254396Y1542641D03*
X259120D03*
X249671D03*
X258326Y1592380D03*
X254066D03*
X248026Y1602380D03*
X252306D03*
X260086D03*
X258326Y1624292D03*
X254066D03*
X248026Y1614292D03*
X252306D03*
X260086D03*
X256889Y1679320D03*
Y1683857D03*
X249015Y1684454D03*
Y1679920D03*
Y1675383D03*
X256889Y1688391D03*
Y1693493D03*
Y1698030D03*
X249015Y1698627D03*
Y1694093D03*
Y1689556D03*
X256889Y1702564D03*
Y1707666D03*
Y1712203D03*
Y1716737D03*
X249015Y1712800D03*
Y1708266D03*
Y1703729D03*
X256889Y1721840D03*
Y1726377D03*
Y1730911D03*
X249015Y1726974D03*
Y1722440D03*
Y1717903D03*
X262141Y1521453D03*
X262777Y1536063D03*
X270386Y1592380D03*
X266126D03*
X264366Y1602380D03*
X272146D03*
X270386Y1624292D03*
X266126D03*
X272146Y1614292D03*
X264366D03*
X272637Y1679320D03*
Y1683857D03*
X264763Y1684454D03*
Y1679920D03*
Y1675383D03*
X272637Y1688391D03*
Y1693493D03*
Y1698030D03*
X264763Y1698627D03*
Y1694093D03*
Y1689556D03*
X272637Y1702564D03*
Y1707666D03*
Y1712203D03*
Y1716737D03*
X264763Y1712800D03*
Y1708266D03*
Y1703729D03*
X272637Y1721840D03*
Y1726377D03*
Y1730911D03*
X264763Y1726974D03*
Y1722440D03*
Y1717903D03*
X290246Y1592380D03*
X278186D03*
X282446D03*
X276426Y1602380D03*
X284206D03*
X288486D03*
X290236Y1624292D03*
X282446D03*
X278186D03*
X288486Y1614292D03*
X284206D03*
X276426D03*
X288385Y1683857D03*
Y1679320D03*
X280511Y1684454D03*
Y1679920D03*
Y1675383D03*
X288385Y1688391D03*
Y1693494D03*
Y1698031D03*
X280511Y1698627D03*
Y1694093D03*
Y1689556D03*
X288385Y1712204D03*
Y1716738D03*
Y1702565D03*
Y1707667D03*
X280511Y1712800D03*
Y1708266D03*
Y1703729D03*
X288385Y1721840D03*
Y1726377D03*
Y1730911D03*
X280511Y1726974D03*
Y1722440D03*
Y1717903D03*
X305641Y1528725D03*
Y1523810D03*
X302306Y1592380D03*
X294506D03*
X296266Y1602380D03*
X300546D03*
X302306Y1624292D03*
X294516D03*
X300546Y1614292D03*
X296266D03*
X300196Y1675383D03*
Y1679920D03*
Y1684454D03*
Y1689556D03*
Y1694093D03*
Y1698627D03*
Y1703729D03*
Y1708266D03*
Y1712800D03*
Y1717903D03*
Y1722440D03*
Y1726974D03*
X309886Y1028056D03*
X315437Y1031245D03*
X317288Y1040812D03*
X309886D03*
X317288Y1034434D03*
X309886D03*
X315437Y1044001D03*
X309886Y1047190D03*
X311736Y1056757D03*
X309886Y1053568D03*
X315437Y1050379D03*
X317288Y1053568D03*
Y1059946D03*
X309886D03*
X313587D03*
X315437Y1063135D03*
X317288Y1072702D03*
X309886D03*
Y1066324D03*
X315437Y1069513D03*
X317288Y1079080D03*
X309886D03*
X315437Y1082269D03*
Y1088647D03*
X309886Y1085458D03*
Y1091836D03*
X317288D03*
X309886Y1104592D03*
X315437Y1101403D03*
X317288Y1098214D03*
X309886D03*
X315437Y1107781D03*
X309886Y1110970D03*
X317288D03*
X309886Y1117348D03*
X317288D03*
X309886Y1123726D03*
X315437Y1120537D03*
Y1126915D03*
X309886Y1130103D03*
X317288D03*
X309886Y1136481D03*
X315437Y1139670D03*
X317288Y1136481D03*
X309886Y1142859D03*
X317288Y1149237D03*
X309886D03*
X315437Y1146048D03*
X317288Y1155615D03*
X309886D03*
X313587D03*
X308036Y1158804D03*
X311736Y1165182D03*
X320988Y1155615D03*
Y1161993D03*
X311009Y1507514D03*
X316316Y1507295D03*
X321041D03*
X319316Y1521453D03*
X314592D03*
X313750Y1519195D03*
X314922Y1514243D03*
X319646D03*
X319867Y1528853D03*
X315143D03*
X319366Y1536063D03*
X314641D03*
X311113Y1542425D03*
X316316Y1542641D03*
X321041D03*
X318626Y1592380D03*
X306566D03*
X314366D03*
X308326Y1602380D03*
X312606D03*
X320386D03*
X314366Y1624292D03*
X318626D03*
X306566D03*
X320386Y1614292D03*
X312606D03*
X308326D03*
X315944Y1675383D03*
Y1679920D03*
Y1684454D03*
X308070Y1683857D03*
Y1679320D03*
X315944Y1689556D03*
Y1694093D03*
Y1698627D03*
X308070Y1698030D03*
Y1693493D03*
Y1688391D03*
X315944Y1703729D03*
Y1708266D03*
Y1712800D03*
X308070Y1716737D03*
Y1712203D03*
Y1707666D03*
Y1702564D03*
X315944Y1722440D03*
Y1726974D03*
X308070Y1730911D03*
Y1726377D03*
Y1721840D03*
X315944Y1717903D03*
X328390Y1028056D03*
X335791D03*
X322839Y1031245D03*
Y1037623D03*
Y1044001D03*
X328390Y1040812D03*
Y1034434D03*
X330240Y1031245D03*
Y1037623D03*
Y1044001D03*
X335791Y1040812D03*
Y1034434D03*
X328390Y1047190D03*
X322839Y1050379D03*
Y1056757D03*
X326539D03*
X328390Y1053568D03*
Y1059946D03*
X324689D03*
X330240Y1050379D03*
Y1056757D03*
X335791Y1047190D03*
Y1053568D03*
Y1059946D03*
X328390Y1072702D03*
X330240Y1069513D03*
X335791Y1072702D03*
Y1066324D03*
X322839Y1063135D03*
X330240D03*
X322839Y1069513D03*
X328390Y1066324D03*
X322839Y1075891D03*
X330240D03*
X328390Y1079080D03*
X322839Y1088647D03*
X328390Y1085458D03*
X330240Y1088647D03*
X322839Y1082269D03*
X330240D03*
X335791Y1079080D03*
Y1085458D03*
X328390Y1091836D03*
X322839Y1095025D03*
X330240D03*
X328390Y1104592D03*
Y1098214D03*
X322839Y1101403D03*
X330240D03*
X335791Y1091836D03*
Y1104592D03*
Y1098214D03*
X322839Y1107781D03*
X330240D03*
X328390Y1110970D03*
Y1117348D03*
X330240Y1114159D03*
X322839D03*
X335791Y1110970D03*
Y1117348D03*
X330240Y1126915D03*
X322839D03*
X328390Y1123726D03*
X330240Y1120537D03*
X322839D03*
Y1133293D03*
X330240D03*
X328390Y1130103D03*
X335791Y1123726D03*
X335792Y1130105D03*
X328390Y1142859D03*
X322839Y1139670D03*
X328390Y1136481D03*
X330240Y1139670D03*
X328390Y1149237D03*
X330240Y1146048D03*
X322839D03*
X335791Y1136481D03*
Y1142859D03*
Y1149237D03*
X328390Y1155615D03*
X330240Y1152426D03*
X322839D03*
X326539Y1158804D03*
X330240D03*
X333941D03*
X322839D03*
X328390Y1161993D03*
X330240Y1165182D03*
X335791Y1155615D03*
Y1161993D03*
X330489Y1507295D03*
X335214D03*
X325765D03*
X333489Y1521453D03*
X328765D03*
X324041D03*
X324371Y1514243D03*
X329095D03*
X333820D03*
X334040Y1528853D03*
X329316D03*
X324592D03*
X324091Y1536063D03*
X328815D03*
X325765Y1542641D03*
X330489D03*
X335214D03*
X330686Y1592380D03*
X326426D03*
X324666Y1602380D03*
X332446D03*
X326426Y1624292D03*
X330686D03*
X332446Y1614292D03*
X324666D03*
X331692Y1675383D03*
Y1679920D03*
Y1684454D03*
X323818Y1683857D03*
Y1679320D03*
X331692Y1689556D03*
Y1694093D03*
Y1698627D03*
X323818Y1698030D03*
Y1693493D03*
Y1688391D03*
X331692Y1703729D03*
Y1708266D03*
Y1712800D03*
X323818Y1716737D03*
Y1712203D03*
Y1707666D03*
Y1702564D03*
Y1721840D03*
X331692Y1717903D03*
Y1722440D03*
Y1726974D03*
X323818Y1730911D03*
Y1726377D03*
X348744Y1031245D03*
X341343D03*
X343193Y1040812D03*
X348744Y1037623D03*
X343193Y1034434D03*
X348744Y1044001D03*
X341343D03*
X350595Y1059946D03*
X337642Y1056757D03*
X348744D03*
X343193Y1053568D03*
X341343Y1050379D03*
X348744D03*
X343193Y1059946D03*
X339492D03*
X341343Y1063135D03*
X348744D03*
X341343Y1069513D03*
X343193Y1072702D03*
X348744Y1069513D03*
X343193Y1079080D03*
X348744Y1075891D03*
X341343Y1082269D03*
X348744D03*
X341343Y1088647D03*
X348744D03*
Y1095025D03*
X343193Y1091836D03*
X348744Y1101403D03*
X341343D03*
X343193Y1098214D03*
X341343Y1107781D03*
X348744D03*
X343193Y1110970D03*
Y1117348D03*
X348744Y1114159D03*
Y1120537D03*
X341343D03*
Y1126915D03*
X348744D03*
Y1133293D03*
X343193Y1130103D03*
X341343Y1139670D03*
X343193Y1136481D03*
X348744Y1139670D03*
X343193Y1149237D03*
X348744Y1146048D03*
X341343D03*
X348744Y1152426D03*
X337642Y1158804D03*
X341343D03*
X348744D03*
X339492Y1155615D03*
X343193D03*
X346894D03*
X337642Y1165182D03*
X343193Y1161993D03*
X346894D03*
X348744Y1165182D03*
X339938Y1507295D03*
X344663D03*
X349387D03*
X347663Y1521453D03*
X342938D03*
X338214D03*
X338544Y1514243D03*
X343268D03*
X347993D03*
X348214Y1528853D03*
X343489D03*
X338765D03*
X342988Y1536063D03*
X339938Y1542641D03*
X344663D03*
X349387D03*
X338486Y1592380D03*
X342746D03*
X350546D03*
X336726Y1602380D03*
X344506D03*
X348786D03*
X350546Y1624292D03*
X342746D03*
X338486D03*
X348786Y1614292D03*
X344506D03*
X336726D03*
X347440Y1675383D03*
Y1679920D03*
Y1684454D03*
X339566Y1683857D03*
Y1679320D03*
X347440Y1694093D03*
Y1698627D03*
X339566Y1698030D03*
Y1693493D03*
Y1688391D03*
X347440Y1689556D03*
Y1703729D03*
Y1708266D03*
Y1712800D03*
X339566Y1716737D03*
Y1712203D03*
Y1707666D03*
Y1702564D03*
X347440Y1717903D03*
Y1722440D03*
Y1726974D03*
X339566Y1730911D03*
Y1726377D03*
Y1721840D03*
X354295Y1028056D03*
X361697D03*
Y1040812D03*
X356146Y1044001D03*
X354295Y1040812D03*
Y1034434D03*
X356146Y1031245D03*
Y1037623D03*
X361697Y1034434D03*
X354295Y1047190D03*
X361697D03*
X354295Y1053568D03*
Y1059946D03*
X363547Y1056757D03*
X356146D03*
Y1050379D03*
X361697Y1053568D03*
X365398Y1059946D03*
X361697D03*
X352445Y1056757D03*
X356146Y1063135D03*
X354295Y1072702D03*
Y1066324D03*
X356146Y1069513D03*
X361697Y1066324D03*
Y1072702D03*
X356146Y1075891D03*
X354295Y1079080D03*
X361697D03*
X354295Y1085458D03*
X356146Y1088647D03*
X361697Y1085458D03*
X356146Y1082269D03*
X354295Y1091836D03*
X361697D03*
X356146Y1095025D03*
X354295Y1104592D03*
Y1098214D03*
X361697Y1104592D03*
X356146Y1101403D03*
X361697Y1098214D03*
X356146Y1107781D03*
X354295Y1110970D03*
X361697D03*
Y1117348D03*
X356146Y1114159D03*
X354295Y1117348D03*
Y1123726D03*
X356146Y1126915D03*
Y1120537D03*
X361697Y1123726D03*
X356146Y1133293D03*
X361697Y1130103D03*
X354296Y1130105D03*
X354295Y1136481D03*
X356146Y1139670D03*
X361697Y1136481D03*
X354295Y1142859D03*
X361697D03*
Y1149237D03*
X356146Y1146048D03*
X354295Y1149237D03*
X363547Y1165182D03*
X356146D03*
X361697Y1161993D03*
X363547Y1158804D03*
X356146D03*
X359847D03*
X352445D03*
X365398Y1155615D03*
X356146Y1152426D03*
X361697Y1155615D03*
X354295D03*
Y1161993D03*
X354111Y1507295D03*
X358836D03*
X363560D03*
X361836Y1521453D03*
X357111D03*
X352387D03*
X352717Y1514243D03*
X357442D03*
X362166D03*
X362387Y1528853D03*
X357662D03*
X352938D03*
X352437Y1536063D03*
X354111Y1542641D03*
X358836D03*
X363560D03*
X362606Y1592380D03*
X354806D03*
X356566Y1602380D03*
X360846D03*
X354806Y1624292D03*
X360846Y1614292D03*
X356566D03*
X362606Y1624292D03*
X355314Y1683857D03*
Y1679320D03*
Y1688391D03*
Y1698030D03*
Y1693493D03*
Y1716737D03*
Y1712203D03*
Y1707666D03*
Y1702564D03*
Y1730911D03*
Y1726377D03*
Y1721840D03*
X380201Y1028056D03*
X367248Y1031245D03*
Y1044001D03*
X369099Y1034434D03*
Y1040812D03*
X374650Y1031245D03*
X380201Y1040812D03*
Y1034434D03*
X374650Y1037623D03*
Y1044001D03*
X367248Y1050379D03*
X380201Y1047190D03*
X369099Y1053568D03*
Y1059946D03*
X380201Y1053568D03*
X378351Y1056757D03*
X374650Y1050379D03*
Y1056757D03*
X380201Y1059946D03*
X376500D03*
X367248Y1063135D03*
Y1069513D03*
X374650Y1063135D03*
X369099Y1072702D03*
X380201D03*
X374650Y1069513D03*
X367248Y1088647D03*
Y1082269D03*
X374650Y1075891D03*
X369099Y1079080D03*
X380201Y1085458D03*
X374650Y1088647D03*
Y1082269D03*
X367248Y1101403D03*
X369099Y1091836D03*
X374650Y1095025D03*
X369099Y1098214D03*
X380201Y1104592D03*
Y1098214D03*
X374650Y1101403D03*
X367248Y1107781D03*
X374650D03*
X369099Y1110970D03*
Y1117348D03*
X380201D03*
X374650Y1114159D03*
X367248Y1120537D03*
Y1126915D03*
X374650Y1120537D03*
Y1126915D03*
X380201Y1130103D03*
X374650Y1133293D03*
X369099Y1130103D03*
X367248Y1139670D03*
Y1146048D03*
X380201Y1142859D03*
X374650Y1139670D03*
X369099Y1136481D03*
Y1149237D03*
X374650Y1146048D03*
X380201Y1155615D03*
X369099D03*
X372799D03*
X374650Y1152426D03*
X378351Y1158804D03*
X374650D03*
X376500Y1161993D03*
X377523Y1222274D03*
X372730Y1216782D03*
X367697Y1216624D03*
X377733Y1507295D03*
X368285D03*
X373009D03*
X376009Y1521453D03*
X380734D03*
X366560D03*
X371285D03*
X376339Y1514243D03*
X366890D03*
X371615D03*
X376560Y1528853D03*
X367111D03*
X371836D03*
X376059Y1536063D03*
X366610D03*
X377733Y1542641D03*
X368285D03*
X373009D03*
X374666Y1592380D03*
X366866D03*
X380696Y1602380D03*
X368626Y1602286D03*
X372906Y1602380D03*
X374666Y1624292D03*
X380696Y1614292D03*
X372906D03*
X368626D03*
X366866Y1624292D03*
X387603Y1028056D03*
X395004D03*
X393154Y1044001D03*
X385752Y1031245D03*
Y1037623D03*
Y1044001D03*
X395004Y1040812D03*
X387603Y1034434D03*
Y1040812D03*
X395004Y1034434D03*
X393154Y1031245D03*
Y1037623D03*
X395004Y1047190D03*
X387603D03*
Y1053568D03*
X391303Y1059946D03*
X395004Y1053568D03*
X385752Y1050379D03*
X393154Y1056757D03*
Y1050379D03*
X382051Y1063135D03*
Y1069513D03*
X393154Y1063135D03*
X395004Y1066324D03*
X387603D03*
X383902D03*
X391303Y1072702D03*
Y1066324D03*
X393154Y1069513D03*
X382051Y1075891D03*
Y1088647D03*
Y1082269D03*
X393154Y1075891D03*
X387603Y1079080D03*
X383902D03*
X391303D03*
X395004D03*
X393154Y1082269D03*
X391303Y1085458D03*
X393154Y1088647D03*
X382051Y1095025D03*
X383902Y1091836D03*
X393154Y1095025D03*
X391303Y1091836D03*
X395004D03*
X387603D03*
X391303Y1098214D03*
Y1104592D03*
X395004D03*
X387603D03*
X383902D03*
X382051Y1107781D03*
Y1114159D03*
X383902Y1110970D03*
X387603D03*
X393154Y1107781D03*
X391303Y1110970D03*
X395004D03*
X391303Y1117348D03*
X393154Y1114159D03*
X391304Y1130105D03*
X382051Y1126915D03*
Y1120537D03*
Y1133293D03*
X383902Y1123726D03*
X387603D03*
X393154Y1126915D03*
X391303Y1123726D03*
X395004D03*
X393154Y1120537D03*
Y1133293D03*
X382051Y1139670D03*
Y1146048D03*
X393154Y1139670D03*
X395004Y1136481D03*
X391303D03*
X383902D03*
X387603D03*
X391303Y1142859D03*
X393154Y1146048D03*
X395004Y1149237D03*
X383902D03*
X387603D03*
X389453Y1158804D03*
X391303Y1155615D03*
X395004D03*
X383902D03*
X387603D03*
Y1161993D03*
X382458Y1507295D03*
X387182D03*
X390203Y1521453D03*
X385458D03*
X385788Y1514243D03*
X381285Y1528853D03*
X386009D03*
X385508Y1536063D03*
X390839D03*
X382458Y1542641D03*
X387182D03*
X398705Y1028056D03*
X409795Y1028064D03*
X398705Y1034434D03*
X402406Y1040812D03*
X400555Y1031245D03*
Y1037623D03*
Y1044001D03*
X409795Y1034442D03*
Y1040820D03*
X402406Y1047190D03*
X409807D03*
X402406Y1053568D03*
X407957Y1056757D03*
X402406Y1059946D03*
X409807Y1053568D03*
X400555Y1056757D03*
Y1050379D03*
X407957D03*
X398705Y1066324D03*
X404256Y1063135D03*
X402406Y1072702D03*
X404256Y1069513D03*
X406107Y1066324D03*
X409807D03*
X402406D03*
X398705Y1079080D03*
X404256Y1075891D03*
X406107Y1079080D03*
X409807D03*
X402406D03*
X404256Y1088647D03*
X402406Y1085458D03*
X404256Y1082269D03*
X398705Y1091836D03*
Y1104592D03*
X404256Y1095025D03*
X406107Y1091836D03*
X409807D03*
X402406D03*
Y1098214D03*
Y1104592D03*
X398705Y1110970D03*
X404256Y1107781D03*
X406107Y1110970D03*
X409807D03*
X402406D03*
X404256Y1114159D03*
X402406Y1117348D03*
X398705Y1123726D03*
X406107D03*
X409807D03*
X404256Y1120537D03*
X402406Y1123726D03*
X404256Y1126915D03*
Y1133293D03*
X402406Y1130103D03*
X398705Y1136481D03*
Y1149237D03*
X402406Y1142859D03*
X404256Y1139670D03*
X406107Y1136481D03*
X409807D03*
X402406D03*
X404256Y1146048D03*
X406107Y1149237D03*
X409807D03*
X398705Y1155615D03*
Y1161993D03*
X406107Y1155615D03*
X409807D03*
X402406D03*
X400555Y1158804D03*
X409807Y1161993D03*
X400555Y1165182D03*
X424598Y1040820D03*
X417197D03*
X413508Y1059946D03*
X417209Y1047190D03*
X424610D03*
Y1053568D03*
X422760Y1056757D03*
X424610Y1059946D03*
X417209Y1053568D03*
X415358Y1056757D03*
Y1050379D03*
X422760D03*
X413508Y1072702D03*
Y1066324D03*
X415358Y1063135D03*
X424610Y1072702D03*
Y1066324D03*
X420910D03*
X417209D03*
X415358Y1069513D03*
X413508Y1079080D03*
Y1085458D03*
X415358Y1075891D03*
X420910Y1079080D03*
X424610D03*
X417209D03*
X424610Y1085458D03*
X415358Y1088647D03*
Y1082269D03*
X413508Y1091836D03*
Y1098214D03*
Y1104592D03*
X415358Y1095025D03*
X420910Y1091836D03*
X424610D03*
X417209D03*
X420910Y1104592D03*
X424610D03*
Y1098214D03*
X417209Y1104592D03*
X415358Y1101403D03*
X413508Y1110970D03*
Y1117348D03*
X415358Y1107781D03*
X424610Y1110970D03*
X420910D03*
X417209D03*
X424610Y1117348D03*
X415358Y1114159D03*
Y1120537D03*
Y1126915D03*
X424610Y1123726D03*
X420910D03*
X417209D03*
X415358Y1133293D03*
X413508Y1123726D03*
Y1130103D03*
X424611Y1130105D03*
X413508Y1142859D03*
Y1136481D03*
X424610Y1142859D03*
Y1136481D03*
X420910D03*
X415358Y1139670D03*
X417209Y1136481D03*
X420910Y1149237D03*
X417209D03*
X415358Y1146048D03*
X413508Y1155615D03*
X411658Y1158804D03*
X424610Y1155615D03*
X420910D03*
X417209D03*
X422760Y1158804D03*
Y1165182D03*
X420910Y1161993D03*
X430162Y1056757D03*
Y1050379D03*
X432012Y1047190D03*
Y1053568D03*
X435713Y1059946D03*
X426461Y1063135D03*
X430162D03*
X426461Y1069513D03*
X433862Y1063135D03*
X435713Y1072702D03*
Y1066324D03*
X430162Y1075891D03*
X426461D03*
X430162Y1088647D03*
X426461D03*
Y1082269D03*
X433862Y1075891D03*
X435713Y1079080D03*
Y1085458D03*
X433862Y1088647D03*
X426461Y1095025D03*
X430162Y1101403D03*
X426461D03*
X435713Y1091836D03*
Y1098214D03*
Y1104592D03*
X433862Y1101403D03*
X430162Y1107781D03*
X426461D03*
Y1114159D03*
X433862Y1107781D03*
X435713Y1110970D03*
Y1117348D03*
X426461Y1126915D03*
X430162Y1120537D03*
X426461D03*
X430162Y1133293D03*
X426461D03*
X435713Y1123726D03*
X433862Y1120537D03*
X435713Y1130103D03*
X433862Y1133293D03*
X426461Y1139670D03*
Y1146048D03*
X428311Y1149237D03*
X435713Y1136481D03*
Y1142859D03*
Y1149237D03*
X432012D03*
X430162Y1158804D03*
X435713Y1155615D03*
Y1161993D03*
X454204Y1040820D03*
X446790Y1047190D03*
Y1053568D03*
Y1059946D03*
X454192Y1047190D03*
X448641Y1056757D03*
X454192Y1053568D03*
X448641Y1050379D03*
X446790Y1066324D03*
Y1072702D03*
X452341Y1063135D03*
X448641D03*
X446790Y1079080D03*
Y1085458D03*
X452341Y1075891D03*
X448641D03*
X452341Y1088647D03*
X448641D03*
X446790Y1091836D03*
Y1098214D03*
Y1104592D03*
X452341Y1101403D03*
X448641D03*
X446790Y1110970D03*
Y1117348D03*
X452341Y1107781D03*
X448641D03*
X446790Y1123726D03*
Y1130103D03*
X448641Y1120537D03*
X452341D03*
Y1133293D03*
X448641D03*
X446790Y1136481D03*
Y1142859D03*
Y1149237D03*
X454192D03*
X450491D03*
X446790Y1155615D03*
Y1161993D03*
X454192Y1155615D03*
X447120Y1507512D03*
X452427Y1507295D03*
X450703Y1521453D03*
X451033Y1514243D03*
X449861Y1519195D03*
X451254Y1528853D03*
X450752Y1536063D03*
X441752Y1523810D03*
Y1528725D03*
X452427Y1542641D03*
X447224Y1542425D03*
X450139Y1592380D03*
Y1624292D03*
X469007Y1040820D03*
X461606D03*
X461593Y1047190D03*
Y1053568D03*
X456042Y1056757D03*
X457893Y1059946D03*
X456042Y1050379D03*
X468995Y1047190D03*
Y1053568D03*
Y1059946D03*
X463444Y1056757D03*
Y1050379D03*
X456042Y1063135D03*
Y1069513D03*
X457893Y1072702D03*
Y1066324D03*
X461593D03*
X467145Y1063135D03*
X468995Y1072702D03*
Y1066324D03*
X467145Y1069513D03*
X465294Y1066324D03*
X456042Y1075891D03*
X461593Y1079080D03*
X457893D03*
X456042Y1088647D03*
X457893Y1085458D03*
X456042Y1082269D03*
X467145Y1075891D03*
X468995Y1079080D03*
X465294D03*
X468995Y1085458D03*
X467145Y1088647D03*
Y1082269D03*
X457893Y1091836D03*
X461593D03*
X456042Y1095025D03*
X457893Y1098214D03*
X456042Y1101403D03*
X457893Y1104592D03*
X461593D03*
X467145Y1095025D03*
X468995Y1091836D03*
X465294D03*
X468995Y1104592D03*
X465294D03*
X468995Y1098214D03*
X467145Y1101403D03*
X456042Y1107781D03*
X457893Y1110970D03*
X461593D03*
X457893Y1117348D03*
X456042Y1114159D03*
X468995Y1110970D03*
X465294D03*
X467145Y1107781D03*
Y1114159D03*
X468995Y1117348D03*
X456042Y1126915D03*
X461593Y1123726D03*
X457893D03*
X456042Y1120537D03*
Y1133293D03*
X468995Y1123726D03*
X467145Y1120537D03*
X465294Y1123726D03*
X467145Y1126915D03*
X468995Y1130103D03*
X467145Y1133293D03*
X457893Y1130104D03*
X456042Y1139670D03*
X461593Y1136481D03*
X457893D03*
Y1142859D03*
X456042Y1146048D03*
X461593Y1149237D03*
X468995Y1142859D03*
X467145Y1139670D03*
X468995Y1136481D03*
X465294D03*
X467145Y1146048D03*
X465294Y1149237D03*
X459743Y1158804D03*
Y1152426D03*
X465294Y1155615D03*
X457152Y1507295D03*
X461876D03*
X466600D03*
X469600Y1521453D03*
X464876D03*
X460152D03*
X455427D03*
X455757Y1514243D03*
X460482D03*
X465206D03*
X469931D03*
X470151Y1528853D03*
X465427D03*
X460703D03*
X455978D03*
X464926Y1536063D03*
X460202D03*
X455477D03*
X466600Y1542641D03*
X457152D03*
X461876D03*
X469999Y1592380D03*
X457939D03*
X462199D03*
X463959Y1602380D03*
X456179D03*
X468239D03*
X457939Y1624292D03*
X463959Y1614292D03*
X456179D03*
X468239D03*
X469999Y1624292D03*
X462199D03*
X480097Y1028056D03*
X478247Y1037623D03*
Y1044001D03*
X480097Y1034434D03*
X483798Y1040812D03*
X481948Y1031245D03*
X476400Y1040820D03*
X476397Y1047190D03*
Y1053568D03*
X470845Y1056757D03*
X478247D03*
X470845Y1050379D03*
X478247D03*
X483798Y1047190D03*
Y1053568D03*
X480097Y1059946D03*
X478247Y1063135D03*
X472696Y1066324D03*
X476397D03*
X478247Y1069513D03*
X483798Y1066324D03*
X480097Y1072702D03*
Y1066324D03*
X478247Y1075891D03*
X476397Y1079080D03*
X472696D03*
X478247Y1088647D03*
Y1082269D03*
X483798Y1079080D03*
X480097D03*
Y1085458D03*
Y1104592D03*
X483798D03*
X480097Y1098214D03*
X478247Y1095025D03*
X472696Y1091836D03*
X476397D03*
X480097D03*
X483798D03*
X472696Y1110970D03*
X476397D03*
X478247Y1107781D03*
Y1114159D03*
X483798Y1110970D03*
X480097D03*
Y1117348D03*
X476397Y1123726D03*
X472696D03*
X478247Y1120537D03*
Y1126915D03*
Y1133293D03*
X483798Y1123726D03*
X480097D03*
Y1130103D03*
X478247Y1139670D03*
X476397Y1136481D03*
X472696D03*
X476397Y1149237D03*
X472696D03*
X478247Y1146048D03*
X483798Y1136481D03*
X480097D03*
Y1142859D03*
X483798Y1149237D03*
X476397Y1155615D03*
X474546Y1152426D03*
X470845Y1158804D03*
X481948D03*
X471325Y1507295D03*
X476049D03*
X480774D03*
X483774Y1521453D03*
X479049D03*
X474325D03*
X474655Y1514243D03*
X479379D03*
X484104D03*
X484325Y1528853D03*
X479600D03*
X474876D03*
X479099Y1536063D03*
X476049Y1542641D03*
X471325D03*
X480774D03*
X482059Y1592380D03*
X474259D03*
X476019Y1602380D03*
X480299D03*
X482059Y1624292D03*
X476019Y1614292D03*
X474259Y1624292D03*
X480299Y1614292D03*
X494901Y1028056D03*
X487499D03*
X485649Y1044001D03*
X494901Y1034434D03*
X491200Y1040812D03*
X487499Y1034434D03*
X489349Y1031245D03*
X493050Y1037623D03*
X485649D03*
X493050Y1044001D03*
X496751Y1031245D03*
X498601Y1040812D03*
X491200Y1047190D03*
X493050Y1056757D03*
X491200Y1059946D03*
Y1053568D03*
X485649Y1056757D03*
X493050Y1050379D03*
X485649D03*
X498601Y1047190D03*
Y1053568D03*
X489349Y1063135D03*
X494901Y1066324D03*
X491200D03*
X487499D03*
X491200Y1072702D03*
X489349Y1069513D03*
X498601Y1066324D03*
X489349Y1082269D03*
X498601Y1079080D03*
X494901D03*
X489349Y1075891D03*
X487499Y1079080D03*
X491200D03*
Y1085458D03*
X489349Y1088647D03*
X494901Y1091836D03*
X487499D03*
X491200D03*
X489349Y1095025D03*
X494901Y1104592D03*
X491200Y1098214D03*
Y1104592D03*
X487499D03*
X498601Y1091836D03*
Y1104592D03*
X496751Y1101403D03*
X491200Y1110970D03*
X489349Y1114159D03*
X491200Y1117348D03*
X498601Y1110970D03*
X494901D03*
X489349Y1107781D03*
X487499Y1110970D03*
X494901Y1123726D03*
X489349Y1126915D03*
X491200Y1123726D03*
X487499D03*
X489349Y1120537D03*
X491200Y1130103D03*
X489349Y1133293D03*
X498601Y1123726D03*
X494901Y1136481D03*
X489349Y1139670D03*
X491200Y1136481D03*
X487499D03*
X491200Y1142859D03*
X494901Y1149237D03*
X489349Y1146048D03*
X487499Y1149237D03*
X498601Y1136481D03*
Y1149237D03*
X487499Y1155615D03*
X485649Y1152426D03*
X493050Y1158804D03*
X498601Y1155615D03*
X496751Y1152426D03*
X485498Y1507295D03*
X490222D03*
X499671D03*
X494947D03*
X497947Y1521453D03*
X493222D03*
X488498D03*
X488828Y1514243D03*
X493553D03*
X498277D03*
X498498Y1528853D03*
X493773D03*
X489049D03*
X488548Y1536063D03*
X494947Y1542641D03*
X485498D03*
X490222D03*
X499671D03*
X498379Y1592380D03*
X486319D03*
X494119D03*
X488079Y1602380D03*
X492359D03*
X498379Y1624292D03*
X488079Y1614292D03*
X486319Y1624292D03*
X494119D03*
X492359Y1614292D03*
X497440Y1684454D03*
Y1679920D03*
Y1675383D03*
Y1698627D03*
Y1694093D03*
Y1689556D03*
Y1712800D03*
Y1708266D03*
Y1703729D03*
Y1726974D03*
Y1722440D03*
Y1717903D03*
X502302Y1028056D03*
X513405D03*
X507853Y1037623D03*
X500452D03*
X502302Y1034434D03*
X507853Y1044001D03*
X500452D03*
X507853Y1031245D03*
X513405Y1034434D03*
Y1040812D03*
X507853Y1056757D03*
Y1050379D03*
X500452Y1056757D03*
X504153D03*
X500452Y1050379D03*
X502302Y1059946D03*
X506003D03*
X513405Y1053568D03*
Y1059946D03*
X507853Y1063135D03*
X500452D03*
X507853Y1069513D03*
X500452D03*
X502302Y1072702D03*
X513405D03*
X507853Y1075891D03*
X500452D03*
X507853Y1088647D03*
X500452D03*
X502302Y1085458D03*
X507853Y1082269D03*
X500452D03*
X513405Y1079080D03*
X507853Y1095025D03*
X500452D03*
X502302Y1098214D03*
X507853Y1101403D03*
X502302Y1104592D03*
X513405Y1091836D03*
Y1098214D03*
X507853Y1107781D03*
X500452D03*
X507853Y1114159D03*
X502302Y1117348D03*
X500452Y1114159D03*
X513405Y1110970D03*
Y1117348D03*
X507853Y1120537D03*
X500452D03*
X507853Y1126915D03*
X500452D03*
X507853Y1133293D03*
X500452D03*
X502302Y1130103D03*
X513405Y1130104D03*
X507853Y1139670D03*
X500452D03*
X502302Y1142859D03*
X507853Y1146048D03*
X500452D03*
X513405Y1136481D03*
Y1149237D03*
X511554Y1165182D03*
X509704Y1155615D03*
X507853Y1152426D03*
X502302Y1155615D03*
X507853Y1158804D03*
X504153D03*
X513405Y1155615D03*
X504396Y1507295D03*
X509120D03*
X513844D03*
X512120Y1521453D03*
X507396D03*
X502671D03*
X503001Y1514243D03*
X507726D03*
X512450D03*
X512671Y1528853D03*
X507947D03*
X503222D03*
X512170Y1536063D03*
X502721D03*
X513844Y1542641D03*
X504396D03*
X509120D03*
X510439Y1592380D03*
X506179D03*
X512199Y1602380D03*
X500139D03*
X504419D03*
X512199Y1614292D03*
X500139D03*
X506179Y1624292D03*
X510439D03*
X504419Y1614292D03*
X505314Y1679320D03*
Y1683857D03*
X513188Y1684454D03*
Y1679920D03*
Y1675383D03*
X505314Y1688391D03*
Y1693493D03*
Y1698030D03*
X513188Y1698627D03*
Y1694093D03*
Y1689556D03*
X505314Y1707666D03*
Y1712203D03*
X513188Y1712800D03*
Y1708266D03*
Y1703729D03*
X505314Y1716737D03*
Y1702564D03*
Y1721840D03*
Y1726377D03*
Y1730911D03*
X513188Y1726974D03*
Y1722440D03*
Y1717903D03*
X520806Y1028056D03*
X528208D03*
X526357Y1037623D03*
Y1044001D03*
Y1031245D03*
X515255D03*
X520806Y1040812D03*
Y1034434D03*
X515255Y1044001D03*
X528208Y1040812D03*
Y1034434D03*
X520806Y1047190D03*
X526357Y1050379D03*
Y1056757D03*
X520806Y1053568D03*
X515255Y1050379D03*
X518956Y1056757D03*
X520806Y1059946D03*
X517105D03*
X528208Y1047190D03*
Y1053568D03*
Y1059946D03*
X526357Y1063135D03*
X515255D03*
X526357Y1069513D03*
X520806Y1066324D03*
Y1072702D03*
X515255Y1069513D03*
X528208Y1066324D03*
Y1072702D03*
X526357Y1075891D03*
X520806Y1079080D03*
X526357Y1088647D03*
Y1082269D03*
X520806Y1085458D03*
X515255Y1088647D03*
Y1082269D03*
X528208Y1079080D03*
Y1085458D03*
X526357Y1095025D03*
X520806Y1091836D03*
X526357Y1101403D03*
X520806Y1104592D03*
Y1098214D03*
X515255Y1101403D03*
X528208Y1091836D03*
Y1104592D03*
Y1098214D03*
X526357Y1107781D03*
X520806Y1110970D03*
X515255Y1107781D03*
X526357Y1114159D03*
X520806Y1117348D03*
X528208Y1110970D03*
Y1117348D03*
Y1130104D03*
X526357Y1120537D03*
Y1126915D03*
X520806Y1123726D03*
X515255Y1120537D03*
Y1126915D03*
X526357Y1133293D03*
X520806Y1130103D03*
X528208Y1123726D03*
X515255Y1139670D03*
X520806Y1142859D03*
X526357Y1139670D03*
X520806Y1136481D03*
X526357Y1146048D03*
X520806Y1149237D03*
X515255Y1146048D03*
X528208Y1136481D03*
Y1142859D03*
Y1149237D03*
X526357Y1152426D03*
Y1158804D03*
X520806Y1155615D03*
X517105D03*
X522657Y1158804D03*
X515255D03*
X517105Y1161993D03*
X528208Y1155615D03*
X518569Y1507295D03*
X523293D03*
X526314Y1521453D03*
X521569D03*
X516845D03*
X521899Y1514243D03*
X522120Y1528853D03*
X517396D03*
X521619Y1536063D03*
X526950D03*
X523293Y1542641D03*
X518569D03*
X518239Y1592380D03*
X522499D03*
X524259Y1602380D03*
X528539D03*
X516479D03*
X524259Y1614292D03*
X518239Y1624292D03*
X522499D03*
X528539Y1614292D03*
X516479D03*
X521062Y1679320D03*
Y1683857D03*
X528936Y1684454D03*
Y1679920D03*
Y1675383D03*
X521062Y1688391D03*
Y1693493D03*
Y1698030D03*
X528936Y1698627D03*
Y1694093D03*
Y1689556D03*
X521062Y1716737D03*
Y1702564D03*
Y1707666D03*
Y1712203D03*
X528936Y1712800D03*
Y1708266D03*
Y1703729D03*
X521062Y1721840D03*
Y1726377D03*
Y1730911D03*
X528936Y1726974D03*
Y1722440D03*
Y1717903D03*
X539310Y1028056D03*
X541160Y1031245D03*
X533759D03*
X539310Y1034434D03*
Y1040812D03*
X533759Y1037623D03*
X541160Y1044001D03*
X533759D03*
X543011Y1059946D03*
X530058Y1056757D03*
X541160Y1050379D03*
X539310Y1053568D03*
X533759Y1050379D03*
Y1056757D03*
X539310Y1059946D03*
X531908D03*
X541160Y1063135D03*
X533759D03*
X541160Y1069513D03*
X539310Y1072702D03*
X533759Y1069513D03*
Y1075891D03*
X539310Y1079080D03*
X541160Y1088647D03*
X533759D03*
X541160Y1082269D03*
X533759D03*
X539310Y1091836D03*
X533759Y1095025D03*
X539310Y1098214D03*
X541160Y1101403D03*
X533759D03*
X541160Y1107781D03*
X533759D03*
X539310Y1110970D03*
Y1117348D03*
X533759Y1114159D03*
X541160Y1120537D03*
X533759D03*
X541160Y1126915D03*
X533759D03*
X539310Y1130103D03*
X533759Y1133293D03*
X541160Y1139670D03*
X539310Y1136481D03*
X533759Y1139670D03*
Y1146048D03*
X541160D03*
X539310Y1149237D03*
X543011Y1155615D03*
X533759Y1158804D03*
X530058D03*
X539310Y1155615D03*
X535609D03*
X533759Y1152426D03*
X543011Y1161993D03*
X542359Y1592380D03*
X530299D03*
X534559D03*
X536319Y1602380D03*
X540599D03*
X542359Y1624292D03*
X536319Y1614292D03*
X530299Y1624292D03*
X534559D03*
X540599Y1614292D03*
X536810Y1679320D03*
Y1683857D03*
X544684Y1684454D03*
Y1679920D03*
Y1675383D03*
X536810Y1688391D03*
Y1693493D03*
Y1698030D03*
X544684Y1698627D03*
Y1694093D03*
Y1689556D03*
X536810Y1716737D03*
Y1702564D03*
Y1707666D03*
Y1712203D03*
X544684Y1712800D03*
Y1708266D03*
Y1703729D03*
X536810Y1721840D03*
Y1726377D03*
Y1730911D03*
X544684Y1726974D03*
Y1722440D03*
Y1717903D03*
X554113Y1028056D03*
X546712D03*
Y1040812D03*
Y1034434D03*
X552263Y1031245D03*
X554113Y1040812D03*
X552263Y1037623D03*
X554113Y1034434D03*
X552263Y1044001D03*
X559664Y1031245D03*
Y1037623D03*
Y1044001D03*
X546712Y1047190D03*
X554113D03*
X544861Y1056757D03*
X546712Y1053568D03*
Y1059946D03*
X552263Y1056757D03*
X555964D03*
X554113Y1053568D03*
X552263Y1050379D03*
X554113Y1059946D03*
X557814D03*
X559664Y1050379D03*
Y1056757D03*
X552263Y1063135D03*
X546712Y1072702D03*
Y1066324D03*
X552263Y1069513D03*
X554113Y1066324D03*
Y1072702D03*
X559664Y1063135D03*
Y1069513D03*
X552263Y1075891D03*
X546712Y1079080D03*
X554113D03*
X546712Y1085458D03*
X552263Y1088647D03*
X554113Y1085458D03*
X552263Y1082269D03*
X559664Y1075891D03*
Y1088647D03*
Y1082269D03*
X546712Y1091836D03*
X554113D03*
X552263Y1095025D03*
Y1101403D03*
X554113Y1098214D03*
X546712Y1104592D03*
Y1098214D03*
X554113Y1104592D03*
X559664Y1095025D03*
Y1101403D03*
X552263Y1107781D03*
X554113Y1110970D03*
X546712D03*
X554113Y1117348D03*
X552263Y1114159D03*
X546712Y1117348D03*
X559664Y1107781D03*
Y1114159D03*
X546712Y1123726D03*
X554113D03*
X552263Y1120537D03*
Y1126915D03*
Y1133293D03*
X554113Y1130103D03*
X559664Y1120537D03*
Y1126915D03*
Y1133293D03*
X546712Y1130104D03*
X552263Y1139670D03*
X554113Y1136481D03*
X546712D03*
X554113Y1142859D03*
X546712D03*
Y1149237D03*
X552263Y1146048D03*
X554113Y1149237D03*
X559664Y1139670D03*
Y1146048D03*
X555964Y1165182D03*
X554113Y1155615D03*
X552263Y1152426D03*
X555964Y1158804D03*
X552263D03*
X548562D03*
X546712Y1155615D03*
X554113Y1161993D03*
X559664Y1152426D03*
Y1158804D03*
X558679Y1592380D03*
X546619D03*
X554419D03*
X548379Y1602380D03*
X552659D03*
X558679Y1624292D03*
X548379Y1614292D03*
X546619Y1624292D03*
X554419D03*
X552659Y1614292D03*
X552558Y1679320D03*
Y1683857D03*
Y1688391D03*
Y1693493D03*
Y1698030D03*
Y1716737D03*
Y1702564D03*
Y1707666D03*
Y1712203D03*
Y1721840D03*
Y1726377D03*
Y1730911D03*
X565216Y1028056D03*
X572617D03*
X567066Y1031245D03*
X565215Y1034434D03*
Y1040812D03*
X572617Y1034434D03*
Y1040812D03*
X567066Y1044001D03*
X565215Y1059946D03*
X572617Y1047190D03*
X567066Y1050379D03*
X572617Y1053568D03*
X570767Y1056757D03*
X565215Y1053568D03*
X572617Y1059946D03*
X568916D03*
X567066Y1063135D03*
X572617Y1066324D03*
Y1072702D03*
X567066Y1069513D03*
X565215Y1072702D03*
Y1079080D03*
X572617D03*
X567066Y1088647D03*
X572617Y1085458D03*
X567066Y1082269D03*
X572617Y1091836D03*
X565215D03*
X572617Y1104592D03*
Y1098214D03*
X567066Y1101403D03*
X565215Y1098214D03*
X567066Y1107781D03*
X572617Y1110970D03*
X565215D03*
X572617Y1117348D03*
X565215D03*
X572617Y1123726D03*
X567066Y1120537D03*
Y1126915D03*
X572617Y1130103D03*
X565215D03*
X572617Y1136481D03*
X565215Y1149237D03*
X572617D03*
X567066Y1146048D03*
X572617Y1142859D03*
X567066Y1139670D03*
X565215Y1136481D03*
X574467Y1158804D03*
X565215Y1155615D03*
X568916D03*
X572617D03*
X561515D03*
X565215Y1161993D03*
X569814Y1523810D03*
Y1528725D03*
X570739Y1592380D03*
X566479D03*
X572499Y1602380D03*
X560439D03*
X564719D03*
X572499Y1614292D03*
X570739Y1624292D03*
X560439Y1614292D03*
X566479Y1624292D03*
X564719Y1614292D03*
X572243Y1683857D03*
X564369Y1684454D03*
Y1679920D03*
Y1675383D03*
X572243Y1679320D03*
X564369Y1694093D03*
Y1689556D03*
X572243Y1688391D03*
Y1693493D03*
Y1698030D03*
X564369Y1698627D03*
X572243Y1702564D03*
Y1707666D03*
Y1712203D03*
X564369Y1712800D03*
Y1708266D03*
Y1703729D03*
X572243Y1716737D03*
Y1726377D03*
Y1730911D03*
X564369Y1726974D03*
Y1722440D03*
Y1717903D03*
X572243Y1721840D03*
X577728Y906182D03*
Y912560D03*
Y918938D03*
Y925316D03*
Y931694D03*
Y938072D03*
Y944450D03*
Y950828D03*
Y957206D03*
Y963584D03*
Y969962D03*
Y976340D03*
Y982718D03*
Y989096D03*
Y995474D03*
Y1008230D03*
Y1001852D03*
X578909Y1030198D03*
Y1036576D03*
Y1042954D03*
Y1049332D03*
Y1055710D03*
Y1062088D03*
Y1074844D03*
Y1068466D03*
Y1087600D03*
Y1081222D03*
Y1093978D03*
Y1100356D03*
Y1106734D03*
Y1113112D03*
Y1119490D03*
Y1125868D03*
Y1132246D03*
Y1138623D03*
Y1145001D03*
Y1151379D03*
X578168Y1158804D03*
X575182Y1507514D03*
X580489Y1507295D03*
X585214D03*
X588214Y1521453D03*
X583489D03*
X578765D03*
X579095Y1514243D03*
X583819D03*
X588544D03*
X577923Y1519195D03*
X588765Y1528853D03*
X584040D03*
X579316D03*
X588264Y1536063D03*
X583539D03*
X578814D03*
X585214Y1542641D03*
X580489D03*
X575286Y1542425D03*
X578539Y1592380D03*
X582799D03*
X584559Y1602380D03*
X588839D03*
X576779D03*
X584559Y1614292D03*
X582799Y1624292D03*
X578539D03*
X588839Y1614292D03*
X576779D03*
X587991Y1679320D03*
Y1683857D03*
X580117Y1684454D03*
Y1679920D03*
Y1675383D03*
X587991Y1688391D03*
Y1693493D03*
Y1698030D03*
X580117Y1698627D03*
Y1694093D03*
Y1689556D03*
X587991Y1716737D03*
Y1702564D03*
Y1707666D03*
Y1712203D03*
X580117Y1712800D03*
Y1708266D03*
Y1703729D03*
X587991Y1721840D03*
Y1726377D03*
Y1730911D03*
X580117Y1726974D03*
Y1722440D03*
Y1717903D03*
X589938Y1507295D03*
X594662D03*
X599387D03*
X604111D03*
X602387Y1521453D03*
X597662D03*
X592938D03*
X593268Y1514243D03*
X597993D03*
X602717D03*
X602938Y1528853D03*
X598213D03*
X593489D03*
X592988Y1536063D03*
X589938Y1542641D03*
X604111D03*
X599387D03*
X594662D03*
X602659Y1592380D03*
X590599D03*
X594859D03*
X596619Y1602380D03*
X600899D03*
X602659Y1624292D03*
X596619Y1614292D03*
X594859Y1624292D03*
X590599D03*
X600899Y1614292D03*
X603739Y1679320D03*
Y1683857D03*
X595865Y1684454D03*
Y1679920D03*
Y1675383D03*
X603739Y1688391D03*
Y1693493D03*
Y1698030D03*
X595865Y1698627D03*
Y1694093D03*
Y1689556D03*
X603739Y1716737D03*
Y1702564D03*
Y1707666D03*
Y1712203D03*
X595865Y1712800D03*
Y1708266D03*
Y1703729D03*
X603739Y1721840D03*
Y1726377D03*
Y1730911D03*
X595865Y1726974D03*
Y1722440D03*
Y1717903D03*
X608836Y1507295D03*
X613560D03*
X618284D03*
X616560Y1521453D03*
X611836D03*
X607111D03*
X607441Y1514243D03*
X612166D03*
X616890D03*
X617111Y1528853D03*
X612387D03*
X607662D03*
X607161Y1536063D03*
X616610D03*
X613560Y1542641D03*
X618284D03*
X608836D03*
X618979Y1592380D03*
X614719D03*
X606919D03*
X608679Y1602380D03*
X612959D03*
X618979Y1624292D03*
X608679Y1614292D03*
X606919Y1624292D03*
X614719D03*
X612959Y1614292D03*
X611613Y1684454D03*
Y1679920D03*
Y1675383D03*
Y1698627D03*
Y1694093D03*
Y1689556D03*
Y1712800D03*
Y1708266D03*
Y1703729D03*
Y1726974D03*
Y1722440D03*
Y1717903D03*
X623009Y1507295D03*
X627733D03*
X632458D03*
X630733Y1521453D03*
X626009D03*
X621284D03*
X621615Y1514243D03*
X626339D03*
X631063D03*
X631284Y1528853D03*
X626560D03*
X621835D03*
X630783Y1536063D03*
X632458Y1542641D03*
X627733D03*
X623009D03*
X631039Y1592380D03*
X626779D03*
X632799Y1602286D03*
X620739Y1602380D03*
X625019D03*
X631039Y1624292D03*
X632799Y1614292D03*
X626779Y1624292D03*
X620739Y1614292D03*
X625019D03*
X619487Y1679320D03*
Y1683857D03*
Y1688391D03*
Y1693493D03*
Y1698030D03*
Y1716737D03*
Y1702564D03*
Y1707666D03*
Y1712203D03*
Y1721840D03*
Y1726377D03*
Y1730911D03*
X637182Y1507295D03*
X641906D03*
X646631D03*
X644907Y1521453D03*
X640182D03*
X635458D03*
X635788Y1514243D03*
X640512D03*
X645458Y1528853D03*
X640733D03*
X636009D03*
X640232Y1536063D03*
X646631Y1542641D03*
X641906D03*
X637182D03*
X638839Y1592380D03*
X644869Y1602380D03*
X637079D03*
X644869Y1614292D03*
X638839Y1624292D03*
X637079Y1614292D03*
X651355Y1507295D03*
X654376Y1521453D03*
X649631D03*
X649961Y1514243D03*
X650182Y1528853D03*
X649681Y1536063D03*
X655012D03*
X651355Y1542641D03*
X1185452Y1556810D03*
Y1561725D03*
X1190820Y1540512D03*
X1194733Y1547243D03*
X1196127Y1540295D03*
X1199457Y1547243D03*
X1193561Y1552195D03*
X1199127Y1554453D03*
X1194403D03*
X1199678Y1561853D03*
X1194954D03*
X1199177Y1569063D03*
X1196127Y1575641D03*
X1194452Y1569063D03*
X1190924Y1575425D03*
X1193839Y1625380D03*
X1199879Y1635380D03*
Y1647292D03*
X1193839Y1657292D03*
X1200852Y1540295D03*
X1204182Y1547243D03*
X1205576Y1540295D03*
X1208906Y1547243D03*
X1210300Y1540295D03*
X1213631Y1547243D03*
X1215025Y1540295D03*
X1213300Y1554453D03*
X1208576D03*
X1203852D03*
X1213851Y1561853D03*
X1209127D03*
X1204403D03*
X1210300Y1575641D03*
X1208626Y1569063D03*
X1203902D03*
X1200852Y1575641D03*
X1205576D03*
X1215025D03*
X1205899Y1625380D03*
X1201639D03*
X1213699D03*
X1207659Y1635380D03*
X1211939D03*
X1207659Y1647292D03*
X1211939D03*
X1201639Y1657292D03*
X1205899D03*
X1213699D03*
X1218355Y1547243D03*
X1219749Y1540295D03*
X1223079Y1547243D03*
X1227804D03*
X1229198Y1540295D03*
X1224474D03*
X1227474Y1554453D03*
X1222749D03*
X1218025D03*
X1228025Y1561853D03*
X1223300D03*
X1218576D03*
X1222799Y1569063D03*
X1219749Y1575641D03*
X1224474D03*
X1229198D03*
X1217959Y1625380D03*
X1225759D03*
X1230019D03*
X1223999Y1635380D03*
X1219719D03*
X1223999Y1647292D03*
X1219719D03*
X1217959Y1657292D03*
X1230019D03*
X1225759D03*
X1232528Y1547243D03*
X1233922Y1540295D03*
X1237253Y1547243D03*
X1241977D03*
X1243371Y1540295D03*
X1238647D03*
X1241647Y1554453D03*
X1236922D03*
X1232198D03*
X1242198Y1561853D03*
X1237473D03*
X1232749D03*
X1238647Y1575641D03*
X1232248Y1569063D03*
X1233922Y1575641D03*
X1243371D03*
X1237819Y1625380D03*
X1242079D03*
X1231779Y1635380D03*
X1236059D03*
X1243839D03*
X1236059Y1647292D03*
X1231779D03*
X1243839D03*
X1237819Y1657292D03*
X1242079D03*
X1241140Y1684454D03*
Y1679920D03*
Y1675383D03*
Y1698627D03*
Y1694093D03*
Y1689556D03*
Y1712800D03*
Y1708266D03*
Y1703729D03*
Y1726974D03*
Y1722440D03*
Y1717903D03*
X1246701Y1547243D03*
X1248096Y1540295D03*
X1251426Y1547243D03*
X1252820Y1540295D03*
X1256150Y1547243D03*
X1257544Y1540295D03*
X1255820Y1554453D03*
X1251096D03*
X1246371D03*
X1256371Y1561853D03*
X1251647D03*
X1246922D03*
X1257544Y1575641D03*
X1255870Y1569063D03*
X1246421D03*
X1248096Y1575641D03*
X1252820D03*
X1249879Y1625380D03*
X1254139D03*
X1248119Y1635380D03*
X1255899D03*
X1260179D03*
X1248119Y1647292D03*
X1255899D03*
X1260179D03*
X1254139Y1657292D03*
X1249879D03*
X1249014Y1679320D03*
Y1683857D03*
X1256888Y1684454D03*
Y1679920D03*
Y1675383D03*
X1249014Y1688391D03*
Y1693493D03*
Y1698030D03*
X1256888Y1698627D03*
Y1694093D03*
Y1689556D03*
Y1703729D03*
X1249014Y1716737D03*
Y1702564D03*
Y1707666D03*
Y1712203D03*
X1256888Y1712800D03*
Y1708266D03*
X1249014Y1721840D03*
Y1726377D03*
Y1730911D03*
X1256888Y1726974D03*
Y1722440D03*
Y1717903D03*
X1262269Y1540295D03*
X1265599Y1547243D03*
X1266993Y1540295D03*
X1270014Y1554453D03*
X1265269D03*
X1260545D03*
X1265820Y1561853D03*
X1261096D03*
X1270650Y1569063D03*
X1266993Y1575641D03*
X1265319Y1569063D03*
X1262269Y1575641D03*
X1266199Y1625380D03*
X1261939D03*
X1273999D03*
X1267959Y1635380D03*
X1272239D03*
X1267959Y1647292D03*
X1272239D03*
X1266199Y1657292D03*
X1261939D03*
X1273999D03*
X1264762Y1679320D03*
Y1683857D03*
X1272636Y1684454D03*
Y1679920D03*
Y1675383D03*
X1264762Y1688391D03*
Y1693493D03*
Y1698030D03*
X1272636Y1698627D03*
Y1694093D03*
Y1689556D03*
X1264762Y1716737D03*
Y1702564D03*
Y1707666D03*
Y1712203D03*
X1272636Y1712800D03*
Y1708266D03*
Y1703729D03*
X1264762Y1721840D03*
Y1726377D03*
Y1730911D03*
X1272636Y1726974D03*
Y1722440D03*
Y1717903D03*
X1286028Y1028055D03*
Y1034433D03*
Y1040811D03*
Y1047189D03*
Y1053567D03*
X1287878Y1056756D03*
X1289729Y1059945D03*
X1286028D03*
Y1066323D03*
Y1072701D03*
Y1079079D03*
Y1085457D03*
Y1091835D03*
Y1098213D03*
Y1104591D03*
Y1110969D03*
Y1117347D03*
Y1123725D03*
Y1130102D03*
Y1136480D03*
Y1142858D03*
Y1149236D03*
X1289729Y1155614D03*
X1286028D03*
X1284178Y1158803D03*
X1287878Y1165181D03*
X1278259Y1625380D03*
X1286059D03*
X1280019Y1635380D03*
X1284299D03*
X1280019Y1647292D03*
X1284299D03*
X1278259Y1657292D03*
X1286059D03*
X1280510Y1679320D03*
Y1683857D03*
X1288384Y1684454D03*
Y1679920D03*
Y1675383D03*
X1280510Y1688391D03*
Y1693493D03*
Y1698030D03*
X1288384Y1698627D03*
Y1694093D03*
Y1689556D03*
X1280510Y1716737D03*
Y1702564D03*
Y1707666D03*
Y1712203D03*
X1288384Y1712800D03*
Y1708266D03*
Y1703729D03*
X1280510Y1721840D03*
Y1726377D03*
Y1730911D03*
X1288384Y1726974D03*
Y1722440D03*
Y1717903D03*
X1304532Y1028055D03*
X1293430Y1034433D03*
Y1040811D03*
X1298981Y1044000D03*
Y1037622D03*
X1304532Y1034433D03*
Y1040811D03*
X1298981Y1031244D03*
X1291579D03*
Y1044000D03*
X1304532Y1047189D03*
X1291579Y1050378D03*
X1293430Y1053567D03*
Y1059945D03*
X1304532Y1053567D03*
X1298981Y1050378D03*
X1302681Y1056756D03*
X1298981D03*
X1300831Y1059945D03*
X1304532D03*
X1298981Y1063134D03*
X1291579D03*
Y1069512D03*
X1293430Y1072701D03*
X1304532D03*
Y1066323D03*
X1298981Y1069512D03*
Y1075890D03*
X1293430Y1079079D03*
X1304532D03*
Y1085457D03*
X1298981Y1088646D03*
X1291579Y1082268D03*
X1298981D03*
X1291579Y1088646D03*
X1293430Y1091835D03*
X1304532D03*
X1298981Y1095024D03*
X1293430Y1098213D03*
X1298981Y1101402D03*
X1304532Y1098213D03*
Y1104591D03*
X1291579Y1101402D03*
X1298981Y1107780D03*
X1291579D03*
X1293430Y1110969D03*
X1304532D03*
X1293430Y1117347D03*
X1298981Y1114158D03*
X1304532Y1117347D03*
X1291579Y1120536D03*
X1298981D03*
X1304532Y1123725D03*
X1291579Y1126914D03*
X1298981D03*
X1304532Y1130102D03*
X1298981Y1133292D03*
X1293430Y1130102D03*
X1304532Y1136480D03*
X1298981Y1139669D03*
X1291579D03*
X1293430Y1136480D03*
X1304532Y1142858D03*
X1291579Y1146047D03*
X1293430Y1149236D03*
X1298981Y1146047D03*
X1304532Y1149236D03*
X1293430Y1155614D03*
X1304532D03*
X1298981Y1152425D03*
X1297130Y1155614D03*
X1302681Y1158803D03*
X1298981D03*
X1304532Y1161992D03*
X1297130D03*
X1298119Y1625380D03*
X1290319D03*
X1302379D03*
X1292079Y1635380D03*
X1296359D03*
X1304139D03*
X1296359Y1647292D03*
X1292079D03*
X1304139D03*
X1298119Y1657292D03*
X1290319D03*
X1302379D03*
X1296258Y1679320D03*
Y1683857D03*
Y1688391D03*
Y1693493D03*
Y1698030D03*
Y1716737D03*
Y1702564D03*
Y1707666D03*
Y1712203D03*
Y1721840D03*
Y1726377D03*
Y1730911D03*
X1311933Y1028055D03*
X1306382Y1044000D03*
Y1037622D03*
Y1031244D03*
X1319335Y1034433D03*
X1311933Y1040811D03*
X1319335D03*
X1317485Y1031244D03*
Y1044000D03*
X1311933Y1034433D03*
X1306382Y1050378D03*
Y1056756D03*
X1311933Y1047189D03*
X1313784Y1056756D03*
X1311933Y1059945D03*
X1315634D03*
X1319335D03*
X1317485Y1050378D03*
X1319335Y1053567D03*
X1311933D03*
X1306382Y1063134D03*
Y1069512D03*
X1317485Y1063134D03*
X1319335Y1072701D03*
X1317485Y1069512D03*
X1311933Y1066323D03*
Y1072701D03*
X1306382Y1075890D03*
Y1088646D03*
Y1082268D03*
X1319335Y1079079D03*
X1311933D03*
Y1085457D03*
X1317485Y1088646D03*
Y1082268D03*
X1306382Y1095024D03*
Y1101402D03*
X1319335Y1091835D03*
X1311933D03*
Y1098213D03*
X1319335D03*
X1317485Y1101402D03*
X1311933Y1104591D03*
X1306382Y1107780D03*
Y1114158D03*
X1317485Y1107780D03*
X1319335Y1110969D03*
X1311933D03*
Y1117347D03*
X1319335D03*
X1306382Y1120536D03*
Y1126914D03*
Y1133292D03*
X1317485Y1120536D03*
X1311933Y1123725D03*
X1317485Y1126914D03*
X1319335Y1130102D03*
X1311933Y1130103D03*
X1306382Y1139669D03*
Y1146047D03*
X1319335Y1136480D03*
X1317485Y1139669D03*
X1311933Y1136480D03*
Y1142858D03*
X1317485Y1146047D03*
X1319335Y1149236D03*
X1311933D03*
X1317485Y1158803D03*
X1313784D03*
X1319335Y1161992D03*
X1311933D03*
X1306382Y1165181D03*
X1313784D03*
X1306382Y1152425D03*
Y1158803D03*
X1319335Y1155614D03*
X1315634D03*
X1311933D03*
X1310083Y1158803D03*
X1318882Y1540514D03*
X1313514Y1556810D03*
Y1561725D03*
X1318986Y1575425D03*
X1310179Y1625380D03*
X1314439D03*
X1308419Y1635380D03*
X1316199D03*
X1308419Y1647292D03*
X1316199D03*
X1310179Y1657292D03*
X1314439D03*
X1315943Y1679320D03*
Y1683857D03*
X1308069Y1684454D03*
Y1679920D03*
Y1675383D03*
X1315943Y1688391D03*
Y1693493D03*
Y1698030D03*
X1308069Y1698627D03*
Y1694093D03*
Y1689556D03*
X1315943Y1716737D03*
Y1702564D03*
Y1707666D03*
Y1712203D03*
X1308069Y1712800D03*
Y1708266D03*
Y1703729D03*
X1315943Y1721840D03*
Y1726377D03*
Y1730911D03*
X1308069Y1726974D03*
Y1722440D03*
Y1717903D03*
X1330437Y1028055D03*
X1324886Y1031244D03*
X1332288D03*
X1324886Y1044000D03*
Y1037622D03*
X1332288Y1044000D03*
X1330437Y1034433D03*
X1332288Y1037622D03*
X1330437Y1040811D03*
Y1047189D03*
X1324886Y1050378D03*
Y1056756D03*
X1332288Y1050378D03*
X1330437Y1053567D03*
X1328587Y1056756D03*
X1332288D03*
X1326737Y1059945D03*
X1330437D03*
X1332288Y1063134D03*
X1324886D03*
Y1069512D03*
X1330437Y1066323D03*
X1332288Y1069512D03*
X1330437Y1072701D03*
X1324886Y1075890D03*
X1332288D03*
X1330437Y1079079D03*
X1324886Y1088646D03*
X1330437Y1085457D03*
X1332288Y1088646D03*
X1324886Y1082268D03*
X1332288D03*
X1330437Y1091835D03*
X1324886Y1095024D03*
X1332288D03*
X1324886Y1101402D03*
X1330437Y1098213D03*
X1332288Y1101402D03*
X1330437Y1104591D03*
X1324886Y1107780D03*
X1332288D03*
X1330437Y1110969D03*
X1324886Y1114158D03*
X1332288D03*
X1330437Y1117347D03*
X1324886Y1120536D03*
X1332288D03*
X1330437Y1123725D03*
X1324886Y1126914D03*
X1332288D03*
X1324886Y1133292D03*
X1332288D03*
X1330439Y1130102D03*
X1324886Y1139669D03*
X1330437Y1136480D03*
X1332288Y1139669D03*
X1330437Y1142858D03*
X1332288Y1146047D03*
X1330437Y1149236D03*
X1324886Y1146047D03*
X1332288Y1165181D03*
X1323036Y1155614D03*
Y1161992D03*
X1332288Y1152425D03*
X1330437Y1155614D03*
X1324886Y1152425D03*
X1332288Y1158803D03*
X1328587D03*
X1324886D03*
X1330437Y1161992D03*
X1324886Y1165181D03*
X1322795Y1547243D03*
X1324189Y1540295D03*
X1327519Y1547243D03*
X1328914Y1540295D03*
X1332244Y1547243D03*
X1333638Y1540295D03*
X1321623Y1552195D03*
X1331914Y1554453D03*
X1327189D03*
X1322465D03*
X1332465Y1561853D03*
X1327740D03*
X1323016D03*
X1333638Y1575641D03*
X1331964Y1569063D03*
X1328914Y1575641D03*
X1327239Y1569063D03*
X1324189Y1575641D03*
X1322514Y1569063D03*
X1326499Y1625380D03*
X1322239D03*
X1334299D03*
X1320479Y1635380D03*
X1328259D03*
X1332539D03*
X1328259Y1647292D03*
X1320479D03*
X1332539D03*
X1322239Y1657292D03*
X1326499D03*
X1334299D03*
X1331691Y1679320D03*
Y1683857D03*
X1323817Y1684454D03*
Y1679920D03*
Y1675383D03*
X1331691Y1688391D03*
Y1693493D03*
Y1698030D03*
X1323817Y1698627D03*
Y1694093D03*
Y1689556D03*
X1331691Y1716737D03*
Y1702564D03*
Y1707666D03*
Y1712203D03*
X1323817Y1712800D03*
Y1708266D03*
Y1703729D03*
X1331691Y1721840D03*
Y1726377D03*
Y1730911D03*
X1323817Y1726974D03*
Y1722440D03*
Y1717903D03*
X1337839Y1028055D03*
Y1040811D03*
Y1034433D03*
X1343390Y1031244D03*
Y1044000D03*
X1345241Y1040811D03*
Y1034433D03*
X1337839Y1047189D03*
Y1053567D03*
Y1059945D03*
X1339689Y1056756D03*
X1343390Y1050378D03*
X1345241Y1053567D03*
X1341540Y1059945D03*
X1345241D03*
X1337839Y1072701D03*
Y1066323D03*
X1343390Y1063134D03*
Y1069512D03*
X1345241Y1072701D03*
X1337839Y1079079D03*
Y1085457D03*
X1345241Y1079079D03*
X1343390Y1088646D03*
Y1082268D03*
X1337839Y1091835D03*
Y1098213D03*
Y1104591D03*
X1345241Y1091835D03*
X1343390Y1101402D03*
X1345241Y1098213D03*
X1337839Y1110969D03*
Y1117347D03*
X1343390Y1107780D03*
X1345241Y1110969D03*
Y1117347D03*
X1337839Y1123725D03*
Y1130102D03*
X1343390Y1120536D03*
Y1126914D03*
X1345241Y1130102D03*
X1337839Y1136480D03*
Y1142858D03*
Y1149236D03*
X1343390Y1139669D03*
X1345241Y1136480D03*
Y1149236D03*
X1343390Y1146047D03*
X1337839Y1155614D03*
X1335989Y1158803D03*
X1337839Y1161992D03*
X1341540Y1155614D03*
X1339689Y1158803D03*
X1348941Y1155614D03*
X1345241D03*
X1339689Y1165181D03*
X1336968Y1547243D03*
X1338362Y1540295D03*
X1341693Y1547243D03*
X1343087Y1540295D03*
X1346417Y1547243D03*
X1347811Y1540295D03*
X1346087Y1554453D03*
X1341362D03*
X1336638D03*
X1346638Y1561853D03*
X1341913D03*
X1337189D03*
X1347811Y1575641D03*
X1343087D03*
X1338362D03*
X1336688Y1569063D03*
X1338559Y1625380D03*
X1346359D03*
X1340319Y1635380D03*
X1344599D03*
X1340319Y1647292D03*
X1344599D03*
X1338559Y1657292D03*
X1346359D03*
X1347439Y1679320D03*
Y1683857D03*
X1339565Y1684454D03*
Y1679920D03*
Y1675383D03*
X1347439Y1688391D03*
Y1693493D03*
Y1698030D03*
X1339565Y1698627D03*
Y1694093D03*
Y1689556D03*
X1347439Y1716737D03*
Y1702564D03*
Y1707666D03*
Y1712203D03*
X1339565Y1712800D03*
Y1708266D03*
Y1703729D03*
X1347439Y1721840D03*
Y1726377D03*
Y1730911D03*
X1339565Y1726974D03*
Y1722440D03*
Y1717903D03*
X1356343Y1028055D03*
X1363745D03*
X1350792Y1031244D03*
Y1044000D03*
Y1037622D03*
X1356343Y1034433D03*
Y1040811D03*
X1363745Y1034433D03*
Y1040811D03*
X1361894Y1044000D03*
Y1037622D03*
Y1031244D03*
X1354493Y1056756D03*
X1350792D03*
Y1050378D03*
X1352642Y1059945D03*
X1356343Y1047189D03*
X1363745D03*
X1356343Y1053567D03*
X1361894Y1050378D03*
X1356343Y1059945D03*
X1363745Y1053567D03*
X1350792Y1063134D03*
Y1069512D03*
X1358193Y1063134D03*
X1356343Y1072701D03*
X1363745Y1066323D03*
X1358193Y1069512D03*
X1360044Y1066323D03*
X1350792Y1075890D03*
Y1082268D03*
Y1088646D03*
X1358193Y1075890D03*
X1363745Y1079079D03*
X1360044D03*
X1356343Y1085457D03*
X1358193Y1088646D03*
Y1082268D03*
X1350792Y1095024D03*
Y1101402D03*
X1356343Y1104591D03*
X1363745Y1091835D03*
X1360044D03*
X1358193Y1095024D03*
X1356343Y1098213D03*
X1363745Y1104591D03*
X1360044D03*
X1350792Y1107780D03*
Y1114158D03*
X1358193Y1107780D03*
X1360044Y1110969D03*
X1363745D03*
X1356343Y1117347D03*
X1358193Y1114158D03*
X1350792Y1120536D03*
Y1126914D03*
Y1133292D03*
X1358193Y1126914D03*
X1363745Y1123725D03*
X1360044D03*
X1358193Y1120536D03*
X1356343Y1130102D03*
X1358193Y1133292D03*
X1350792Y1139669D03*
Y1146047D03*
X1358193Y1139669D03*
X1363745Y1136480D03*
X1360044D03*
X1356343Y1142858D03*
X1363745Y1149236D03*
X1360044D03*
X1358193Y1146047D03*
X1354493Y1158803D03*
X1350792Y1152425D03*
Y1158803D03*
X1352642Y1161992D03*
X1356343Y1155614D03*
X1363745D03*
X1360044D03*
X1363745Y1161992D03*
X1351141Y1547243D03*
X1352536Y1540295D03*
X1355866Y1547243D03*
X1357260Y1540295D03*
X1360590Y1547243D03*
X1361984Y1540295D03*
X1360260Y1554453D03*
X1355536D03*
X1350811D03*
X1360811Y1561853D03*
X1356087D03*
X1351362D03*
X1361984Y1575641D03*
X1360310Y1569063D03*
X1352536Y1575641D03*
X1350861Y1569063D03*
X1357260Y1575641D03*
X1350619Y1625380D03*
X1358419D03*
X1362679D03*
X1352379Y1635380D03*
X1356659D03*
X1364439D03*
X1356659Y1647292D03*
X1352379D03*
X1364439D03*
X1358419Y1657292D03*
X1350619D03*
X1362679D03*
X1363187Y1679320D03*
Y1683857D03*
X1355313Y1684454D03*
Y1679920D03*
Y1675383D03*
Y1694093D03*
Y1689556D03*
X1363187Y1688391D03*
Y1693493D03*
Y1698030D03*
X1355313Y1698627D03*
X1363187Y1716737D03*
Y1702564D03*
Y1707666D03*
Y1712203D03*
X1355313Y1712800D03*
Y1708266D03*
Y1703729D03*
X1363187Y1726377D03*
Y1730911D03*
X1355313Y1726974D03*
Y1722440D03*
Y1717903D03*
X1363187Y1721840D03*
X1371146Y1028055D03*
X1374847D03*
X1369296Y1044000D03*
Y1037622D03*
Y1031244D03*
X1371146Y1034433D03*
X1376697Y1037622D03*
X1378548Y1040811D03*
X1371146D03*
X1374847Y1034433D03*
X1376697Y1031244D03*
Y1044000D03*
X1378548Y1053567D03*
X1376697Y1050378D03*
X1367445Y1059945D03*
X1369296Y1056756D03*
Y1050378D03*
X1371146Y1047189D03*
X1378548D03*
X1376697Y1056756D03*
X1371146Y1053567D03*
X1378548Y1059945D03*
X1369296Y1063134D03*
Y1069512D03*
X1367445Y1066323D03*
Y1072701D03*
X1371146Y1066323D03*
X1378548D03*
X1374847D03*
X1378548Y1072701D03*
X1369296Y1075890D03*
X1367445Y1079079D03*
X1369296Y1088646D03*
X1367445Y1085457D03*
X1369296Y1082268D03*
X1371146Y1079079D03*
X1378548D03*
X1374847D03*
X1378548Y1085457D03*
X1367445Y1091835D03*
X1369296Y1095024D03*
X1367445Y1104591D03*
Y1098213D03*
X1371146Y1091835D03*
X1378548D03*
X1374847D03*
X1371146Y1104591D03*
X1374847D03*
X1378548Y1098213D03*
Y1104591D03*
X1369296Y1107780D03*
X1367445Y1110969D03*
X1369296Y1114158D03*
X1367445Y1117347D03*
X1371146Y1110969D03*
X1378548D03*
X1374847D03*
X1378548Y1117347D03*
X1367445Y1130103D03*
X1369296Y1126914D03*
Y1120536D03*
X1367445Y1123725D03*
X1369296Y1133292D03*
X1374847Y1123725D03*
X1371146D03*
X1378548D03*
Y1130102D03*
X1369296Y1139669D03*
X1367445Y1136480D03*
Y1142858D03*
X1369296Y1146047D03*
X1374847Y1136480D03*
X1371146D03*
X1378548D03*
Y1142858D03*
X1371146Y1149236D03*
X1374847D03*
X1367445Y1155614D03*
X1365595Y1158803D03*
X1371146Y1155614D03*
X1378548D03*
X1374847D03*
X1376697Y1158803D03*
Y1165181D03*
X1374847Y1161992D03*
X1365315Y1547243D03*
X1366709Y1540295D03*
X1370039Y1547243D03*
X1371433Y1540295D03*
X1374763Y1547243D03*
X1376158Y1540295D03*
X1379488Y1547243D03*
X1379158Y1554453D03*
X1374433D03*
X1369709D03*
X1364984D03*
X1374984Y1561853D03*
X1370260D03*
X1365535D03*
X1371433Y1575641D03*
X1366709D03*
X1376158D03*
X1374483Y1569063D03*
X1370479Y1625380D03*
X1374740D03*
X1368719Y1635380D03*
X1376499Y1635286D03*
X1368719Y1647292D03*
X1376499D03*
X1370479Y1657292D03*
X1374739D03*
X1385937Y1028063D03*
Y1034441D03*
X1393339Y1040819D03*
X1385937D03*
X1385949Y1047189D03*
Y1053567D03*
X1384099Y1056756D03*
Y1050378D03*
X1393351Y1047189D03*
Y1053567D03*
X1389650Y1059945D03*
X1391500Y1056756D03*
Y1050378D03*
X1389650Y1066323D03*
X1391500Y1069512D03*
X1389650Y1072701D03*
X1380398Y1063134D03*
X1385949Y1066323D03*
X1382249D03*
X1380398Y1069512D03*
X1391500Y1063134D03*
X1393351Y1066323D03*
X1380398Y1075890D03*
X1385949Y1079079D03*
X1382249D03*
X1380398Y1088646D03*
Y1082268D03*
X1391500Y1075890D03*
X1393351Y1079079D03*
X1389650D03*
X1391500Y1088646D03*
X1389650Y1085457D03*
X1391500Y1082268D03*
X1385949Y1091835D03*
X1382249D03*
X1380398Y1095024D03*
X1393351Y1091835D03*
X1389650D03*
X1391500Y1095024D03*
Y1101402D03*
X1389650Y1098213D03*
X1393351Y1104591D03*
X1389650D03*
X1385949Y1110969D03*
X1382249D03*
X1380398Y1107780D03*
Y1114158D03*
X1393351Y1110969D03*
X1389650D03*
X1391500Y1107780D03*
X1389650Y1117347D03*
X1391500Y1114158D03*
X1385949Y1123725D03*
X1382249D03*
X1380398Y1120536D03*
Y1126914D03*
Y1133292D03*
X1393351Y1123725D03*
X1389650D03*
X1391500Y1120536D03*
Y1126914D03*
Y1133292D03*
X1389650Y1130102D03*
X1380398Y1139669D03*
X1385949Y1136480D03*
X1382249D03*
X1385949Y1149236D03*
X1382249D03*
X1380398Y1146047D03*
X1391500Y1139669D03*
X1393351Y1136480D03*
X1389650D03*
Y1142858D03*
X1393351Y1149236D03*
X1391500Y1146047D03*
X1385949Y1155614D03*
X1382249D03*
X1385949Y1161992D03*
X1387800Y1158803D03*
X1393351Y1155614D03*
X1389650D03*
X1380882Y1540295D03*
X1384212Y1547243D03*
X1385606Y1540295D03*
X1390331D03*
X1393661Y1547243D03*
X1393331Y1554453D03*
X1388607D03*
X1383882D03*
X1393882Y1561853D03*
X1389158D03*
X1384433D03*
X1379709D03*
X1385606Y1575641D03*
X1383932Y1569063D03*
X1380882Y1575641D03*
X1390331D03*
X1393381Y1569063D03*
X1382539Y1625380D03*
X1388569Y1635380D03*
X1380779D03*
Y1647292D03*
X1388569D03*
X1382539Y1657292D03*
X1400740Y1040819D03*
X1400752Y1047189D03*
X1398902Y1056756D03*
X1400752Y1053567D03*
Y1059945D03*
X1398902Y1050378D03*
X1408154Y1047189D03*
Y1053567D03*
X1406304Y1056756D03*
Y1050378D03*
X1402603Y1063134D03*
Y1069512D03*
X1397052Y1066323D03*
X1400752D03*
Y1072701D03*
X1406304Y1063134D03*
X1402603Y1075890D03*
X1400752Y1079079D03*
X1397052D03*
X1402603Y1088646D03*
Y1082268D03*
X1400752Y1085457D03*
X1406304Y1075890D03*
Y1088646D03*
X1402603Y1095024D03*
X1400752Y1091835D03*
X1397052D03*
X1402603Y1101402D03*
X1400752Y1104591D03*
X1397052D03*
X1400752Y1098213D03*
X1406304Y1101402D03*
X1402603Y1107780D03*
X1397052Y1110969D03*
X1400752D03*
X1402603Y1114158D03*
X1400752Y1117347D03*
X1406304Y1107780D03*
X1402603Y1120536D03*
Y1126914D03*
X1397052Y1123725D03*
X1400752D03*
X1402603Y1133292D03*
X1406304Y1120536D03*
Y1133292D03*
X1400752Y1130103D03*
X1402603Y1139669D03*
X1397052Y1136480D03*
X1400752D03*
Y1142858D03*
X1402603Y1146047D03*
X1397052Y1149236D03*
X1408154D03*
X1404453D03*
X1398902Y1158803D03*
X1397052Y1155614D03*
X1400752D03*
X1397052Y1161992D03*
X1398902Y1165181D03*
X1406304Y1158803D03*
X1395055Y1540295D03*
X1398076Y1554453D03*
X1395055Y1575641D03*
X1398712Y1569063D03*
X1411855Y1059945D03*
X1422932Y1047189D03*
Y1059945D03*
Y1053567D03*
X1410004Y1063134D03*
X1411855Y1066323D03*
Y1072701D03*
X1422932D03*
Y1066323D03*
X1410004Y1075890D03*
X1411855Y1079079D03*
Y1085457D03*
X1410004Y1088646D03*
X1422932Y1079079D03*
Y1085457D03*
Y1091835D03*
Y1104591D03*
Y1098213D03*
X1411855Y1091835D03*
Y1104591D03*
Y1098213D03*
X1410004Y1101402D03*
Y1107780D03*
X1411855Y1110969D03*
Y1117347D03*
X1422932Y1110969D03*
Y1117347D03*
X1411855Y1123725D03*
X1410004Y1120536D03*
X1411855Y1130102D03*
X1410004Y1133292D03*
X1422932Y1123725D03*
Y1130102D03*
X1411855Y1136480D03*
Y1142858D03*
Y1149236D03*
X1422932Y1136480D03*
Y1142858D03*
Y1149236D03*
X1411855Y1155614D03*
Y1161992D03*
X1422932Y1155614D03*
Y1161992D03*
X1430346Y1040819D03*
X1437748D03*
X1430334Y1047189D03*
X1424783Y1056756D03*
X1434035Y1059945D03*
X1432184Y1056756D03*
X1430334Y1053567D03*
X1424783Y1050378D03*
X1432184D03*
X1437735Y1047189D03*
Y1053567D03*
X1432184Y1063134D03*
X1428483D03*
X1424783D03*
X1432184Y1069512D03*
X1434035Y1072701D03*
Y1066323D03*
X1437735D03*
Y1079079D03*
X1428483Y1075890D03*
X1432184D03*
X1424783D03*
X1434035Y1079079D03*
X1424783Y1088646D03*
X1432184Y1082268D03*
X1428483Y1088646D03*
X1432184D03*
X1434035Y1085457D03*
X1432184Y1095024D03*
X1434035Y1091835D03*
Y1104591D03*
X1428483Y1101402D03*
X1432184D03*
X1434035Y1098213D03*
X1424783Y1101402D03*
X1437735Y1091835D03*
Y1104591D03*
X1428483Y1107780D03*
X1432184D03*
X1424783D03*
X1434035Y1110969D03*
Y1117347D03*
X1432184Y1114158D03*
X1437735Y1110969D03*
X1432184Y1126914D03*
Y1120536D03*
X1428483D03*
X1424783D03*
X1434035Y1123725D03*
X1424783Y1133292D03*
X1428483D03*
X1432184D03*
X1437735Y1123725D03*
X1434035Y1130103D03*
X1432184Y1139669D03*
X1434035Y1136480D03*
Y1142858D03*
X1430334Y1149236D03*
X1432184Y1146047D03*
X1426633Y1149236D03*
X1437735Y1136480D03*
Y1149236D03*
X1430333Y1155614D03*
X1435885Y1158803D03*
Y1152425D03*
X1452542Y1040819D03*
X1445149D03*
X1445137Y1047189D03*
X1446987Y1056756D03*
X1445137Y1059945D03*
X1439586Y1056756D03*
X1445137Y1053567D03*
X1439586Y1050378D03*
X1446987D03*
X1452539Y1047189D03*
Y1053567D03*
X1443287Y1063134D03*
X1445137Y1072701D03*
X1443287Y1069512D03*
X1448838Y1066323D03*
X1445137D03*
X1441436D03*
X1452539D03*
X1445137Y1079079D03*
X1448838D03*
X1441436D03*
X1443287Y1075890D03*
Y1088646D03*
X1445137Y1085457D03*
X1443287Y1082268D03*
X1452539Y1079079D03*
X1441436Y1091835D03*
X1448838D03*
X1445137D03*
X1443287Y1095024D03*
X1445137Y1104591D03*
X1443287Y1101402D03*
X1445137Y1098213D03*
X1441436Y1104591D03*
X1452539Y1091835D03*
X1441436Y1110969D03*
X1448838D03*
X1445137D03*
X1443287Y1107780D03*
X1445137Y1117347D03*
X1443287Y1114158D03*
X1452539Y1110969D03*
X1445137Y1123725D03*
X1448838D03*
X1443287Y1120536D03*
X1441436Y1123725D03*
X1443287Y1126914D03*
Y1133292D03*
X1445137Y1130102D03*
X1452539Y1123725D03*
X1448838Y1149236D03*
X1443287Y1146047D03*
X1441436Y1149236D03*
X1452539Y1136480D03*
Y1149236D03*
X1445137Y1142858D03*
X1443287Y1139669D03*
X1445137Y1136480D03*
X1448838D03*
X1441436D03*
X1446987Y1158803D03*
X1450688Y1152425D03*
X1441436Y1155614D03*
X1449626Y1556810D03*
Y1561725D03*
X1463641Y1028055D03*
X1456239D03*
X1459940Y1040811D03*
X1458090Y1031244D03*
X1463641Y1034433D03*
X1456239D03*
X1465491Y1031244D03*
X1454389Y1037622D03*
X1467342Y1040811D03*
X1454389Y1044000D03*
X1461791Y1037622D03*
Y1044000D03*
X1459940Y1047189D03*
X1456239Y1059945D03*
X1459940Y1053567D03*
X1454389Y1056756D03*
X1461791D03*
X1454389Y1050378D03*
X1461791D03*
X1467342Y1047189D03*
Y1059945D03*
Y1053567D03*
X1465491Y1063134D03*
X1454389D03*
X1456239Y1072701D03*
X1459940Y1066323D03*
X1463641D03*
X1465491Y1069512D03*
X1454389D03*
X1456239Y1066323D03*
X1467342Y1072701D03*
Y1066323D03*
X1459940Y1079079D03*
X1463641D03*
X1456239D03*
X1465491Y1075890D03*
X1454389D03*
X1465491Y1088646D03*
X1454389D03*
X1456239Y1085457D03*
X1465491Y1082268D03*
X1454389D03*
X1467342Y1079079D03*
Y1085457D03*
X1456239Y1098213D03*
X1467342Y1091835D03*
Y1104591D03*
Y1098213D03*
X1463641Y1091835D03*
X1459940D03*
X1456239D03*
X1465491Y1095024D03*
X1454389D03*
X1459940Y1104591D03*
X1463641D03*
X1456239D03*
X1465491Y1107780D03*
X1454389D03*
X1463641Y1110969D03*
X1459940D03*
X1456239D03*
Y1117347D03*
X1454389Y1114158D03*
X1465491D03*
X1467342Y1110969D03*
Y1117347D03*
X1454389Y1120536D03*
X1465491Y1126914D03*
X1454389D03*
X1459940Y1123725D03*
X1463641D03*
X1465491Y1120536D03*
X1456239Y1123725D03*
X1454389Y1133292D03*
X1456239Y1130102D03*
X1465491Y1133292D03*
X1467342Y1123725D03*
Y1130102D03*
X1456239Y1142858D03*
X1465491Y1139669D03*
X1459940Y1136480D03*
X1463641D03*
X1454389Y1139669D03*
X1456239Y1136480D03*
X1465491Y1146047D03*
X1459940Y1149236D03*
X1463641D03*
X1454389Y1146047D03*
X1467342Y1136480D03*
Y1142858D03*
X1463641Y1155614D03*
X1461791Y1152425D03*
X1458090Y1158803D03*
X1454994Y1540512D03*
X1458907Y1547243D03*
X1460301Y1540295D03*
X1463631Y1547243D03*
X1465026Y1540295D03*
X1468356Y1547243D03*
X1457735Y1552195D03*
X1468026Y1554453D03*
X1463301D03*
X1458577D03*
X1468577Y1561853D03*
X1463852D03*
X1459128D03*
X1455098Y1575425D03*
X1468076Y1569063D03*
X1463351D03*
X1460301Y1575641D03*
X1458626Y1569063D03*
X1465026Y1575641D03*
X1458013Y1625380D03*
X1465813D03*
X1464053Y1635380D03*
Y1647292D03*
X1465813Y1657292D03*
X1458013D03*
X1478444Y1028055D03*
X1471043D03*
X1472893Y1031244D03*
X1469192Y1037622D03*
Y1044000D03*
X1478444Y1034433D03*
X1476594Y1037622D03*
X1474743Y1040811D03*
X1476594Y1044000D03*
X1471043Y1034433D03*
X1474743Y1047189D03*
X1480295Y1056756D03*
X1482145Y1059945D03*
X1469192Y1050378D03*
X1476594D03*
Y1056756D03*
X1474743Y1053567D03*
X1478444Y1059945D03*
X1469192Y1056756D03*
X1476594Y1063134D03*
X1478444Y1072701D03*
X1476594Y1069512D03*
X1474743Y1066323D03*
X1471043D03*
X1476594Y1075890D03*
X1474743Y1079079D03*
X1471043D03*
X1478444Y1085457D03*
X1476594Y1088646D03*
Y1082268D03*
X1474743Y1091835D03*
X1471043D03*
X1476594Y1095024D03*
X1478444Y1098213D03*
Y1104591D03*
X1474743D03*
X1471043D03*
X1472893Y1101402D03*
X1476594Y1107780D03*
X1474743Y1110969D03*
X1471043D03*
X1476594Y1114158D03*
X1478444Y1117347D03*
X1476594Y1126914D03*
Y1120536D03*
X1474743Y1123725D03*
X1471043D03*
X1478444Y1130102D03*
X1476594Y1133292D03*
Y1139669D03*
X1474743Y1136480D03*
X1471043D03*
X1478444Y1142858D03*
X1476594Y1146047D03*
X1474743Y1149236D03*
X1471043D03*
X1474743Y1155614D03*
X1478444D03*
X1472893Y1152425D03*
X1480295Y1158803D03*
X1469192D03*
X1469750Y1540295D03*
X1473080Y1547243D03*
X1474474Y1540295D03*
X1477805Y1547243D03*
X1479199Y1540295D03*
X1482529Y1547243D03*
X1483923Y1540295D03*
X1482199Y1554453D03*
X1477474D03*
X1472750D03*
X1482750Y1561853D03*
X1478025D03*
X1473301D03*
X1469750Y1575641D03*
X1483923D03*
X1474474D03*
X1472800Y1569063D03*
X1479199Y1575641D03*
X1470073Y1625380D03*
X1482133D03*
X1477873D03*
X1471833Y1635380D03*
X1483893D03*
X1476113D03*
X1471833Y1647292D03*
X1483893D03*
X1476113D03*
X1470073Y1657292D03*
X1477873D03*
X1482133D03*
X1489547Y1028055D03*
X1496948D03*
X1483995Y1031244D03*
Y1037622D03*
Y1044000D03*
X1491397Y1031244D03*
X1489547Y1040811D03*
Y1034433D03*
X1491397Y1044000D03*
X1496948Y1034433D03*
Y1040811D03*
Y1047189D03*
X1483995Y1050378D03*
Y1056756D03*
X1489547Y1053567D03*
X1495098Y1056756D03*
X1491397Y1050378D03*
X1489547Y1059945D03*
X1493247D03*
X1496948Y1053567D03*
Y1059945D03*
X1483995Y1063134D03*
X1491397D03*
X1483995Y1069512D03*
X1489547Y1072701D03*
X1491397Y1069512D03*
X1496948Y1072701D03*
Y1066323D03*
X1483995Y1075890D03*
X1489547Y1079079D03*
X1496948D03*
X1483995Y1088646D03*
X1491397D03*
X1496948Y1085457D03*
X1483995Y1082268D03*
X1491397D03*
X1489547Y1091835D03*
X1496948D03*
X1483995Y1095024D03*
Y1101402D03*
X1489547Y1098213D03*
X1491397Y1101402D03*
X1496948Y1098213D03*
Y1104591D03*
X1489547Y1110969D03*
X1496948D03*
X1483995Y1107780D03*
X1491397D03*
X1483995Y1114158D03*
X1489547Y1117347D03*
X1496948D03*
X1483995Y1120536D03*
X1491397D03*
X1496948Y1123725D03*
X1483995Y1126914D03*
X1491397D03*
X1483995Y1133292D03*
X1496948Y1130102D03*
X1489547Y1130103D03*
X1483995Y1139669D03*
X1489547Y1136480D03*
X1491397Y1139669D03*
X1496948Y1136480D03*
Y1142858D03*
X1483995Y1146047D03*
X1489547Y1149236D03*
X1491397Y1146047D03*
X1496948Y1149236D03*
X1487696Y1165181D03*
X1498799Y1158803D03*
X1483995Y1152425D03*
X1485846Y1155614D03*
X1489547D03*
X1493247D03*
X1496948D03*
X1483995Y1158803D03*
X1491397D03*
X1493247Y1161992D03*
X1495111Y1165289D03*
X1491410D03*
X1498812D03*
X1488648Y1540295D03*
X1487253Y1547243D03*
X1491978D03*
X1493372Y1540295D03*
X1496702Y1547243D03*
X1498096Y1540295D03*
X1496372Y1554453D03*
X1491648D03*
X1486923D03*
X1496923Y1561853D03*
X1492199D03*
X1487474D03*
X1488648Y1575641D03*
X1493372D03*
X1498096D03*
X1496422Y1569063D03*
X1486973D03*
X1489933Y1625380D03*
X1494193D03*
X1495953Y1635380D03*
X1488173D03*
X1495953Y1647292D03*
X1488173D03*
X1494193Y1657292D03*
X1489933D03*
X1504350Y1028055D03*
X1502499Y1031244D03*
X1509901D03*
X1504350Y1040811D03*
X1502499Y1037622D03*
X1504350Y1034433D03*
X1502499Y1044000D03*
X1509901Y1037622D03*
Y1044000D03*
X1504350Y1047189D03*
Y1053567D03*
X1502499Y1050378D03*
X1509901Y1056756D03*
Y1050378D03*
X1504350Y1059945D03*
X1508050D03*
X1506200Y1056756D03*
X1502499D03*
Y1063134D03*
X1509901D03*
X1502499Y1069512D03*
X1504350Y1072701D03*
Y1066323D03*
X1509901Y1069512D03*
X1502499Y1075890D03*
X1509901D03*
X1504350Y1079079D03*
Y1085457D03*
X1502499Y1088646D03*
X1509901D03*
X1502499Y1082268D03*
X1509901D03*
X1504350Y1091835D03*
X1502499Y1095024D03*
X1509901D03*
X1504350Y1098213D03*
X1502499Y1101402D03*
X1509901D03*
X1504350Y1104591D03*
X1502499Y1107780D03*
X1509901D03*
X1504350Y1110969D03*
X1509901Y1114158D03*
X1504350Y1117347D03*
X1502499Y1114158D03*
Y1120536D03*
X1504350Y1123725D03*
X1509901Y1120536D03*
X1502499Y1126914D03*
X1509901D03*
Y1133292D03*
X1502499D03*
X1504350Y1130103D03*
X1502499Y1139669D03*
X1504350Y1136480D03*
X1509901Y1139669D03*
X1504350Y1142858D03*
Y1149236D03*
X1502499Y1146047D03*
X1509901D03*
X1504350Y1155614D03*
X1502499Y1152425D03*
X1509901D03*
X1511751Y1155614D03*
X1502499Y1158803D03*
X1506200D03*
X1509901D03*
X1509914Y1165289D03*
X1506213D03*
X1502821Y1540295D03*
X1501427Y1547243D03*
X1506151D03*
X1507545Y1540295D03*
X1510875Y1547243D03*
X1512270Y1540295D03*
X1510545Y1554453D03*
X1505821D03*
X1501096D03*
X1511096Y1561853D03*
X1506372D03*
X1501647D03*
X1507545Y1575641D03*
X1512270D03*
X1510595Y1569063D03*
X1502821Y1575641D03*
X1501993Y1625380D03*
X1506253D03*
X1508013Y1635380D03*
X1500233D03*
X1512293D03*
X1508013Y1647292D03*
X1500233D03*
X1512293D03*
X1501993Y1657292D03*
X1506253D03*
X1513187Y1679320D03*
Y1683857D03*
X1505313Y1684454D03*
Y1679920D03*
Y1675383D03*
X1513187Y1688391D03*
Y1693493D03*
Y1698030D03*
X1505313Y1698627D03*
Y1694093D03*
Y1689556D03*
X1513187Y1716737D03*
Y1702564D03*
Y1707666D03*
Y1712203D03*
X1505313Y1712800D03*
Y1708266D03*
Y1703729D03*
X1513187Y1721840D03*
Y1726377D03*
Y1730911D03*
X1505313Y1726974D03*
Y1722440D03*
Y1717903D03*
X1522854Y1028055D03*
X1515452D03*
X1522854Y1034433D03*
Y1040811D03*
X1517302Y1044000D03*
X1528405Y1037622D03*
Y1044000D03*
X1515452Y1040811D03*
Y1034433D03*
X1517302Y1031244D03*
X1528405D03*
X1515452Y1053567D03*
Y1059945D03*
X1522854Y1047189D03*
Y1053567D03*
X1521003Y1056756D03*
X1517302Y1050378D03*
X1522854Y1059945D03*
X1519153D03*
X1528405Y1050378D03*
Y1056756D03*
X1517302Y1063134D03*
X1528405D03*
X1515452Y1072701D03*
X1522854Y1066323D03*
Y1072701D03*
X1517302Y1069512D03*
X1528405D03*
Y1075890D03*
X1515452Y1079079D03*
X1522854D03*
X1517302Y1082268D03*
X1528405D03*
X1522854Y1085457D03*
X1517302Y1088646D03*
X1528405D03*
X1515452Y1091835D03*
X1522854D03*
X1528405Y1095024D03*
X1522854Y1104591D03*
X1528405Y1101402D03*
X1515452Y1098213D03*
X1522854D03*
X1517302Y1101402D03*
Y1107780D03*
X1528405D03*
X1522854Y1110969D03*
X1515452D03*
X1522854Y1117347D03*
X1528405Y1114158D03*
X1515452Y1117347D03*
X1522854Y1123725D03*
X1517302Y1120536D03*
X1528405D03*
X1517302Y1126914D03*
X1528405D03*
Y1133292D03*
X1515452Y1130102D03*
X1522854Y1130103D03*
Y1142858D03*
Y1136480D03*
X1517302Y1139669D03*
X1528405D03*
X1515452Y1136480D03*
X1528405Y1146047D03*
X1515452Y1149236D03*
X1522854D03*
X1517302Y1146047D03*
X1528405Y1152425D03*
X1524704Y1158803D03*
X1528405D03*
X1515452Y1155614D03*
X1519153D03*
X1522854D03*
X1519153Y1161992D03*
X1521718Y1540295D03*
X1515600Y1547243D03*
X1516994Y1540295D03*
X1520324Y1547243D03*
X1526443Y1540295D03*
X1524719Y1554453D03*
X1519994D03*
X1515270D03*
X1525270Y1561853D03*
X1520545D03*
X1515821D03*
X1516994Y1575641D03*
X1526443D03*
X1521718D03*
X1520044Y1569063D03*
X1514053Y1625380D03*
X1518313D03*
X1526113D03*
X1520073Y1635380D03*
X1524353D03*
X1520073Y1647292D03*
X1524353D03*
X1518313Y1657292D03*
X1514053D03*
X1526113D03*
X1521061Y1684454D03*
Y1679920D03*
Y1675383D03*
Y1698627D03*
Y1694093D03*
Y1689556D03*
Y1712800D03*
Y1708266D03*
Y1703729D03*
Y1726974D03*
Y1722440D03*
Y1717903D03*
X1530255Y1028055D03*
X1541358D03*
X1530255Y1034433D03*
Y1040811D03*
X1541357D03*
Y1034433D03*
X1543208Y1031244D03*
Y1044000D03*
X1535806Y1031244D03*
Y1037622D03*
Y1044000D03*
X1530255Y1047189D03*
Y1053567D03*
Y1059945D03*
X1541357Y1053567D03*
Y1059945D03*
X1543208Y1050378D03*
X1532106Y1056756D03*
X1535806D03*
Y1050378D03*
X1533956Y1059945D03*
X1530255Y1066323D03*
Y1072701D03*
X1543208Y1063134D03*
X1535806D03*
X1543208Y1069512D03*
X1541357Y1072701D03*
X1535806Y1069512D03*
X1530255Y1079079D03*
Y1085457D03*
X1535806Y1075890D03*
X1541357Y1079079D03*
X1543208Y1082268D03*
Y1088646D03*
X1535806D03*
Y1082268D03*
X1530255Y1098213D03*
Y1104591D03*
X1541357Y1091835D03*
X1535806Y1095024D03*
X1543208Y1101402D03*
X1541357Y1098213D03*
X1535806Y1101402D03*
X1530255Y1091835D03*
Y1110969D03*
Y1117347D03*
X1543208Y1107780D03*
X1535806D03*
X1541357Y1110969D03*
Y1117347D03*
X1535806Y1114158D03*
X1530255Y1123725D03*
Y1130102D03*
X1543208Y1120536D03*
X1535806D03*
X1543208Y1126914D03*
X1535806D03*
X1541357Y1130102D03*
X1535806Y1133292D03*
X1530255Y1142858D03*
Y1136480D03*
Y1149236D03*
X1541357Y1136480D03*
X1543208Y1139669D03*
X1535806D03*
X1543208Y1146047D03*
X1541357Y1149236D03*
X1535806Y1146047D03*
X1530255Y1155614D03*
X1537657D03*
X1541357D03*
X1535806Y1152425D03*
X1532106Y1158803D03*
X1535806D03*
X1541357Y1161992D03*
X1532106Y1165181D03*
X1531167Y1540295D03*
X1529773Y1547243D03*
X1534188Y1554453D03*
X1529443D03*
X1529994Y1561853D03*
X1534824Y1569063D03*
X1531167Y1575641D03*
X1529493Y1569063D03*
X1530373Y1625380D03*
X1542433D03*
X1538173D03*
X1532133Y1635380D03*
X1536413D03*
X1532133Y1647292D03*
X1536413D03*
X1530373Y1657292D03*
X1542433D03*
X1538173D03*
X1528935Y1679320D03*
Y1683857D03*
X1536809Y1684454D03*
Y1679920D03*
Y1675383D03*
X1528935Y1688391D03*
Y1693493D03*
Y1698030D03*
X1536809Y1698627D03*
Y1694093D03*
Y1689556D03*
X1528935Y1712203D03*
X1536809Y1712800D03*
Y1708266D03*
Y1703729D03*
X1528935Y1716737D03*
Y1702564D03*
Y1707666D03*
Y1721840D03*
Y1726377D03*
Y1730911D03*
X1536809Y1726974D03*
Y1722440D03*
Y1717903D03*
X1553870Y906181D03*
Y912559D03*
Y918937D03*
Y925315D03*
Y931693D03*
Y938071D03*
Y944449D03*
Y950827D03*
Y957205D03*
Y963583D03*
Y969961D03*
Y976339D03*
Y982717D03*
Y989095D03*
Y995473D03*
Y1008229D03*
Y1001851D03*
X1548759Y1028055D03*
X1555051Y1030197D03*
X1548759Y1040811D03*
Y1034433D03*
X1555051Y1042953D03*
Y1036575D03*
X1546909Y1056756D03*
X1545058Y1059945D03*
X1548759Y1047189D03*
X1555051Y1049331D03*
X1548759Y1053567D03*
Y1059945D03*
X1555051Y1055709D03*
Y1062087D03*
X1548759Y1072701D03*
Y1066323D03*
X1555051Y1068465D03*
Y1074843D03*
X1548759Y1079079D03*
X1555051Y1081221D03*
X1548759Y1085457D03*
X1555051Y1087599D03*
X1548759Y1091835D03*
X1555051Y1093977D03*
X1548759Y1098213D03*
Y1104591D03*
X1555051Y1100355D03*
Y1106733D03*
X1548759Y1110969D03*
X1555051Y1113111D03*
X1548759Y1117347D03*
X1555051Y1119489D03*
Y1132245D03*
X1548759Y1123725D03*
X1555051Y1125867D03*
X1548759Y1130102D03*
Y1136480D03*
X1555051Y1138622D03*
X1548759Y1142858D03*
X1555051Y1145000D03*
X1548759Y1149236D03*
X1545058Y1155614D03*
X1548759D03*
X1555051Y1151378D03*
X1550609Y1158803D03*
X1554310D03*
X1550233Y1625380D03*
X1554493D03*
X1544193Y1635380D03*
X1556253D03*
X1548473D03*
X1544193Y1647292D03*
X1556253D03*
X1548473D03*
X1554493Y1657292D03*
X1550233D03*
X1544683Y1679320D03*
Y1683857D03*
X1552557Y1684454D03*
Y1679920D03*
Y1675383D03*
X1544683Y1688391D03*
Y1693493D03*
Y1698030D03*
X1552557Y1698627D03*
Y1694093D03*
Y1689556D03*
X1544683Y1716737D03*
Y1702564D03*
Y1707666D03*
Y1712203D03*
X1552557Y1712800D03*
Y1708266D03*
Y1703729D03*
X1544683Y1721840D03*
Y1726377D03*
Y1730911D03*
X1552557Y1726974D03*
Y1722440D03*
Y1717903D03*
X1562293Y1625380D03*
X1566553D03*
X1568313Y1635380D03*
X1560533D03*
X1572593D03*
X1568313Y1647292D03*
X1560533D03*
X1572593D03*
X1562293Y1657292D03*
X1566553D03*
X1572243Y1684454D03*
Y1679920D03*
Y1675383D03*
X1560431Y1679320D03*
Y1683857D03*
X1572243Y1698627D03*
Y1694093D03*
Y1689556D03*
X1560431Y1688391D03*
Y1693493D03*
Y1698030D03*
X1572243Y1712800D03*
Y1708266D03*
Y1703729D03*
X1560431Y1716737D03*
Y1702564D03*
Y1707666D03*
Y1712203D03*
X1572243Y1726974D03*
Y1722440D03*
Y1717903D03*
X1560431Y1721840D03*
Y1726377D03*
Y1730911D03*
X1583056Y1540514D03*
X1586969Y1547243D03*
X1585797Y1552195D03*
X1586639Y1554453D03*
X1587190Y1561853D03*
X1577688Y1556810D03*
Y1561725D03*
X1586688Y1569063D03*
X1583160Y1575425D03*
X1574353Y1625380D03*
X1578613D03*
X1586413D03*
X1580373Y1635380D03*
X1584653D03*
X1580373Y1647292D03*
X1584653D03*
X1574353Y1657292D03*
X1578613D03*
X1586413D03*
X1580117Y1679320D03*
Y1683857D03*
X1587991Y1684454D03*
Y1679920D03*
Y1675383D03*
X1580117Y1688391D03*
Y1693493D03*
Y1698030D03*
X1587991Y1698627D03*
Y1694093D03*
Y1689556D03*
X1580117Y1716737D03*
Y1702564D03*
Y1707666D03*
Y1712203D03*
X1587991Y1712800D03*
Y1708266D03*
Y1703729D03*
X1580117Y1721840D03*
Y1726377D03*
Y1730911D03*
X1587991Y1726974D03*
Y1722440D03*
Y1717903D03*
X1588363Y1540295D03*
X1591693Y1547243D03*
X1593088Y1540295D03*
X1596418Y1547243D03*
X1597812Y1540295D03*
X1601142Y1547243D03*
X1602536Y1540295D03*
X1600812Y1554453D03*
X1596088D03*
X1591363D03*
X1601363Y1561853D03*
X1596639D03*
X1591914D03*
X1602536Y1575641D03*
X1600862Y1569063D03*
X1597812Y1575641D03*
X1596138Y1569063D03*
X1593088Y1575641D03*
X1591413Y1569063D03*
X1588363Y1575641D03*
X1590673Y1625380D03*
X1602733D03*
X1598473D03*
X1592433Y1635380D03*
X1596713D03*
X1592433Y1647292D03*
X1596713D03*
X1590673Y1657292D03*
X1598473D03*
X1602733D03*
X1595865Y1679320D03*
Y1683857D03*
Y1688391D03*
Y1693493D03*
Y1698030D03*
Y1716737D03*
Y1702564D03*
Y1707666D03*
Y1712203D03*
Y1721840D03*
Y1726377D03*
Y1730911D03*
X1605867Y1547243D03*
X1607261Y1540295D03*
X1610591Y1547243D03*
X1611985Y1540295D03*
X1615315Y1547243D03*
X1616710Y1540295D03*
X1614985Y1554453D03*
X1610261D03*
X1605536D03*
X1615536Y1561853D03*
X1610812D03*
X1606087D03*
X1616710Y1575641D03*
X1615035Y1569063D03*
X1611985Y1575641D03*
X1607261D03*
X1610533Y1625380D03*
X1614793D03*
X1604493Y1635380D03*
X1616553D03*
X1608773D03*
X1604493Y1647292D03*
X1616553D03*
X1608773D03*
X1614793Y1657292D03*
X1610533D03*
X1611613Y1679320D03*
Y1683857D03*
X1603739Y1684454D03*
Y1679920D03*
Y1675383D03*
X1611613Y1688391D03*
Y1693493D03*
Y1698030D03*
X1603739Y1698627D03*
Y1694093D03*
Y1689556D03*
X1611613Y1702564D03*
Y1707666D03*
Y1712203D03*
X1603739Y1712800D03*
Y1708266D03*
Y1703729D03*
X1611613Y1716737D03*
Y1721840D03*
Y1726377D03*
Y1730911D03*
X1603739Y1726974D03*
Y1722440D03*
Y1717903D03*
X1620040Y1547243D03*
X1621434Y1540295D03*
X1624764Y1547243D03*
X1626158Y1540295D03*
X1629489Y1547243D03*
X1630883Y1540295D03*
X1629158Y1554453D03*
X1624434D03*
X1619710D03*
X1629709Y1561853D03*
X1624985D03*
X1620261D03*
X1630883Y1575641D03*
X1626158D03*
X1624484Y1569063D03*
X1621434Y1575641D03*
X1622593Y1625380D03*
X1626853D03*
X1628613Y1635380D03*
X1620833D03*
X1632893D03*
X1628613Y1647292D03*
X1620833D03*
X1632893D03*
X1622593Y1657292D03*
X1626853D03*
X1627361Y1679320D03*
Y1683857D03*
X1619487Y1684454D03*
Y1679920D03*
Y1675383D03*
X1627361Y1688391D03*
Y1693493D03*
Y1698030D03*
X1619487Y1698627D03*
Y1694093D03*
Y1689556D03*
Y1708266D03*
Y1703729D03*
X1627361Y1716737D03*
Y1702564D03*
Y1707666D03*
Y1712203D03*
X1619487Y1712800D03*
X1627361Y1721840D03*
Y1726377D03*
Y1730911D03*
X1619487Y1726974D03*
Y1722440D03*
Y1717903D03*
X1634213Y1547243D03*
X1635607Y1540295D03*
X1638937Y1547243D03*
X1640332Y1540295D03*
X1643662Y1547243D03*
X1645056Y1540295D03*
X1643332Y1554453D03*
X1638607D03*
X1633883D03*
X1643883Y1561853D03*
X1639158D03*
X1634434D03*
X1645056Y1575641D03*
X1640332D03*
X1638657Y1569063D03*
X1635607Y1575641D03*
X1634653Y1625380D03*
X1638923D03*
X1646713D03*
X1640673Y1635286D03*
X1644953Y1635380D03*
X1640673Y1647292D03*
X1644953D03*
X1634653Y1657292D03*
X1638913D03*
X1646713D03*
X1648386Y1547243D03*
X1649780Y1540295D03*
X1654505D03*
X1657835Y1547243D03*
X1659229Y1540295D03*
X1662250Y1554453D03*
X1657505D03*
X1652781D03*
X1648056D03*
X1658056Y1561853D03*
X1653332D03*
X1648607D03*
X1649780Y1575641D03*
X1648106Y1569063D03*
X1654505Y1575641D03*
X1657555Y1569063D03*
X1659229Y1575641D03*
X1652743Y1635380D03*
Y1647292D03*
X1662886Y1569063D03*
G54D36*
X274913Y1019214D03*
X320189Y838505D03*
Y1199923D03*
X561133Y838505D03*
Y1199923D03*
X606409Y1019214D03*
X841240Y1420331D03*
X1016240D03*
X1251055Y1019213D03*
X1296331Y838504D03*
Y1199922D03*
X1537275Y838504D03*
Y1199922D03*
X1582551Y1019213D03*
G54D44*
X393287Y-28508D03*
Y-18508D03*
X731757Y-20090D03*
X735010Y-20104D03*
X728717Y-18895D03*
X734995Y-17589D03*
X731742Y-17575D03*
X735041Y-14717D03*
X735026Y-12202D03*
X734996Y-7172D03*
X728718Y-8478D03*
X735011Y-9687D03*
X731743Y-7158D03*
X731758Y-9673D03*
X844766Y-24648D03*
Y5352D03*
Y15352D03*
X1180124Y-35569D03*
X1183149Y-34249D03*
X1183164Y-36764D03*
X1183139Y-26179D03*
X1180099Y-14984D03*
X1183124Y-13664D03*
X1183139Y-16179D03*
X1183124Y-23664D03*
X1180099Y-24984D03*
X1183139Y-6179D03*
X1183124Y-3664D03*
X1180099Y-4984D03*
Y15016D03*
X1183124Y16336D03*
X1183139Y13821D03*
X1180099Y5016D03*
X1183124Y6336D03*
X1183139Y3821D03*
X1183140Y24187D03*
X1183125Y26702D03*
X1180100Y25382D03*
X1186402Y-34263D03*
X1186417Y-36778D03*
X1186448Y-31442D03*
X1186433Y-28927D03*
X1186392Y-26193D03*
X1186377Y-13678D03*
X1186392Y-16193D03*
X1186377Y-23678D03*
X1186392Y-6193D03*
X1186377Y-3678D03*
Y16322D03*
X1186392Y13807D03*
X1186377Y6322D03*
X1186392Y3807D03*
X1186423Y19143D03*
X1186408Y21658D03*
X1186393Y24173D03*
X1186378Y26688D03*
X1248286Y-34648D03*
Y-4648D03*
Y5352D03*
X1438983Y-35569D03*
X1438959Y25382D03*
X1445292Y-28927D03*
X1445307Y-31442D03*
X1442023Y-36764D03*
X1442008Y-34249D03*
X1445276Y-36778D03*
X1445261Y-34263D03*
X1441909Y-19948D03*
X1445171D03*
X1441909Y-9948D03*
X1445171D03*
X1441909Y52D03*
X1445171D03*
X1441909Y10052D03*
X1445171D03*
X1445237Y26688D03*
X1445252Y24173D03*
X1441984Y26702D03*
X1441999Y24187D03*
X1445267Y21658D03*
X1445282Y19143D03*
X1541580Y-38849D03*
Y-28849D03*
X1735374Y-27916D03*
X1732349Y-29236D03*
X1735389Y-30431D03*
X1735390Y-20014D03*
X1735375Y-17499D03*
X1732350Y-18819D03*
X1738627Y-27930D03*
X1738642Y-30445D03*
X1738643Y-20028D03*
X1738628Y-17513D03*
X1738673Y-25058D03*
X1738658Y-22543D03*
G54D78*
X1900275Y-39973D03*
X1910275D03*
X1931395Y572237D03*
X1921395D03*
X1929766Y1198160D03*
X1919766D03*
X1942395Y-39783D03*
X1952395D03*
X1963362Y572379D03*
X1961856Y1198170D03*
X1973362Y572379D03*
X1971856Y1198170D03*
X1984482Y-39811D03*
X1994482D03*
X2005452Y572389D03*
X2003823Y1198312D03*
X2015452Y572389D03*
X2013823Y1198312D03*
X2036452Y-39631D03*
X2026452D03*
X2047419Y572531D03*
X2057419D03*
G54D21*
X57646Y12480D03*
X137272D03*
X186622D03*
X266858D03*
X315598D03*
X502528Y33267D03*
X582154D03*
X631504D03*
X711740D03*
X760480D03*
X1532055Y12480D03*
X1611681D03*
X1661031D03*
X1741267D03*
X1790007D03*
G54D40*
X326731Y663237D03*
X363731D03*
X754645Y1436735D03*
X1166535Y1422322D03*
X1291146Y1385558D03*
X1320516D03*
X1487677Y649988D03*
X1524437Y650208D03*
X1701285Y208455D03*
X1700840Y1434362D03*
X1731660Y208455D03*
X1770442Y294777D03*
X1800002D03*
G54D62*
X1077638Y133866D03*
G54D26*
X77394Y734588D03*
Y1021399D03*
Y1277698D03*
X107095Y734588D03*
Y1021399D03*
Y1277698D03*
X136795Y734588D03*
Y1021399D03*
Y1277698D03*
X166496Y734588D03*
Y1021399D03*
Y1277698D03*
X196197Y734588D03*
Y1021399D03*
Y1277698D03*
X225898Y734588D03*
Y1021399D03*
Y1277698D03*
X655425Y734588D03*
Y1021399D03*
Y1277698D03*
X685126Y734588D03*
Y1021399D03*
Y1277698D03*
X714827Y734588D03*
Y1021399D03*
Y1277698D03*
X744528Y734588D03*
Y1021399D03*
Y1277698D03*
X774229Y734588D03*
Y1021399D03*
Y1277698D03*
X803929Y734588D03*
Y1021399D03*
Y1277698D03*
X1053536Y734587D03*
Y1021398D03*
Y1277697D03*
X1083237Y734587D03*
Y1021398D03*
Y1277697D03*
X1112937Y734587D03*
Y1021398D03*
Y1277697D03*
X1142638Y734587D03*
Y1021398D03*
Y1277697D03*
X1172339Y734587D03*
Y1021398D03*
Y1277697D03*
X1202040Y734587D03*
Y1021398D03*
Y1277697D03*
X1631567Y734587D03*
Y1021398D03*
Y1277697D03*
X1661268Y734587D03*
Y1021398D03*
Y1277697D03*
X1690969Y734587D03*
Y1021398D03*
Y1277697D03*
X1720670Y734587D03*
Y1021398D03*
Y1277697D03*
X1750371Y734587D03*
Y1021398D03*
Y1277697D03*
X1780071Y734587D03*
Y1021398D03*
Y1277697D03*
G54D56*
X887519Y1528191D03*
G54D68*
X1299439Y112812D03*
G54D69*
X1454797Y87432D03*
G54D70*
X1550377Y581353D03*
G54D48*
X549016Y274272D03*
G54D57*
X900197Y175177D03*
X944685Y155197D03*
G54D77*
X1864706Y1722195D03*
X1887340Y424013D03*
X1887240Y796658D03*
X1887579Y1171532D03*
G54D75*
X1865648Y796913D03*
X1866790Y1171255D03*
X1886177Y1722507D03*
X2076128Y424013D03*
%LPC*%
G75*
G54D82*
G01X-476840Y-884638D02*
Y2768362D01*
X5911000D01*
Y-884638D01*
X-476840D01*
G01X8000Y-625138D02*
Y-630138D01*
G01X6543Y-625138D02*
X9457D01*
G01X14367Y-630138D02*
X11833D01*
Y-625138D01*
X14367D01*
G01X13353Y-627555D02*
X11833D01*
G01X16933Y-625138D02*
Y-630138D01*
X19467D01*
G01X23300Y-630305D02*
X23173Y-630221D01*
Y-630055D01*
X23300Y-629971D01*
X23427Y-630055D01*
Y-630221D01*
X23300Y-630305D01*
G01Y-628055D02*
X23173Y-627971D01*
Y-627805D01*
X23300Y-627721D01*
X23427Y-627805D01*
Y-627971D01*
X23300Y-628055D01*
G01X28083Y-631805D02*
X27450Y-630971D01*
X27133Y-630138D01*
Y-626805D01*
X27450Y-625971D01*
X28083Y-625138D01*
G01X33500D02*
X32993Y-625305D01*
X32613Y-625721D01*
X32360Y-626221D01*
X32170Y-626888D01*
X32107Y-627638D01*
X32170Y-628388D01*
X32360Y-629055D01*
X32613Y-629555D01*
X32993Y-629971D01*
X33500Y-630138D01*
X34007Y-629971D01*
X34387Y-629555D01*
X34640Y-629055D01*
X34830Y-628388D01*
X34893Y-627638D01*
X34830Y-626888D01*
X34640Y-626221D01*
X34387Y-625721D01*
X34007Y-625305D01*
X33500Y-625138D01*
G01X37207Y-629138D02*
X37587Y-629721D01*
X38093Y-630055D01*
X38663Y-630138D01*
X39170Y-630055D01*
X39677Y-629638D01*
X39993Y-629138D01*
X40057Y-628638D01*
X39930Y-628055D01*
X39487Y-627638D01*
X39043Y-627471D01*
X38473D01*
G01X39043D02*
X39423Y-627221D01*
X39740Y-626805D01*
X39867Y-626305D01*
X39740Y-625805D01*
X39423Y-625388D01*
X38853Y-625138D01*
X38283Y-625221D01*
X37713Y-625555D01*
G01X44017Y-631805D02*
X44650Y-630971D01*
X44967Y-630138D01*
Y-626805D01*
X44650Y-625971D01*
X44017Y-625138D01*
G01X47407Y-629138D02*
X47787Y-629721D01*
X48293Y-630055D01*
X48863Y-630138D01*
X49370Y-630055D01*
X49877Y-629638D01*
X50193Y-629138D01*
X50257Y-628638D01*
X50130Y-628055D01*
X49687Y-627638D01*
X49243Y-627471D01*
X48673D01*
G01X49243D02*
X49623Y-627221D01*
X49940Y-626805D01*
X50067Y-626305D01*
X49940Y-625805D01*
X49623Y-625388D01*
X49053Y-625138D01*
X48483Y-625221D01*
X47913Y-625555D01*
G01X52697Y-625971D02*
X53077Y-625471D01*
X53520Y-625221D01*
X54027Y-625138D01*
X54660Y-625305D01*
X55103Y-625721D01*
X55230Y-626221D01*
X55167Y-626721D01*
X54913Y-627138D01*
X53647Y-627971D01*
X53077Y-628555D01*
X52697Y-629388D01*
X52570Y-630138D01*
X55230D01*
G01X58873D02*
X59000Y-629055D01*
X59190Y-628138D01*
X59443Y-627305D01*
X59760Y-626388D01*
X60267Y-625138D01*
X57733D01*
G01X63277Y-628471D02*
X64923D01*
G01X67997Y-625971D02*
X68377Y-625471D01*
X68820Y-625221D01*
X69327Y-625138D01*
X69960Y-625305D01*
X70403Y-625721D01*
X70530Y-626221D01*
X70467Y-626721D01*
X70213Y-627138D01*
X68947Y-627971D01*
X68377Y-628555D01*
X67997Y-629388D01*
X67870Y-630138D01*
X70530D01*
G01X72907Y-629138D02*
X73287Y-629721D01*
X73793Y-630055D01*
X74363Y-630138D01*
X74870Y-630055D01*
X75377Y-629638D01*
X75693Y-629138D01*
X75757Y-628638D01*
X75630Y-628055D01*
X75187Y-627638D01*
X74743Y-627471D01*
X74173D01*
G01X74743D02*
X75123Y-627221D01*
X75440Y-626805D01*
X75567Y-626305D01*
X75440Y-625805D01*
X75123Y-625388D01*
X74553Y-625138D01*
X73983Y-625221D01*
X73413Y-625555D01*
G01X80160Y-630138D02*
Y-625138D01*
X77817Y-628721D01*
X80983D01*
G01X83107Y-629388D02*
X83487Y-629805D01*
X83930Y-630055D01*
X84500Y-630138D01*
X85070Y-629971D01*
X85513Y-629638D01*
X85830Y-629055D01*
X85893Y-628388D01*
X85767Y-627721D01*
X85450Y-627305D01*
X85007Y-626971D01*
X84563Y-626888D01*
X84120Y-626971D01*
X83550Y-627305D01*
X83740Y-625138D01*
X85450D01*
G01X93497Y-630138D02*
Y-625138D01*
X95903D01*
G01X95017Y-627555D02*
X93497D01*
G01X98217Y-630138D02*
X99800Y-625138D01*
X101383Y-630138D01*
G01X100813Y-628388D02*
X98787D01*
G01X103570Y-630138D02*
X106230Y-625138D01*
G01X103570D02*
X106230Y-630138D01*
G01X110000Y-630305D02*
X109873Y-630221D01*
Y-630055D01*
X110000Y-629971D01*
X110127Y-630055D01*
Y-630221D01*
X110000Y-630305D01*
G01Y-628055D02*
X109873Y-627971D01*
Y-627805D01*
X110000Y-627721D01*
X110127Y-627805D01*
Y-627971D01*
X110000Y-628055D01*
G01X114783Y-631805D02*
X114150Y-630971D01*
X113833Y-630138D01*
Y-626805D01*
X114150Y-625971D01*
X114783Y-625138D01*
G01X120200D02*
X119693Y-625305D01*
X119313Y-625721D01*
X119060Y-626221D01*
X118870Y-626888D01*
X118807Y-627638D01*
X118870Y-628388D01*
X119060Y-629055D01*
X119313Y-629555D01*
X119693Y-629971D01*
X120200Y-630138D01*
X120707Y-629971D01*
X121087Y-629555D01*
X121340Y-629055D01*
X121530Y-628388D01*
X121593Y-627638D01*
X121530Y-626888D01*
X121340Y-626221D01*
X121087Y-625721D01*
X120707Y-625305D01*
X120200Y-625138D01*
G01X123907Y-629138D02*
X124287Y-629721D01*
X124793Y-630055D01*
X125363Y-630138D01*
X125870Y-630055D01*
X126377Y-629638D01*
X126693Y-629138D01*
X126757Y-628638D01*
X126630Y-628055D01*
X126187Y-627638D01*
X125743Y-627471D01*
X125173D01*
G01X125743D02*
X126123Y-627221D01*
X126440Y-626805D01*
X126567Y-626305D01*
X126440Y-625805D01*
X126123Y-625388D01*
X125553Y-625138D01*
X124983Y-625221D01*
X124413Y-625555D01*
G01X130717Y-631805D02*
X131350Y-630971D01*
X131667Y-630138D01*
Y-626805D01*
X131350Y-625971D01*
X130717Y-625138D01*
G01X134107Y-629138D02*
X134487Y-629721D01*
X134993Y-630055D01*
X135563Y-630138D01*
X136070Y-630055D01*
X136577Y-629638D01*
X136893Y-629138D01*
X136957Y-628638D01*
X136830Y-628055D01*
X136387Y-627638D01*
X135943Y-627471D01*
X135373D01*
G01X135943D02*
X136323Y-627221D01*
X136640Y-626805D01*
X136767Y-626305D01*
X136640Y-625805D01*
X136323Y-625388D01*
X135753Y-625138D01*
X135183Y-625221D01*
X134613Y-625555D01*
G01X139523Y-629555D02*
X139967Y-629971D01*
X140473Y-630138D01*
X140980Y-629971D01*
X141423Y-629471D01*
X141740Y-628721D01*
X141867Y-627971D01*
Y-627055D01*
X141740Y-626305D01*
X141423Y-625638D01*
X141043Y-625305D01*
X140600Y-625138D01*
X140093Y-625305D01*
X139713Y-625638D01*
X139460Y-626138D01*
X139333Y-626805D01*
X139460Y-627388D01*
X139777Y-627971D01*
X140157Y-628305D01*
X140600Y-628388D01*
X141107Y-628221D01*
X141487Y-627805D01*
X141867Y-627055D01*
G01X145573Y-630138D02*
X145700Y-629055D01*
X145890Y-628138D01*
X146143Y-627305D01*
X146460Y-626388D01*
X146967Y-625138D01*
X144433D01*
G01X149977Y-628471D02*
X151623D01*
G01X154507Y-629138D02*
X154887Y-629721D01*
X155393Y-630055D01*
X155963Y-630138D01*
X156470Y-630055D01*
X156977Y-629638D01*
X157293Y-629138D01*
X157357Y-628638D01*
X157230Y-628055D01*
X156787Y-627638D01*
X156343Y-627471D01*
X155773D01*
G01X156343D02*
X156723Y-627221D01*
X157040Y-626805D01*
X157167Y-626305D01*
X157040Y-625805D01*
X156723Y-625388D01*
X156153Y-625138D01*
X155583Y-625221D01*
X155013Y-625555D01*
G01X159797Y-628055D02*
X160240Y-627471D01*
X160620Y-627138D01*
X161127Y-626971D01*
X161570Y-627138D01*
X161887Y-627471D01*
X162140Y-627971D01*
X162203Y-628555D01*
X162140Y-629055D01*
X161887Y-629555D01*
X161507Y-629971D01*
X161063Y-630138D01*
X160557Y-629971D01*
X160113Y-629471D01*
X159860Y-628721D01*
X159797Y-627888D01*
X159923Y-626805D01*
X160113Y-626221D01*
X160430Y-625638D01*
X160873Y-625221D01*
X161317Y-625138D01*
X161760Y-625305D01*
X162077Y-625721D01*
G01X166100Y-630138D02*
Y-625138D01*
X165340Y-626138D01*
G01Y-630138D02*
X166860D01*
G01X171960D02*
Y-625138D01*
X169617Y-628721D01*
X172783D01*
G01X-4000Y-560138D02*
Y-635138D01*
X496000D01*
Y-560138D01*
X-4000D01*
G01X191000D02*
Y-635138D01*
G01Y-610138D02*
X294000D01*
Y-585138D01*
G01X191000D02*
X294000D01*
G01X296000Y-560138D02*
Y-635138D01*
G01X294000Y-560138D02*
Y-635138D01*
G01X301507Y-620138D02*
Y-615138D01*
X302773D01*
X303280Y-615388D01*
X303660Y-615721D01*
X303977Y-616221D01*
X304230Y-616805D01*
X304293Y-617638D01*
X304230Y-618471D01*
X303977Y-619055D01*
X303660Y-619555D01*
X303280Y-619888D01*
X302773Y-620138D01*
X301507D01*
G01X306417D02*
X308000Y-615138D01*
X309583Y-620138D01*
G01X309013Y-618388D02*
X306987D01*
G01X313100Y-615138D02*
Y-620138D01*
G01X311643Y-615138D02*
X314557D01*
G01X319467Y-620138D02*
X316933D01*
Y-615138D01*
X319467D01*
G01X318453Y-617555D02*
X316933D01*
G01X323300Y-620305D02*
X323173Y-620221D01*
Y-620055D01*
X323300Y-619971D01*
X323427Y-620055D01*
Y-620221D01*
X323300Y-620305D01*
G01Y-618055D02*
X323173Y-617971D01*
Y-617805D01*
X323300Y-617721D01*
X323427Y-617805D01*
Y-617971D01*
X323300Y-618055D01*
G01X296000Y-610138D02*
X496000D01*
G01X301633Y-595138D02*
Y-590138D01*
X303153D01*
X303660Y-590388D01*
X304040Y-590971D01*
X304167Y-591638D01*
X304040Y-592305D01*
X303723Y-592805D01*
X303153Y-593055D01*
X301633D01*
G01X306860Y-595305D02*
X309140Y-590138D01*
G01X311643Y-595138D02*
Y-590138D01*
X314557Y-595138D01*
Y-590138D01*
G01X318200Y-595305D02*
X318073Y-595221D01*
Y-595055D01*
X318200Y-594971D01*
X318327Y-595055D01*
Y-595221D01*
X318200Y-595305D01*
G01Y-593055D02*
X318073Y-592971D01*
Y-592805D01*
X318200Y-592721D01*
X318327Y-592805D01*
Y-592971D01*
X318200Y-593055D01*
G01X296000Y-585138D02*
X496000D01*
G01X301633Y-570138D02*
Y-565138D01*
X303153D01*
X303660Y-565388D01*
X304040Y-565971D01*
X304167Y-566638D01*
X304040Y-567305D01*
X303723Y-567805D01*
X303153Y-568055D01*
X301633D01*
G01X306733Y-570138D02*
Y-565138D01*
X308317D01*
X308823Y-565388D01*
X309140Y-565721D01*
X309267Y-566388D01*
X309140Y-567055D01*
X308760Y-567471D01*
X308317Y-567721D01*
X306733D01*
G01X308317D02*
X309267Y-570138D01*
G01X313100D02*
X312593Y-570055D01*
X312150Y-569721D01*
X311770Y-569221D01*
X311517Y-568638D01*
X311390Y-567971D01*
Y-567305D01*
X311517Y-566638D01*
X311770Y-566055D01*
X312150Y-565555D01*
X312593Y-565221D01*
X313100Y-565138D01*
X313607Y-565221D01*
X314050Y-565555D01*
X314430Y-566055D01*
X314683Y-566638D01*
X314810Y-567305D01*
Y-567971D01*
X314683Y-568638D01*
X314430Y-569221D01*
X314050Y-569721D01*
X313607Y-570055D01*
X313100Y-570138D01*
G01X316933Y-569138D02*
X317250Y-569638D01*
X317630Y-569971D01*
X318073Y-570138D01*
X318580Y-569971D01*
X318960Y-569638D01*
X319340Y-569138D01*
X319467Y-568471D01*
Y-565138D01*
G01X324567Y-570138D02*
X322033D01*
Y-565138D01*
X324567D01*
G01X323553Y-567555D02*
X322033D01*
G01X329793Y-565555D02*
X329413Y-565305D01*
X328970Y-565138D01*
X328463D01*
X327893Y-565388D01*
X327450Y-565805D01*
X327133Y-566305D01*
X326880Y-567138D01*
X326817Y-567888D01*
X326943Y-568638D01*
X327133Y-569138D01*
X327513Y-569638D01*
X327957Y-569971D01*
X328400Y-570138D01*
X328843D01*
X329287Y-569971D01*
X329667Y-569721D01*
X329983Y-569388D01*
G01X333500Y-565138D02*
Y-570138D01*
G01X332043Y-565138D02*
X334957D01*
G01X338600Y-570305D02*
X338473Y-570221D01*
Y-570055D01*
X338600Y-569971D01*
X338727Y-570055D01*
Y-570221D01*
X338600Y-570305D01*
G01Y-568055D02*
X338473Y-567971D01*
Y-567805D01*
X338600Y-567721D01*
X338727Y-567805D01*
Y-567971D01*
X338600Y-568055D01*
G01X411000Y-610138D02*
Y-635138D01*
G01X413633Y-612638D02*
Y-617638D01*
X416167D01*
G01X419240Y-612638D02*
X420760D01*
G01X420000D02*
Y-617638D01*
G01X419240D02*
X420760D01*
G01X425607Y-614971D02*
X425860Y-614721D01*
X426050Y-614305D01*
X426177Y-613721D01*
X426050Y-613221D01*
X425797Y-612888D01*
X425353Y-612638D01*
X423643D01*
Y-617638D01*
X425733D01*
X426177Y-617305D01*
X426430Y-616805D01*
X426557Y-616221D01*
X426430Y-615638D01*
X426050Y-615138D01*
X425607Y-614971D01*
X423643D01*
G01X430200Y-617805D02*
X430073Y-617721D01*
Y-617555D01*
X430200Y-617471D01*
X430327Y-617555D01*
Y-617721D01*
X430200Y-617805D01*
G01Y-615555D02*
X430073Y-615471D01*
Y-615305D01*
X430200Y-615221D01*
X430327Y-615305D01*
Y-615471D01*
X430200Y-615555D01*
G01X454000Y-610138D02*
Y-635138D01*
G01Y-585138D02*
Y-610138D01*
G01X459013Y-637305D02*
X459120Y-637180D01*
X459200Y-636971D01*
X459253Y-636680D01*
X459200Y-636430D01*
X459093Y-636263D01*
X458907Y-636138D01*
X458187D01*
Y-638638D01*
X459067D01*
X459253Y-638471D01*
X459360Y-638221D01*
X459413Y-637930D01*
X459360Y-637638D01*
X459200Y-637388D01*
X459013Y-637305D01*
X458187D01*
G01X461480Y-638638D02*
Y-636971D01*
G01Y-637263D02*
X461373Y-637096D01*
X461213Y-637013D01*
X461027Y-636971D01*
X460840Y-637055D01*
X460680Y-637221D01*
X460573Y-637471D01*
X460520Y-637805D01*
X460573Y-638138D01*
X460680Y-638388D01*
X460840Y-638555D01*
X461027Y-638638D01*
X461213Y-638596D01*
X461373Y-638471D01*
X461480Y-638305D01*
G01X462800Y-638346D02*
X462933Y-638513D01*
X463120Y-638638D01*
X463280D01*
X463440Y-638555D01*
X463547Y-638430D01*
X463600Y-638263D01*
X463573Y-638013D01*
X463467Y-637888D01*
X462987Y-637638D01*
X462880Y-637346D01*
X462933Y-637138D01*
X463040Y-637013D01*
X463200Y-636971D01*
X463360Y-637013D01*
X463520Y-637138D01*
G01X465000Y-637513D02*
X465853D01*
X465773Y-637221D01*
X465640Y-637055D01*
X465453Y-636971D01*
X465267Y-637013D01*
X465107Y-637138D01*
X465000Y-637430D01*
X464947Y-637680D01*
Y-637930D01*
X465000Y-638180D01*
X465133Y-638430D01*
X465293Y-638596D01*
X465480Y-638638D01*
X465667Y-638555D01*
X465853Y-638305D01*
G01X467120Y-638638D02*
Y-636138D01*
G01Y-637388D02*
X467253Y-637138D01*
X467413Y-637013D01*
X467573Y-636971D01*
X467813Y-637055D01*
X467973Y-637221D01*
X468080Y-637513D01*
Y-637846D01*
X468027Y-638180D01*
X467920Y-638430D01*
X467733Y-638596D01*
X467573Y-638638D01*
X467413Y-638596D01*
X467253Y-638471D01*
X467120Y-638263D01*
G01X469800Y-638638D02*
X469640Y-638596D01*
X469480Y-638430D01*
X469373Y-638138D01*
X469320Y-637805D01*
X469373Y-637471D01*
X469480Y-637180D01*
X469640Y-637013D01*
X469800Y-636971D01*
X469960Y-637013D01*
X470120Y-637180D01*
X470227Y-637471D01*
X470253Y-637805D01*
X470227Y-638138D01*
X470120Y-638430D01*
X469960Y-638596D01*
X469800Y-638638D01*
G01X472480D02*
Y-636971D01*
G01Y-637263D02*
X472373Y-637096D01*
X472213Y-637013D01*
X472027Y-636971D01*
X471840Y-637055D01*
X471680Y-637221D01*
X471573Y-637471D01*
X471520Y-637805D01*
X471573Y-638138D01*
X471680Y-638388D01*
X471840Y-638555D01*
X472027Y-638638D01*
X472213Y-638596D01*
X472373Y-638471D01*
X472480Y-638305D01*
G01X473827Y-638638D02*
Y-636971D01*
G01Y-637305D02*
X473960Y-637138D01*
X474093Y-637013D01*
X474280Y-636971D01*
X474413Y-637013D01*
X474573Y-637138D01*
G01X476880Y-636138D02*
Y-638638D01*
G01Y-638263D02*
X476773Y-638471D01*
X476613Y-638596D01*
X476427Y-638638D01*
X476213Y-638555D01*
X476053Y-638346D01*
X475947Y-638096D01*
X475920Y-637805D01*
X475947Y-637513D01*
X476053Y-637263D01*
X476213Y-637055D01*
X476427Y-636971D01*
X476613Y-637013D01*
X476747Y-637096D01*
X476880Y-637263D01*
G01X480267Y-638638D02*
Y-636138D01*
X480933D01*
X481147Y-636263D01*
X481280Y-636430D01*
X481333Y-636763D01*
X481280Y-637096D01*
X481120Y-637305D01*
X480933Y-637430D01*
X480267D01*
G01X480933D02*
X481333Y-638638D01*
G01X482600Y-637513D02*
X483453D01*
X483373Y-637221D01*
X483240Y-637055D01*
X483053Y-636971D01*
X482867Y-637013D01*
X482707Y-637138D01*
X482600Y-637430D01*
X482547Y-637680D01*
Y-637930D01*
X482600Y-638180D01*
X482733Y-638430D01*
X482893Y-638596D01*
X483080Y-638638D01*
X483267Y-638555D01*
X483453Y-638305D01*
G01X484720Y-636971D02*
X485200Y-638638D01*
X485680Y-636971D01*
G01X487400Y-638721D02*
X487347Y-638680D01*
Y-638596D01*
X487400Y-638555D01*
X487453Y-638596D01*
Y-638680D01*
X487400Y-638721D01*
G01X489147Y-638346D02*
X489333Y-638555D01*
X489547Y-638638D01*
X489760Y-638555D01*
X489947Y-638305D01*
X490080Y-637930D01*
X490133Y-637555D01*
Y-637096D01*
X490080Y-636721D01*
X489947Y-636388D01*
X489787Y-636221D01*
X489600Y-636138D01*
X489387Y-636221D01*
X489227Y-636388D01*
X489120Y-636638D01*
X489067Y-636971D01*
X489120Y-637263D01*
X489253Y-637555D01*
X489413Y-637721D01*
X489600Y-637763D01*
X489813Y-637680D01*
X489973Y-637471D01*
X490133Y-637096D01*
G01X492013Y-637305D02*
X492120Y-637180D01*
X492200Y-636971D01*
X492253Y-636680D01*
X492200Y-636430D01*
X492093Y-636263D01*
X491907Y-636138D01*
X491187D01*
Y-638638D01*
X492067D01*
X492253Y-638471D01*
X492360Y-638221D01*
X492413Y-637930D01*
X492360Y-637638D01*
X492200Y-637388D01*
X492013Y-637305D01*
X491187D01*
G01X457900Y-612638D02*
Y-617638D01*
G01X456443Y-612638D02*
X459357D01*
G01X463000Y-617638D02*
X462620Y-617555D01*
X462240Y-617221D01*
X461987Y-616638D01*
X461860Y-615971D01*
X461987Y-615305D01*
X462240Y-614721D01*
X462620Y-614388D01*
X463000Y-614305D01*
X463380Y-614388D01*
X463760Y-614721D01*
X464013Y-615305D01*
X464077Y-615971D01*
X464013Y-616638D01*
X463760Y-617221D01*
X463380Y-617555D01*
X463000Y-617638D01*
G01X468100D02*
X467720Y-617555D01*
X467340Y-617221D01*
X467087Y-616638D01*
X466960Y-615971D01*
X467087Y-615305D01*
X467340Y-614721D01*
X467720Y-614388D01*
X468100Y-614305D01*
X468480Y-614388D01*
X468860Y-614721D01*
X469113Y-615305D01*
X469177Y-615971D01*
X469113Y-616638D01*
X468860Y-617221D01*
X468480Y-617555D01*
X468100Y-617638D01*
G01X473200D02*
Y-612638D01*
G01X478300Y-617805D02*
X478173Y-617721D01*
Y-617555D01*
X478300Y-617471D01*
X478427Y-617555D01*
Y-617721D01*
X478300Y-617805D01*
G01Y-615555D02*
X478173Y-615471D01*
Y-615305D01*
X478300Y-615221D01*
X478427Y-615305D01*
Y-615471D01*
X478300Y-615555D01*
G01X456633Y-592638D02*
Y-587638D01*
X458217D01*
X458723Y-587888D01*
X459040Y-588221D01*
X459167Y-588888D01*
X459040Y-589555D01*
X458660Y-589971D01*
X458217Y-590221D01*
X456633D01*
G01X458217D02*
X459167Y-592638D01*
G01X464267D02*
X461733D01*
Y-587638D01*
X464267D01*
G01X463253Y-590055D02*
X461733D01*
G01X466517Y-587638D02*
X468100Y-592638D01*
X469683Y-587638D01*
G01X473200Y-592805D02*
X473073Y-592721D01*
Y-592555D01*
X473200Y-592471D01*
X473327Y-592555D01*
Y-592721D01*
X473200Y-592805D01*
G01Y-590555D02*
X473073Y-590471D01*
Y-590305D01*
X473200Y-590221D01*
X473327Y-590305D01*
Y-590471D01*
X473200Y-590555D01*
G01X-476840Y-884638D02*
Y2768362D01*
X5911000D01*
Y-884638D01*
X-476840D01*
G01X8820Y-607488D02*
X10387D01*
Y-609378D01*
X9917Y-610008D01*
X9368Y-610428D01*
X8585Y-610638D01*
X7802Y-610428D01*
X7253Y-610008D01*
X6783Y-609378D01*
X6470Y-608643D01*
X6313Y-607803D01*
Y-607068D01*
X6470Y-606438D01*
X6783Y-605703D01*
X7253Y-605073D01*
X7723Y-604653D01*
X8350Y-604338D01*
X8898D01*
X9525Y-604548D01*
X9995Y-604968D01*
G01X12927Y-604338D02*
Y-608853D01*
X13240Y-609798D01*
X13867Y-610428D01*
X14650Y-610638D01*
X15433Y-610428D01*
X16060Y-609798D01*
X16373Y-608853D01*
Y-604338D01*
G01X20010D02*
X21890D01*
G01X20950D02*
Y-610638D01*
G01X20010D02*
X21890D01*
G01X25605Y-609798D02*
X26232Y-610323D01*
X26937Y-610638D01*
X27563D01*
X28190Y-610323D01*
X28660Y-609798D01*
X28895Y-609063D01*
X28738Y-608328D01*
X28347Y-607698D01*
X27642Y-607278D01*
X26702Y-607068D01*
X26153Y-606648D01*
X25918Y-605913D01*
X26075Y-605178D01*
X26467Y-604653D01*
X27015Y-604338D01*
X27563D01*
X28112Y-604548D01*
X28582Y-605073D01*
G01X31905Y-610638D02*
Y-604338D01*
G01X35195D02*
Y-610638D01*
G01Y-607488D02*
X31905D01*
G01X37892Y-610638D02*
X39850Y-604338D01*
X41808Y-610638D01*
G01X41103Y-608433D02*
X38597D01*
G01X44348Y-610638D02*
Y-604338D01*
X47952Y-610638D01*
Y-604338D01*
G01X57027Y-610638D02*
Y-604338D01*
X58593D01*
X59220Y-604653D01*
X59690Y-605073D01*
X60082Y-605703D01*
X60395Y-606438D01*
X60473Y-607488D01*
X60395Y-608538D01*
X60082Y-609273D01*
X59690Y-609903D01*
X59220Y-610323D01*
X58593Y-610638D01*
X57027D01*
G01X64110Y-604338D02*
X65990D01*
G01X65050D02*
Y-610638D01*
G01X64110D02*
X65990D01*
G01X69705Y-609798D02*
X70332Y-610323D01*
X71037Y-610638D01*
X71663D01*
X72290Y-610323D01*
X72760Y-609798D01*
X72995Y-609063D01*
X72838Y-608328D01*
X72447Y-607698D01*
X71742Y-607278D01*
X70802Y-607068D01*
X70253Y-606648D01*
X70018Y-605913D01*
X70175Y-605178D01*
X70567Y-604653D01*
X71115Y-604338D01*
X71663D01*
X72212Y-604548D01*
X72682Y-605073D01*
G01X77650Y-604338D02*
Y-610638D01*
G01X75848Y-604338D02*
X79452D01*
G01X83950Y-610848D02*
X83793Y-610743D01*
Y-610533D01*
X83950Y-610428D01*
X84107Y-610533D01*
Y-610743D01*
X83950Y-610848D01*
G01X90093Y-611793D02*
X90407Y-610428D01*
G01X96550Y-604338D02*
Y-610638D01*
G01X94748Y-604338D02*
X98352D01*
G01X100892Y-610638D02*
X102850Y-604338D01*
X104808Y-610638D01*
G01X104103Y-608433D02*
X101597D01*
G01X109150Y-610638D02*
X108523Y-610533D01*
X107975Y-610113D01*
X107505Y-609483D01*
X107192Y-608748D01*
X107035Y-607908D01*
Y-607068D01*
X107192Y-606228D01*
X107505Y-605493D01*
X107975Y-604863D01*
X108523Y-604443D01*
X109150Y-604338D01*
X109777Y-604443D01*
X110325Y-604863D01*
X110795Y-605493D01*
X111108Y-606228D01*
X111265Y-607068D01*
Y-607908D01*
X111108Y-608748D01*
X110795Y-609483D01*
X110325Y-610113D01*
X109777Y-610533D01*
X109150Y-610638D01*
G01X115450D02*
Y-607803D01*
X113883Y-604338D01*
G01X117017D02*
X115450Y-607803D01*
G01X120027Y-604338D02*
Y-608853D01*
X120340Y-609798D01*
X120967Y-610428D01*
X121750Y-610638D01*
X122533Y-610428D01*
X123160Y-609798D01*
X123473Y-608853D01*
Y-604338D01*
G01X126092Y-610638D02*
X128050Y-604338D01*
X130008Y-610638D01*
G01X129303Y-608433D02*
X126797D01*
G01X132548Y-610638D02*
Y-604338D01*
X136152Y-610638D01*
Y-604338D01*
G01X10073Y-614863D02*
X9603Y-614548D01*
X9055Y-614338D01*
X8428D01*
X7723Y-614653D01*
X7175Y-615178D01*
X6783Y-615808D01*
X6470Y-616858D01*
X6392Y-617803D01*
X6548Y-618748D01*
X6783Y-619378D01*
X7253Y-620008D01*
X7802Y-620428D01*
X8350Y-620638D01*
X8898D01*
X9447Y-620428D01*
X9917Y-620113D01*
X10308Y-619693D01*
G01X13710Y-614338D02*
X15590D01*
G01X14650D02*
Y-620638D01*
G01X13710D02*
X15590D01*
G01X20950Y-614338D02*
Y-620638D01*
G01X19148Y-614338D02*
X22752D01*
G01X27250Y-620638D02*
Y-617803D01*
X25683Y-614338D01*
G01X28817D02*
X27250Y-617803D01*
G01X38127Y-619378D02*
X38597Y-620113D01*
X39223Y-620533D01*
X39928Y-620638D01*
X40555Y-620533D01*
X41182Y-620008D01*
X41573Y-619378D01*
X41652Y-618748D01*
X41495Y-618013D01*
X40947Y-617488D01*
X40398Y-617278D01*
X39693D01*
G01X40398D02*
X40868Y-616963D01*
X41260Y-616438D01*
X41417Y-615808D01*
X41260Y-615178D01*
X40868Y-614653D01*
X40163Y-614338D01*
X39458Y-614443D01*
X38753Y-614863D01*
G01X44427Y-619378D02*
X44897Y-620113D01*
X45523Y-620533D01*
X46228Y-620638D01*
X46855Y-620533D01*
X47482Y-620008D01*
X47873Y-619378D01*
X47952Y-618748D01*
X47795Y-618013D01*
X47247Y-617488D01*
X46698Y-617278D01*
X45993D01*
G01X46698D02*
X47168Y-616963D01*
X47560Y-616438D01*
X47717Y-615808D01*
X47560Y-615178D01*
X47168Y-614653D01*
X46463Y-614338D01*
X45758Y-614443D01*
X45053Y-614863D01*
G01X50727Y-619378D02*
X51197Y-620113D01*
X51823Y-620533D01*
X52528Y-620638D01*
X53155Y-620533D01*
X53782Y-620008D01*
X54173Y-619378D01*
X54252Y-618748D01*
X54095Y-618013D01*
X53547Y-617488D01*
X52998Y-617278D01*
X52293D01*
G01X52998D02*
X53468Y-616963D01*
X53860Y-616438D01*
X54017Y-615808D01*
X53860Y-615178D01*
X53468Y-614653D01*
X52763Y-614338D01*
X52058Y-614443D01*
X51353Y-614863D01*
G01X58593Y-620638D02*
X58750Y-619273D01*
X58985Y-618118D01*
X59298Y-617068D01*
X59690Y-615913D01*
X60317Y-614338D01*
X57183D01*
G01X64893Y-620638D02*
X65050Y-619273D01*
X65285Y-618118D01*
X65598Y-617068D01*
X65990Y-615913D01*
X66617Y-614338D01*
X63483D01*
G01X71193Y-621793D02*
X71507Y-620428D01*
G01X77650Y-614338D02*
Y-620638D01*
G01X75848Y-614338D02*
X79452D01*
G01X81992Y-620638D02*
X83950Y-614338D01*
X85908Y-620638D01*
G01X85203Y-618433D02*
X82697D01*
G01X89310Y-614338D02*
X91190D01*
G01X90250D02*
Y-620638D01*
G01X89310D02*
X91190D01*
G01X94200Y-614338D02*
X95297Y-620638D01*
X96550Y-614338D01*
X97803Y-620638D01*
X98900Y-614338D01*
G01X100892Y-620638D02*
X102850Y-614338D01*
X104808Y-620638D01*
G01X104103Y-618433D02*
X101597D01*
G01X107348Y-620638D02*
Y-614338D01*
X110952Y-620638D01*
Y-614338D01*
G01X121358Y-622738D02*
X120575Y-621688D01*
X120183Y-620638D01*
Y-616438D01*
X120575Y-615388D01*
X121358Y-614338D01*
G01X132783Y-620638D02*
Y-614338D01*
X134742D01*
X135368Y-614653D01*
X135760Y-615073D01*
X135917Y-615913D01*
X135760Y-616753D01*
X135290Y-617278D01*
X134742Y-617593D01*
X132783D01*
G01X134742D02*
X135917Y-620638D01*
G01X140650Y-620848D02*
X140493Y-620743D01*
Y-620533D01*
X140650Y-620428D01*
X140807Y-620533D01*
Y-620743D01*
X140650Y-620848D01*
G01X146950Y-620638D02*
X146323Y-620533D01*
X145775Y-620113D01*
X145305Y-619483D01*
X144992Y-618748D01*
X144835Y-617908D01*
Y-617068D01*
X144992Y-616228D01*
X145305Y-615493D01*
X145775Y-614863D01*
X146323Y-614443D01*
X146950Y-614338D01*
X147577Y-614443D01*
X148125Y-614863D01*
X148595Y-615493D01*
X148908Y-616228D01*
X149065Y-617068D01*
Y-617908D01*
X148908Y-618748D01*
X148595Y-619483D01*
X148125Y-620113D01*
X147577Y-620533D01*
X146950Y-620638D01*
G01X153250Y-620848D02*
X153093Y-620743D01*
Y-620533D01*
X153250Y-620428D01*
X153407Y-620533D01*
Y-620743D01*
X153250Y-620848D01*
G01X161273Y-614863D02*
X160803Y-614548D01*
X160255Y-614338D01*
X159628D01*
X158923Y-614653D01*
X158375Y-615178D01*
X157983Y-615808D01*
X157670Y-616858D01*
X157592Y-617803D01*
X157748Y-618748D01*
X157983Y-619378D01*
X158453Y-620008D01*
X159002Y-620428D01*
X159550Y-620638D01*
X160098D01*
X160647Y-620428D01*
X161117Y-620113D01*
X161508Y-619693D01*
G01X165850Y-620848D02*
X165693Y-620743D01*
Y-620533D01*
X165850Y-620428D01*
X166007Y-620533D01*
Y-620743D01*
X165850Y-620848D01*
G01X172542Y-622738D02*
X173325Y-621688D01*
X173717Y-620638D01*
Y-616438D01*
X173325Y-615388D01*
X172542Y-614338D01*
G01X6548Y-600638D02*
Y-594338D01*
X10152Y-600638D01*
Y-594338D01*
G01X14650Y-600638D02*
X14023Y-600533D01*
X13475Y-600113D01*
X13005Y-599483D01*
X12692Y-598748D01*
X12535Y-597908D01*
Y-597068D01*
X12692Y-596228D01*
X13005Y-595493D01*
X13475Y-594863D01*
X14023Y-594443D01*
X14650Y-594338D01*
X15277Y-594443D01*
X15825Y-594863D01*
X16295Y-595493D01*
X16608Y-596228D01*
X16765Y-597068D01*
Y-597908D01*
X16608Y-598748D01*
X16295Y-599483D01*
X15825Y-600113D01*
X15277Y-600533D01*
X14650Y-600638D01*
G01X20950Y-600848D02*
X20793Y-600743D01*
Y-600533D01*
X20950Y-600428D01*
X21107Y-600533D01*
Y-600743D01*
X20950Y-600848D01*
G01X25762Y-595388D02*
X26232Y-594758D01*
X26780Y-594443D01*
X27407Y-594338D01*
X28190Y-594548D01*
X28738Y-595073D01*
X28895Y-595703D01*
X28817Y-596333D01*
X28503Y-596858D01*
X26937Y-597908D01*
X26232Y-598643D01*
X25762Y-599693D01*
X25605Y-600638D01*
X28895D01*
G01X33550D02*
Y-594338D01*
X32610Y-595598D01*
G01Y-600638D02*
X34490D01*
G01X39850D02*
Y-594338D01*
X38910Y-595598D01*
G01Y-600638D02*
X40790D01*
G01X45993Y-601793D02*
X46307Y-600428D01*
G01X50100Y-594338D02*
X51197Y-600638D01*
X52450Y-594338D01*
X53703Y-600638D01*
X54800Y-594338D01*
G01X60317Y-600638D02*
X57183D01*
Y-594338D01*
X60317D01*
G01X59063Y-597383D02*
X57183D01*
G01X63248Y-600638D02*
Y-594338D01*
X66852Y-600638D01*
Y-594338D01*
G01X69705Y-600638D02*
Y-594338D01*
G01X72995D02*
Y-600638D01*
G01Y-597488D02*
X69705D01*
G01X75927Y-594338D02*
Y-598853D01*
X76240Y-599798D01*
X76867Y-600428D01*
X77650Y-600638D01*
X78433Y-600428D01*
X79060Y-599798D01*
X79373Y-598853D01*
Y-594338D01*
G01X81992Y-600638D02*
X83950Y-594338D01*
X85908Y-600638D01*
G01X85203Y-598433D02*
X82697D01*
G01X95062Y-595388D02*
X95532Y-594758D01*
X96080Y-594443D01*
X96707Y-594338D01*
X97490Y-594548D01*
X98038Y-595073D01*
X98195Y-595703D01*
X98117Y-596333D01*
X97803Y-596858D01*
X96237Y-597908D01*
X95532Y-598643D01*
X95062Y-599693D01*
X94905Y-600638D01*
X98195D01*
G01X101048D02*
Y-594338D01*
X104652Y-600638D01*
Y-594338D01*
G01X107427Y-600638D02*
Y-594338D01*
X108993D01*
X109620Y-594653D01*
X110090Y-595073D01*
X110482Y-595703D01*
X110795Y-596438D01*
X110873Y-597488D01*
X110795Y-598538D01*
X110482Y-599273D01*
X110090Y-599903D01*
X109620Y-600323D01*
X108993Y-600638D01*
X107427D01*
G01X120183D02*
Y-594338D01*
X122142D01*
X122768Y-594653D01*
X123160Y-595073D01*
X123317Y-595913D01*
X123160Y-596753D01*
X122690Y-597278D01*
X122142Y-597593D01*
X120183D01*
G01X122142D02*
X123317Y-600638D01*
G01X126327D02*
Y-594338D01*
X127893D01*
X128520Y-594653D01*
X128990Y-595073D01*
X129382Y-595703D01*
X129695Y-596438D01*
X129773Y-597488D01*
X129695Y-598538D01*
X129382Y-599273D01*
X128990Y-599903D01*
X128520Y-600323D01*
X127893Y-600638D01*
X126327D01*
G01X134350Y-600848D02*
X134193Y-600743D01*
Y-600533D01*
X134350Y-600428D01*
X134507Y-600533D01*
Y-600743D01*
X134350Y-600848D01*
G01X30650Y-589938D02*
X28130Y-589521D01*
X25925Y-587855D01*
X24035Y-585355D01*
X22775Y-582438D01*
X22145Y-579105D01*
Y-575771D01*
X22775Y-572438D01*
X24035Y-569521D01*
X25925Y-567022D01*
X28130Y-565355D01*
X30650Y-564938D01*
X33170Y-565355D01*
X35375Y-567022D01*
X37265Y-569521D01*
X38525Y-572438D01*
X39155Y-575771D01*
Y-579105D01*
X38525Y-582438D01*
X37265Y-585355D01*
X35375Y-587855D01*
X33170Y-589521D01*
X30650Y-589938D01*
G01X33170Y-583271D02*
X36950Y-589938D01*
G01X50495Y-573272D02*
Y-584938D01*
X51755Y-587855D01*
X53645Y-589521D01*
X55850Y-589938D01*
X58055Y-589521D01*
X59945Y-587855D01*
X61205Y-584938D01*
G01Y-589938D02*
Y-573272D01*
G01X86720Y-589938D02*
Y-573272D01*
G01Y-576188D02*
X85460Y-574522D01*
X83570Y-573688D01*
X81365Y-573272D01*
X79160Y-574105D01*
X77270Y-575771D01*
X76010Y-578272D01*
X75380Y-581605D01*
X76010Y-584938D01*
X77270Y-587439D01*
X79160Y-589105D01*
X81365Y-589938D01*
X83570Y-589521D01*
X85460Y-588272D01*
X86720Y-586605D01*
G01X100895Y-589938D02*
Y-573272D01*
G01Y-577438D02*
X102155Y-575355D01*
X104045Y-573688D01*
X106565Y-573272D01*
X108770Y-573688D01*
X110660Y-575355D01*
X111605Y-578272D01*
Y-589938D01*
G01X131450Y-564938D02*
Y-589938D01*
G01X127040Y-573272D02*
X135860D01*
G01X162320Y-589938D02*
Y-573272D01*
G01Y-576188D02*
X161060Y-574522D01*
X159170Y-573688D01*
X156965Y-573272D01*
X154760Y-574105D01*
X152870Y-575771D01*
X151610Y-578272D01*
X150980Y-581605D01*
X151610Y-584938D01*
X152870Y-587439D01*
X154760Y-589105D01*
X156965Y-589938D01*
X159170Y-589521D01*
X161060Y-588272D01*
X162320Y-586605D01*
G01X202000Y-569638D02*
Y-577638D01*
X206000D01*
G01X213800D02*
Y-572305D01*
G01Y-573238D02*
X213400Y-572705D01*
X212800Y-572438D01*
X212100Y-572305D01*
X211400Y-572571D01*
X210800Y-573105D01*
X210400Y-573905D01*
X210200Y-574971D01*
X210400Y-576038D01*
X210800Y-576838D01*
X211400Y-577371D01*
X212100Y-577638D01*
X212800Y-577505D01*
X213400Y-577105D01*
X213800Y-576572D01*
G01X217900Y-580038D02*
X218500Y-580305D01*
X219300Y-580038D01*
X219800Y-579505D01*
X220200Y-578838D01*
X220800Y-576705D01*
X222100Y-572305D01*
G01X218900D02*
X220800Y-576705D01*
G01X226500Y-574038D02*
X229700D01*
X229400Y-573105D01*
X228900Y-572571D01*
X228200Y-572305D01*
X227500Y-572438D01*
X226900Y-572838D01*
X226500Y-573771D01*
X226300Y-574572D01*
Y-575371D01*
X226500Y-576171D01*
X227000Y-576971D01*
X227600Y-577505D01*
X228300Y-577638D01*
X229000Y-577371D01*
X229700Y-576572D01*
G01X234600Y-577638D02*
Y-572305D01*
G01Y-573371D02*
X235100Y-572838D01*
X235600Y-572438D01*
X236300Y-572305D01*
X236800Y-572438D01*
X237400Y-572838D01*
G01X226000Y-626038D02*
X226500Y-626838D01*
X227100Y-627371D01*
X227800Y-627638D01*
X228600Y-627371D01*
X229200Y-626838D01*
X229800Y-626038D01*
X230000Y-624971D01*
Y-619638D01*
G01X237800Y-627638D02*
Y-622305D01*
G01Y-623238D02*
X237400Y-622705D01*
X236800Y-622438D01*
X236100Y-622305D01*
X235400Y-622571D01*
X234800Y-623105D01*
X234400Y-623905D01*
X234200Y-624971D01*
X234400Y-626038D01*
X234800Y-626838D01*
X235400Y-627371D01*
X236100Y-627638D01*
X236800Y-627505D01*
X237400Y-627105D01*
X237800Y-626572D01*
G01X245600Y-622971D02*
X244900Y-622438D01*
X244300Y-622305D01*
X243500Y-622571D01*
X242900Y-623105D01*
X242500Y-624038D01*
X242400Y-624971D01*
X242500Y-625905D01*
X242900Y-626705D01*
X243500Y-627371D01*
X244300Y-627638D01*
X245000Y-627371D01*
X245600Y-626838D01*
G01X250300Y-627638D02*
Y-619638D01*
G01X253500Y-622305D02*
X250300Y-625371D01*
G01X251600Y-624171D02*
X253700Y-627638D01*
G01X233600Y-598638D02*
X235600D01*
Y-601038D01*
X235000Y-601838D01*
X234300Y-602371D01*
X233300Y-602638D01*
X232300Y-602371D01*
X231600Y-601838D01*
X231000Y-601038D01*
X230600Y-600105D01*
X230400Y-599038D01*
Y-598105D01*
X230600Y-597305D01*
X231000Y-596371D01*
X231600Y-595571D01*
X232200Y-595038D01*
X233000Y-594638D01*
X233700D01*
X234500Y-594905D01*
X235100Y-595438D01*
G01X238700Y-602638D02*
Y-594638D01*
X243300Y-602638D01*
Y-594638D01*
G01X246800Y-602638D02*
Y-594638D01*
X248800D01*
X249600Y-595038D01*
X250200Y-595571D01*
X250700Y-596371D01*
X251100Y-597305D01*
X251200Y-598638D01*
X251100Y-599971D01*
X250700Y-600905D01*
X250200Y-601705D01*
X249600Y-602238D01*
X248800Y-602638D01*
X246800D01*
G01X257000D02*
Y-594638D01*
X255800Y-596238D01*
G01Y-602638D02*
X258200D01*
G01X256700Y-577638D02*
Y-569638D01*
X253000Y-575371D01*
X258000D01*
G01X328600Y-620971D02*
X329200Y-620171D01*
X329900Y-619771D01*
X330700Y-619638D01*
X331700Y-619905D01*
X332400Y-620571D01*
X332600Y-621371D01*
X332500Y-622172D01*
X332100Y-622838D01*
X330100Y-624171D01*
X329200Y-625105D01*
X328600Y-626438D01*
X328400Y-627638D01*
X332600D01*
G01X338500Y-619638D02*
X337700Y-619905D01*
X337100Y-620571D01*
X336700Y-621371D01*
X336400Y-622438D01*
X336300Y-623638D01*
X336400Y-624838D01*
X336700Y-625905D01*
X337100Y-626705D01*
X337700Y-627371D01*
X338500Y-627638D01*
X339300Y-627371D01*
X339900Y-626705D01*
X340300Y-625905D01*
X340600Y-624838D01*
X340700Y-623638D01*
X340600Y-622438D01*
X340300Y-621371D01*
X339900Y-620571D01*
X339300Y-619905D01*
X338500Y-619638D01*
G01X344600Y-620971D02*
X345200Y-620171D01*
X345900Y-619771D01*
X346700Y-619638D01*
X347700Y-619905D01*
X348400Y-620571D01*
X348600Y-621371D01*
X348500Y-622172D01*
X348100Y-622838D01*
X346100Y-624171D01*
X345200Y-625105D01*
X344600Y-626438D01*
X344400Y-627638D01*
X348600D01*
G01X352300Y-626038D02*
X352900Y-626971D01*
X353700Y-627505D01*
X354600Y-627638D01*
X355400Y-627505D01*
X356200Y-626838D01*
X356700Y-626038D01*
X356800Y-625238D01*
X356600Y-624305D01*
X355900Y-623638D01*
X355200Y-623371D01*
X354300D01*
G01X355200D02*
X355800Y-622971D01*
X356300Y-622305D01*
X356500Y-621505D01*
X356300Y-620705D01*
X355800Y-620038D01*
X354900Y-619638D01*
X354000Y-619771D01*
X353100Y-620305D01*
G01X360700Y-627905D02*
X364300Y-619638D01*
G01X370500D02*
X369700Y-619905D01*
X369100Y-620571D01*
X368700Y-621371D01*
X368400Y-622438D01*
X368300Y-623638D01*
X368400Y-624838D01*
X368700Y-625905D01*
X369100Y-626705D01*
X369700Y-627371D01*
X370500Y-627638D01*
X371300Y-627371D01*
X371900Y-626705D01*
X372300Y-625905D01*
X372600Y-624838D01*
X372700Y-623638D01*
X372600Y-622438D01*
X372300Y-621371D01*
X371900Y-620571D01*
X371300Y-619905D01*
X370500Y-619638D01*
G01X379700Y-627638D02*
Y-619638D01*
X376000Y-625371D01*
X381000D01*
G01X384700Y-627905D02*
X388300Y-619638D01*
G01X394500Y-627638D02*
Y-619638D01*
X393300Y-621238D01*
G01Y-627638D02*
X395700D01*
G01X402300D02*
X402500Y-625905D01*
X402800Y-624438D01*
X403200Y-623105D01*
X403700Y-621638D01*
X404500Y-619638D01*
X400500D01*
G01X328300Y-602638D02*
Y-594638D01*
X330300D01*
X331100Y-595038D01*
X331700Y-595571D01*
X332200Y-596371D01*
X332600Y-597305D01*
X332700Y-598638D01*
X332600Y-599971D01*
X332200Y-600905D01*
X331700Y-601705D01*
X331100Y-602238D01*
X330300Y-602638D01*
X328300D01*
G01X336000D02*
X338500Y-594638D01*
X341000Y-602638D01*
G01X340100Y-599838D02*
X336900D01*
G01X344600Y-602638D02*
Y-594638D01*
X348400D01*
G01X347000Y-598505D02*
X344600D01*
G01X354500Y-594638D02*
X353700Y-594905D01*
X353100Y-595571D01*
X352700Y-596371D01*
X352400Y-597438D01*
X352300Y-598638D01*
X352400Y-599838D01*
X352700Y-600905D01*
X353100Y-601705D01*
X353700Y-602371D01*
X354500Y-602638D01*
X355300Y-602371D01*
X355900Y-601705D01*
X356300Y-600905D01*
X356600Y-599838D01*
X356700Y-598638D01*
X356600Y-597438D01*
X356300Y-596371D01*
X355900Y-595571D01*
X355300Y-594905D01*
X354500Y-594638D01*
G01X362500D02*
Y-602638D01*
G01X360200Y-594638D02*
X364800D01*
G01X367900Y-602638D02*
Y-594638D01*
X370500Y-601305D01*
X373100Y-594638D01*
Y-602638D01*
G01X379300Y-598371D02*
X379700Y-597971D01*
X380000Y-597305D01*
X380200Y-596371D01*
X380000Y-595571D01*
X379600Y-595038D01*
X378900Y-594638D01*
X376200D01*
Y-602638D01*
X379500D01*
X380200Y-602105D01*
X380600Y-601305D01*
X380800Y-600371D01*
X380600Y-599438D01*
X380000Y-598638D01*
X379300Y-598371D01*
X376200D01*
G01X384300Y-601038D02*
X384900Y-601971D01*
X385700Y-602505D01*
X386600Y-602638D01*
X387400Y-602505D01*
X388200Y-601838D01*
X388700Y-601038D01*
X388800Y-600238D01*
X388600Y-599305D01*
X387900Y-598638D01*
X387200Y-598371D01*
X386300D01*
G01X387200D02*
X387800Y-597971D01*
X388300Y-597305D01*
X388500Y-596505D01*
X388300Y-595705D01*
X387800Y-595038D01*
X386900Y-594638D01*
X386000Y-594771D01*
X385100Y-595305D01*
G01X393300Y-594638D02*
X395700D01*
G01X394500D02*
Y-602638D01*
G01X393300D02*
X395700D01*
G01X404700Y-595305D02*
X404100Y-594905D01*
X403400Y-594638D01*
X402600D01*
X401700Y-595038D01*
X401000Y-595705D01*
X400500Y-596505D01*
X400100Y-597838D01*
X400000Y-599038D01*
X400200Y-600238D01*
X400500Y-601038D01*
X401100Y-601838D01*
X401800Y-602371D01*
X402500Y-602638D01*
X403200D01*
X403900Y-602371D01*
X404500Y-601971D01*
X405000Y-601438D01*
G01X410500Y-594638D02*
X409700Y-594905D01*
X409100Y-595571D01*
X408700Y-596371D01*
X408400Y-597438D01*
X408300Y-598638D01*
X408400Y-599838D01*
X408700Y-600905D01*
X409100Y-601705D01*
X409700Y-602371D01*
X410500Y-602638D01*
X411300Y-602371D01*
X411900Y-601705D01*
X412300Y-600905D01*
X412600Y-599838D01*
X412700Y-598638D01*
X412600Y-597438D01*
X412300Y-596371D01*
X411900Y-595571D01*
X411300Y-594905D01*
X410500Y-594638D01*
G01X346100Y-577638D02*
Y-569638D01*
X349900D01*
G01X348500Y-573505D02*
X346100D01*
G01X356000Y-569638D02*
X355200Y-569905D01*
X354600Y-570571D01*
X354200Y-571371D01*
X353900Y-572438D01*
X353800Y-573638D01*
X353900Y-574838D01*
X354200Y-575905D01*
X354600Y-576705D01*
X355200Y-577371D01*
X356000Y-577638D01*
X356800Y-577371D01*
X357400Y-576705D01*
X357800Y-575905D01*
X358100Y-574838D01*
X358200Y-573638D01*
X358100Y-572438D01*
X357800Y-571371D01*
X357400Y-570571D01*
X356800Y-569905D01*
X356000Y-569638D01*
G01X364000D02*
Y-577638D01*
G01X361700Y-569638D02*
X366300D01*
G01X372600Y-573638D02*
X374600D01*
Y-576038D01*
X374000Y-576838D01*
X373300Y-577371D01*
X372300Y-577638D01*
X371300Y-577371D01*
X370600Y-576838D01*
X370000Y-576038D01*
X369600Y-575105D01*
X369400Y-574038D01*
Y-573105D01*
X369600Y-572305D01*
X370000Y-571371D01*
X370600Y-570571D01*
X371200Y-570038D01*
X372000Y-569638D01*
X372700D01*
X373500Y-569905D01*
X374100Y-570438D01*
G01X377000Y-580305D02*
X383000D01*
G01X385400Y-577638D02*
Y-569638D01*
X388000Y-576305D01*
X390600Y-569638D01*
Y-577638D01*
G01X396800Y-573371D02*
X397200Y-572971D01*
X397500Y-572305D01*
X397700Y-571371D01*
X397500Y-570571D01*
X397100Y-570038D01*
X396400Y-569638D01*
X393700D01*
Y-577638D01*
X397000D01*
X397700Y-577105D01*
X398100Y-576305D01*
X398300Y-575371D01*
X398100Y-574438D01*
X397500Y-573638D01*
X396800Y-573371D01*
X393700D01*
G01X417000Y-630638D02*
Y-622638D01*
X415800Y-624238D01*
G01Y-630638D02*
X418200D01*
G01X423100Y-627305D02*
X423800Y-626371D01*
X424400Y-625838D01*
X425200Y-625571D01*
X425900Y-625838D01*
X426400Y-626371D01*
X426800Y-627171D01*
X426900Y-628105D01*
X426800Y-628905D01*
X426400Y-629705D01*
X425800Y-630371D01*
X425100Y-630638D01*
X424300Y-630371D01*
X423600Y-629572D01*
X423200Y-628371D01*
X423100Y-627038D01*
X423300Y-625305D01*
X423600Y-624371D01*
X424100Y-623438D01*
X424800Y-622771D01*
X425500Y-622638D01*
X426200Y-622905D01*
X426700Y-623571D01*
G01X433000Y-630905D02*
X432800Y-630771D01*
Y-630505D01*
X433000Y-630371D01*
X433200Y-630505D01*
Y-630771D01*
X433000Y-630905D01*
G01X439100Y-627305D02*
X439800Y-626371D01*
X440400Y-625838D01*
X441200Y-625571D01*
X441900Y-625838D01*
X442400Y-626371D01*
X442800Y-627171D01*
X442900Y-628105D01*
X442800Y-628905D01*
X442400Y-629705D01*
X441800Y-630371D01*
X441100Y-630638D01*
X440300Y-630371D01*
X439600Y-629572D01*
X439200Y-628371D01*
X439100Y-627038D01*
X439300Y-625305D01*
X439600Y-624371D01*
X440100Y-623438D01*
X440800Y-622771D01*
X441500Y-622638D01*
X442200Y-622905D01*
X442700Y-623571D01*
G01X462000Y-630638D02*
Y-622638D01*
X460800Y-624238D01*
G01Y-630638D02*
X463200D01*
G01X469800D02*
X470000Y-628905D01*
X470300Y-627438D01*
X470700Y-626105D01*
X471200Y-624638D01*
X472000Y-622638D01*
X468000D01*
G01X478000Y-630905D02*
X477800Y-630771D01*
Y-630505D01*
X478000Y-630371D01*
X478200Y-630505D01*
Y-630771D01*
X478000Y-630905D01*
G01X484100Y-623971D02*
X484700Y-623171D01*
X485400Y-622771D01*
X486200Y-622638D01*
X487200Y-622905D01*
X487900Y-623571D01*
X488100Y-624371D01*
X488000Y-625172D01*
X487600Y-625838D01*
X485600Y-627171D01*
X484700Y-628105D01*
X484100Y-629438D01*
X483900Y-630638D01*
X488100D01*
G01X486200Y-598305D02*
X485600Y-597905D01*
X484900Y-597638D01*
X484100D01*
X483200Y-598038D01*
X482500Y-598705D01*
X482000Y-599505D01*
X481600Y-600838D01*
X481500Y-602038D01*
X481700Y-603238D01*
X482000Y-604038D01*
X482600Y-604838D01*
X483300Y-605371D01*
X484000Y-605638D01*
X484700D01*
X485400Y-605371D01*
X486000Y-604971D01*
X486500Y-604438D01*
M02*
